G04 ================== begin FILE IDENTIFICATION RECORD ==================*
G04 Layout Name:  15126-1b.brd*
G04 Film Name:    L8VCC*
G04 File Format:  Gerber RS274X*
G04 File Origin:  Cadence Allegro 16.6-2015-S079*
G04 Origin Date:  Fri Feb 10 17:22:43 2017*
G04 *
G04 Layer:  VIA CLASS/L8VCC*
G04 Layer:  PIN/L8VCC*
G04 Layer:  PACKAGE GEOMETRY/PWRVCC*
G04 Layer:  ETCH/L8VCC*
G04 Layer:  DRAWING FORMAT/LAYER_PCB_STORY*
G04 Layer:  DRAWING FORMAT/LAYER_L8VCC*
G04 *
G04 Offset:    (0.00 0.00)*
G04 Mirror:    No*
G04 Mode:      Positive*
G04 Rotation:  0*
G04 FullContactRelief:  No*
G04 UndefLineWidth:     6.00*
G04 ================== end FILE IDENTIFICATION RECORD ====================*
%FSLAX35Y35*MOIN*%
%IR0*IPPOS*OFA0.00000B0.00000*MIA0B0*SFA1.00000B1.00000*%
%ADD11C,.02*%
%ADD10C,.022*%
%ADD15C,.018*%
%ADD14C,.028*%
%ADD12C,.046*%
%ADD13C,.057*%
%ADD16O,.099X.048*%
%ADD17C,.01*%
%ADD18C,.025*%
%ADD19C,.004*%
%ADD20C,.006*%
%ADD21C,.009*%
%ADD49O,.07202X.12102*%
%ADD24C,.03004*%
%ADD55C,.04004*%
%ADD48C,.0314*%
%ADD54C,.04104*%
%ADD34C,.03204*%
%ADD44C,.06004*%
%ADD39C,.06104*%
%ADD36C,.07004*%
%ADD64C,.02604*%
%ADD63C,.08004*%
%ADD43C,.06204*%
%ADD30C,.04404*%
%ADD45C,.07204*%
%ADD65C,.06404*%
%ADD51C,.05504*%
%ADD29C,.02804*%
%ADD58C,.04704*%
%ADD50C,.02904*%
%ADD47C,.06504*%
%ADD38C,.07404*%
%ADD23C,.05604*%
%ADD53C,.09304*%
%ADD46C,.05704*%
%ADD41C,.07504*%
%ADD35C,.08404*%
%ADD27C,.04804*%
%ADD37C,.07604*%
%ADD33C,.05804*%
%ADD52C,.06804*%
%ADD28C,.08604*%
%ADD60C,.06943*%
%ADD56C,.11211*%
%ADD42C,.12104*%
%ADD32C,.11204*%
%ADD31C,.15004*%
%ADD22C,.11404*%
%ADD62O,.06004X.07204*%
%ADD57C,.11209*%
%ADD25O,.15404X.21904*%
%ADD26C,.15504*%
%ADD61C,.15506*%
%ADD59C,.28404*%
%ADD40C,.17804*%
G75*
%LPD*%
G75*
G36*
G01X1973300Y-60000D02*
X-19810D01*
Y-34500D01*
X1973300D01*
Y-60000D01*
G37*
G36*
G01X1436378Y624578D02*
X1440575D01*
G02X1440935Y624005I0J-400D01*
G03X1443367Y622623I1265J-605D01*
G02X1444033I333J-222D01*
G03X1446367I1167J777D01*
G02X1447033I333J-222D01*
G03X1449388Y622656I1167J777D01*
G02X1450080Y622633I339J-212D01*
G03X1452537Y623983I1234J665D01*
G02X1452886Y624578I349J195D01*
G01X1453375D01*
G02X1453735Y624005I0J-400D01*
G03X1456167Y622623I1265J-605D01*
G02X1456833I333J-222D01*
G03X1459313Y622908I1167J777D01*
G02X1459687I187J-70D01*
G03X1459800Y622675I1313J493D01*
G01Y609180D01*
X1459637Y609149D01*
G03X1458150Y608393I563J-2949D01*
G03X1454688Y608849I-2050J-2193D01*
G03X1452039Y608763I-1237J-2735D01*
G03X1449308Y608716I-1320J-2696D01*
G03X1446382Y608462I-1237J-2735D01*
G03X1443063Y603564I-1237J-2735D01*
G02X1442867Y602884I-277J-288D01*
G03X1440504Y599499I606J-2940D01*
G03X1440657Y594929I2021J-2220D01*
G03X1445522Y597099I2997J-180D01*
G03X1445494Y597724I-2997J179D01*
G03X1445555Y602107I-2021J2220D01*
G02X1445751Y602787I277J288D01*
G03X1446834Y603246I-607J2940D01*
G03X1449483Y603332I1237J2735D01*
G03X1450641Y603066I1238J2735D01*
G03X1455040Y600719I2987J302D01*
G03X1459259Y603108I1237J2735D01*
G02X1459504Y603280I199J-23D01*
G03X1459637Y603251I706J2918D01*
G01X1459800Y603220D01*
Y593528D01*
X1459668Y593397D01*
Y593394D01*
X1452637Y586363D01*
X1442476D01*
X1436649Y580536D01*
G02X1435982Y580931I-283J283D01*
G03X1435450Y583638I-2882J839D01*
G03X1429693Y583761I-2860J912D01*
G03X1429211Y583567I876J-2871D01*
G03X1428859Y578423I-1711J-2467D01*
G03X1432718Y578792I1711J2467D01*
G03X1433939Y578888I380J2978D01*
G02X1434334Y578221I112J-384D01*
G01X1420934Y564821D01*
X1420903Y564806D01*
G03X1420209Y564112I657J-1351D01*
G01X1420194Y564081D01*
X1419909Y563796D01*
G02X1419369Y563773I-283J283D01*
G03X1417388Y563732I-967J-1149D01*
G02X1416794Y563790I-271J294D01*
G03X1416596Y561796I-1212J-886D01*
G02X1417190Y561738I271J-294D01*
G03X1417253Y561657I1216J881D01*
G02X1417230Y561117I-306J-257D01*
G01X1413946Y557833D01*
G02X1413299Y557953I-282J283D01*
G03X1412845Y558513I-1280J-573D01*
G02X1412862Y559170I236J323D01*
G03X1411159Y561389I-769J1173D01*
G02X1410627I-266J298D01*
G03X1408643Y561272I-934J-1046D01*
G02X1408043I-300J265D01*
G03X1406005Y561337I-1050J-929D01*
G02X1405455Y561323I-282J284D01*
G03X1403687Y559152I-936J-1043D01*
G02Y558508I-238J-322D01*
G03X1403535Y558379I829J-1131D01*
G02X1402926Y558435I-281J285D01*
G03X1401937Y559025I-1149J-803D01*
G02X1401611Y559571I45J397D01*
G03X1400107Y558630I-1395J557D01*
G02X1400455Y558098I-29J-399D01*
G03X1402761Y556633I1322J-466D01*
G02X1403370Y556577I281J-285D01*
G03X1405492Y556370I1149J803D01*
G02X1406046I277J-288D01*
G03X1407992I973J1010D01*
G02X1408546I277J-288D01*
G03X1410492I973J1010D01*
G02X1411046I277J-288D01*
G03X1411446Y556100I973J1010D01*
G02X1411566Y555453I-163J-365D01*
G01X1396700Y540587D01*
Y539492D01*
G02X1396270Y539093I-400J0D01*
G03Y536097I-112J-1498D01*
G02X1396700Y535698I30J-399D01*
G01Y527009D01*
G02X1396140Y526643I-400J0D01*
G03Y524071I-559J-1286D01*
G02X1396700Y523705I160J-366D01*
G01Y521759D01*
G02X1396065Y521436I-400J1D01*
G03Y519166I-823J-1135D01*
G02X1396700Y518843I235J-324D01*
G01Y516645D01*
G02X1396241Y516250I-400J1D01*
G03Y513476I-206J-1387D01*
G02X1396700Y513081I59J-396D01*
G01Y504916D01*
X1396564Y504780D01*
X1396700Y504644D01*
Y481900D01*
X1409900Y468700D01*
X1417200D01*
X1419442Y466458D01*
Y466457D01*
X1419700Y466200D01*
Y450616D01*
X1427600Y442716D01*
X1427598Y442630D01*
G03X1428942Y441199I1402J-30D01*
G01X1429020Y441196D01*
X1429113Y441103D01*
X1429205Y441110D01*
X1429766Y440550D01*
X1430200Y440116D01*
Y438673D01*
G02X1429622Y438315I-400J0D01*
G03Y435803I-622J-1256D01*
G02X1430200Y435445I178J-358D01*
G01Y402800D01*
X1427302Y399902D01*
X1427097D01*
X1427096Y399900D01*
X1416075D01*
G03X1413925I-1075J-900D01*
G01X1391200D01*
X1389300Y401800D01*
Y409778D01*
X1389323Y409822D01*
G03Y411136I-1238J657D01*
G01X1389300Y411180D01*
Y414834D01*
X1394252Y419785D01*
Y419835D01*
X1395728Y421311D01*
X1395748Y421348D01*
X1396041Y421641D01*
X1396079Y421662D01*
X1400202Y425785D01*
Y425801D01*
X1400700Y426300D01*
X1403050D01*
X1405650Y428900D01*
Y441027D01*
G03X1405664Y443788I-3482J1398D01*
G01X1405650Y443823D01*
Y443850D01*
X1405631Y443869D01*
X1405616Y443904D01*
G03X1403647Y445873I-3448J-1479D01*
G01X1403612Y445888D01*
X1400600Y448900D01*
X1395645D01*
X1395612Y448912D01*
G03X1394588I-512J-1412D01*
G01X1394555Y448900D01*
X1389973D01*
G03X1389827I-73J-1500D01*
G01X1385645D01*
X1385612Y448912D01*
G03X1384588I-512J-1412D01*
G01X1384555Y448900D01*
X1380170D01*
G03X1380030I-70J-1400D01*
G01X1375170D01*
G03X1375030I-70J-1400D01*
G01X1370170D01*
G03X1370030I-70J-1400D01*
G01X1365170D01*
G03X1365030I-70J-1400D01*
G01X1362900D01*
X1362079Y448079D01*
G02X1361439Y448180I-283J282D01*
G03X1359420Y446161I-1339J-680D01*
G02X1359521Y445521I-181J-357D01*
G01X1357004Y443004D01*
G02X1356361Y443112I-283J283D01*
G03X1354488Y441239I-1261J-612D01*
G02X1354596Y440596I-175J-360D01*
G01X1352004Y438004D01*
G02X1351361Y438112I-283J283D01*
G03X1349488Y436239I-1261J-612D01*
G02X1349596Y435596I-175J-360D01*
G01X1342004Y428004D01*
G02X1341361Y428112I-283J283D01*
G03X1339488Y426239I-1261J-612D01*
G02X1339596Y425596I-175J-360D01*
G01X1338547Y424547D01*
X1314830D01*
X1311965Y421682D01*
X1214605D01*
X1214443Y421519D01*
X1213981D01*
X1204162Y411700D01*
X801285D01*
G02X801050Y411777I1J400D01*
G01X800354D01*
G02X799964Y412266I0J400D01*
G03X799945Y413010I-1464J335D01*
G02X800389Y413514I385J109D01*
G03X799165Y414590I221J1486D01*
G02X798721Y414086I-385J-109D01*
G03X797051Y412205I-221J-1486D01*
G02X796665Y411700I-386J-105D01*
G01X786302D01*
G02X786149Y412469I1J400D01*
G03X780193I-2978J7157D01*
G02X780040Y411700I-154J-369D01*
G01X770300D01*
X767959Y414041D01*
X767883Y414193D01*
X767889Y414250D01*
G03X767405Y415508I-1495J147D01*
G02X767364Y416056I269J296D01*
G03X767699Y416905I-1164J950D01*
G02X768094Y417278I399J-27D01*
G03X766581Y418880I-14J1502D01*
G02X766186Y418507I-399J27D01*
G03X764916Y417784I14J-1502D01*
G02X764291Y417709I-342J208D01*
G01X755833Y426167D01*
X753149D01*
X753064Y426252D01*
X681881D01*
G02X681583Y426884I28J399D01*
G03X679157I-1213J886D01*
G02X678859Y426252I-326J-233D01*
G01X630563D01*
G03X628637I-963J-1152D01*
G01X626437D01*
G03X623963I-1237J-852D01*
G01X614742D01*
X612324Y423834D01*
Y416804D01*
X622633Y406494D01*
X713206D01*
X716200Y403500D01*
Y381800D01*
X713100Y378700D01*
X640700D01*
X634800Y372800D01*
X577800D01*
X560709Y389891D01*
X560699Y389958D01*
G03X559423Y391234I-1487J-211D01*
G01X559356Y391244D01*
X559035Y391565D01*
G02X559294Y392247I283J283D01*
G03X557812Y393729I-82J1400D01*
G02X557130Y393470I-399J24D01*
G01X549078Y401522D01*
G02X549283Y402197I283J283D01*
G03X547517Y403963I-293J1473D01*
G02X546842Y403758I-392J78D01*
G01X541600Y409000D01*
X447787D01*
X447743Y409023D01*
G03X446439I-652J-1241D01*
G01X446395Y409000D01*
X428949D01*
G03X427499I-725J-1200D01*
G01X173520D01*
X172170Y410350D01*
Y429620D01*
X170990Y430800D01*
X165716D01*
X165715Y430802D01*
X131985D01*
X131984Y430800D01*
X131728D01*
X131671Y430850D01*
G03X129501Y430800I-1058J-1203D01*
G01X127416D01*
X127415Y430802D01*
X96785D01*
X96784Y430800D01*
X96500D01*
X94000Y428300D01*
Y382505D01*
G02X93622Y382106I-400J1D01*
G03Y378908I90J-1599D01*
G02X94000Y378509I-22J-400D01*
G01Y373913D01*
X93999D01*
Y371401D01*
X94000Y371400D01*
Y351948D01*
G03Y351852I1500J-48D01*
G01Y349348D01*
G03Y349252I1500J-48D01*
G01Y336675D01*
X93866Y336628D01*
G03Y333792I494J-1418D01*
G01X94000Y333745D01*
Y324509D01*
G03X93909Y324419I939J-1041D01*
G02X93565Y324520I-147J136D01*
G03X90916Y325200I-1479J-262D01*
G02X90233Y325301I-312J250D01*
G03X90010Y323798I-1393J-561D01*
G02X90693Y323697I312J-250D01*
G03X93025Y323086I1393J561D01*
G02X93644Y322927I250J-313D01*
G03X94000Y322425I1294J540D01*
G01Y319300D01*
X100298Y313001D01*
Y242197D01*
G02X99869Y241798I-400J0D01*
G03Y238802I-111J-1498D01*
G02X100298Y238403I29J-399D01*
G01Y225660D01*
G02X99814Y225269I-400J0D01*
G03Y222331I-314J-1469D01*
G02X100298Y221940I84J-391D01*
G01Y219914D01*
X94942Y214558D01*
X94598Y214215D01*
Y201105D01*
G02X94132Y200711I-400J1D01*
G03Y197551I-262J-1580D01*
G02X94598Y197157I66J-395D01*
G01Y194885D01*
X94898Y194585D01*
Y194502D01*
G03X98983Y191700I3002J-2D01*
G01X132254D01*
X132595Y191358D01*
X147316D01*
G02X147667Y190768I0J-400D01*
G03X147817Y189210I1233J-668D01*
G02X147795Y188677I-309J-254D01*
G03X147754Y186766I1005J-978D01*
G02Y186234I-298J-266D01*
G03Y184366I1046J-934D01*
G02Y183834I-298J-266D01*
G03X147831Y181887I1046J-934D01*
G02X147853Y181332I-277J-289D01*
G03X149869Y181413I1047J-932D01*
G02X149847Y181968I277J289D01*
G03X149846Y183834I-1047J932D01*
G02Y184366I298J266D01*
G03Y186234I-1046J934D01*
G02Y186766I298J266D01*
G03X149920Y186856I-1045J935D01*
G02X150239I160J-120D01*
G03X152141Y186536I1120J844D01*
G02X152680Y186450I223J-332D01*
G03X154888Y186440I1108J859D01*
G02X155444Y186510I314J-248D01*
G03X157514Y188315I850J1115D01*
G02X157655Y188854I348J197D01*
G03X158140Y190758I-727J1199D01*
G02X158486Y191358I346J200D01*
G01X399041D01*
X406700Y183700D01*
X566300D01*
X582300Y167700D01*
X628500D01*
X634200Y162000D01*
X665000D01*
X675148Y172148D01*
X789416D01*
X791167Y173900D01*
X1216600D01*
X1221100Y178400D01*
X1221139Y178416D01*
G03X1221974Y179251I-559J1394D01*
G01X1221990Y179290D01*
X1224625Y181925D01*
G02X1225302Y181714I283J-282D01*
G03X1225857Y180795I1478J266D01*
G02Y180165I-246J-315D01*
G03X1227965Y178057I923J-1185D01*
G02X1228595I315J-246D01*
G03X1230965I1185J923D01*
G02X1231595I315J-246D01*
G03X1233703Y180165I1185J923D01*
G02Y180795I246J315D01*
G03X1231595Y182903I-923J1185D01*
G02X1230965I-315J246D01*
G03X1228595I-1185J-923D01*
G02X1227965I-315J246D01*
G03X1227877Y183006I-1185J-923D01*
G02X1227905Y183580I292J273D01*
G03X1228262Y185370I-991J1128D01*
G01X1228199Y185499D01*
X1230200Y187500D01*
X1240317D01*
X1240357Y187351D01*
G03X1243067I1355J359D01*
G01X1243107Y187500D01*
X1251061D01*
X1251064Y187498D01*
X1269515D01*
X1269516Y187500D01*
X1269739D01*
X1277500Y195261D01*
Y224000D01*
X1279620Y226120D01*
X1393662D01*
G03X1395374Y225578I1219J877D01*
G02X1395864Y225377I131J-378D01*
G03X1398709Y225934I1347J664D01*
G01X1398722Y226120D01*
X1405833D01*
X1431013Y251300D01*
X1432923D01*
X1432968Y251162D01*
G03X1433602Y250384I1332J438D01*
G02X1433713Y249785I-199J-347D01*
G03X1434115Y247677I1087J-885D01*
G02X1434284Y247164I-196J-349D01*
G03X1435584Y245050I1371J-614D01*
G02X1435951Y244545I-19J-400D01*
G03X1437471Y245650I1449J-395D01*
G02X1437104Y246155I19J400D01*
G03X1436310Y247901I-1449J395D01*
G02X1436111Y248403I175J360D01*
G03X1435498Y250116I-1311J497D01*
G02X1435387Y250715I199J347D01*
G03X1435632Y251162I-1086J886D01*
G01X1435677Y251300D01*
X1445703D01*
X1445752Y251172D01*
G03X1448556I1402J538D01*
G01X1448605Y251300D01*
X1473182D01*
X1473235Y251180D01*
G03X1475805I1285J560D01*
G01X1475858Y251300D01*
X1477171D01*
G03X1479829I1329J700D01*
G01X1483278D01*
X1483331Y251182D01*
G03X1486069I1369J618D01*
G01X1486122Y251300D01*
X1497646D01*
G02X1498030Y250789I0J-400D01*
G03X1500833Y249734I1442J-419D01*
G02X1501399Y249908I362J-170D01*
G03X1503664Y251112I766J1292D01*
G01X1503675Y251300D01*
X1515400D01*
X1519426Y247274D01*
G02X1519178Y246593I-283J-283D01*
G03X1519553Y243817I123J-1397D01*
G02X1520025Y243424I72J-393D01*
G01Y240852D01*
X1519898Y240802D01*
G03X1520697Y238125I515J-1304D01*
G01X1520803Y238147D01*
X1524750Y234200D01*
X1524758Y234132D01*
G03X1527493Y233897I1392J168D01*
G01X1527535Y234039D01*
X1543904D01*
G02X1544303Y233616I0J-400D01*
G03X1547301I1499J-87D01*
G02X1547700Y234039I399J23D01*
G01X1559710D01*
X1559750Y233891D01*
G03X1562102Y235240I1354J364D01*
G02X1562103Y235522I142J140D01*
G01X1562488Y235907D01*
Y238631D01*
X1563292Y239435D01*
X1568653D01*
G02X1569003Y238842I0J-400D01*
G03X1569505Y236853I1315J-726D01*
G02X1569495Y236175I-217J-336D01*
G03X1571660Y234315I777J-1286D01*
G02X1572177Y234534I370J-153D01*
G03X1574226Y235795I553J1397D01*
G02X1574611Y236159I398J-36D01*
G03X1575598Y238746I-51J1501D01*
G02X1575874Y239435I276J289D01*
G01X1595498D01*
G02X1595856Y238857I0J-400D01*
G03X1598546I1345J-669D01*
G02X1598904Y239435I358J178D01*
G01X1612923D01*
X1625952Y252464D01*
X1626093Y252339D01*
G03X1628072Y254318I931J1048D01*
G01X1627947Y254459D01*
X1636572Y263084D01*
X1636695Y263033D01*
G03X1638657Y264995I574J1388D01*
G01X1638606Y265118D01*
X1656975Y283487D01*
X1657088Y283455D01*
G03X1658408Y286095I410J1445D01*
G02X1658395Y286721I242J318D01*
G03X1658083Y289075I-895J1079D01*
G01Y289992D01*
X1659420Y291329D01*
Y293676D01*
X1658083Y295013D01*
Y303178D01*
X1658198Y303232D01*
G03Y305768I-598J1268D01*
G01X1658083Y305822D01*
Y449493D01*
X1658756Y450166D01*
X1658914Y450323D01*
Y450326D01*
X1660946Y452358D01*
X1661063Y452321D01*
G03X1662952Y454210I459J1430D01*
G01X1662915Y454327D01*
X1679586Y470998D01*
X1679591D01*
X1679664Y471072D01*
X1718140D01*
G03X1720038I949J1032D01*
G01X1721039D01*
G03X1723655I1308J739D01*
G01X1724500D01*
X1724573Y470998D01*
X1724578D01*
X1733101Y462474D01*
X1925454D01*
X1925619Y462308D01*
X1925622D01*
X1930681Y457248D01*
X1931100Y456829D01*
Y455163D01*
G02X1930662Y454765I-400J0D01*
G03Y447593I-343J-3586D01*
G02X1931100Y447195I38J-398D01*
G01Y438954D01*
X1929896Y437750D01*
X1926350D01*
X1925650Y437050D01*
Y434850D01*
X1925225Y434425D01*
X1912127D01*
G02X1911766Y434997I0J400D01*
G03X1909333Y436377I-1266J603D01*
G02X1908667I-333J222D01*
G03X1906183Y435120I-1167J-777D01*
G02X1905807Y434583I-376J-137D01*
G01X1725364D01*
G02X1725081Y435266I0J400D01*
G01X1729772Y439956D01*
Y441090D01*
G02X1730345Y441450I400J0D01*
G03X1730092Y444003I651J1354D01*
G02X1729772Y444163I-120J160D01*
G01Y444380D01*
G03X1725949Y445735I-2152J0D01*
G02X1725405Y445661I-311J252D01*
G03X1723579Y445492I-815J-1140D01*
G02X1723001I-289J277D01*
G03Y443550I-1011J-971D01*
G02X1723579I289J-277D01*
G03X1723628Y443501I1016J966D01*
G02X1723568Y442871I-274J-292D01*
G03X1723475Y440394I801J-1270D01*
G02X1723520Y439790I-238J-321D01*
G01X1722182Y438452D01*
X1682609D01*
X1676548Y432391D01*
Y309390D01*
X1674248Y307090D01*
Y269009D01*
X1681242Y262016D01*
X1840834D01*
G02X1841116Y261333I-1J-400D01*
G01X1833145Y253361D01*
X1832737D01*
X1832681Y253410D01*
G03X1830666Y253361I-980J-1138D01*
G01X1738665D01*
X1736375Y251071D01*
Y238812D01*
X1736201Y238789D01*
G03X1735413Y238432I200J-1489D01*
G02X1734887I-263J302D01*
G03Y236168I-987J-1132D01*
G02X1735413I263J-302D01*
G03X1736201Y235811I988J1132D01*
G01X1736375Y235788D01*
Y234766D01*
X1736254Y234714D01*
G03X1735516Y234030I593J-1380D01*
G02X1734892Y233920I-354J185D01*
G03X1735211Y232114I-1012J-1110D01*
G02X1735835Y232224I354J-185D01*
G03X1738032Y232411I1012J1110D01*
G02X1738662I315J-246D01*
G03X1741311Y233000I1185J923D01*
G02X1741848Y233283I390J-89D01*
G03X1742742Y233219I549J1398D01*
G02X1743226Y232754I91J-389D01*
G03X1745923Y232961I1377J-265D01*
G02X1746300Y233495I377J134D01*
G01X1747565D01*
G02X1747964Y233066I0J-400D01*
G03X1750960I1498J-111D01*
G02X1751359Y233495I399J29D01*
G01X1751841D01*
G02X1752175Y232876I0J-400D01*
G03X1754745Y232212I1172J-770D01*
G02X1755126Y232311I199J15D01*
G02X1755227Y231449I-1274J-586D01*
G03X1755619Y230970I392J-79D01*
G01X1756968D01*
X1761271Y226668D01*
X1856179D01*
X1862233Y220614D01*
X1872213D01*
X1880804Y229204D01*
Y230316D01*
G02X1881444Y230636I400J0D01*
G03X1883394Y232912I901J1201D01*
G02X1883364Y233451I280J286D01*
G03X1883425Y233531I-1163J950D01*
G02X1883940Y233652I326J-232D01*
G03X1885288Y233615I711J1323D01*
G02X1885858Y233253I170J-362D01*
G01Y229346D01*
G02X1885362Y228958I-400J0D01*
G03Y226042I-362J-1458D01*
G02X1885858Y225654I96J-388D01*
G01Y225246D01*
G02X1885510Y225112I-200J0D01*
G03X1883413Y225232I-1110J-1012D01*
G02X1882887I-263J302D01*
G03Y222968I-987J-1132D01*
G02X1883413I263J-302D01*
G03X1885236Y222852I987J1132D01*
G02X1885858Y222520I222J-333D01*
G01Y219279D01*
G02X1885210Y218966I-400J0D01*
G03Y216766I-870J-1100D01*
G02X1885858Y216453I248J-313D01*
G01Y214154D01*
G03X1885736Y214007I1092J-1031D01*
G02X1885054Y214063I-324J234D01*
G03X1882947Y212323I-1254J-627D01*
G02Y211688I-243J-318D01*
G03X1884974Y209808I853J-1113D01*
G02X1885639Y209813I334J-219D01*
G03X1885858Y209562I1159J790D01*
G01Y203675D01*
X1885709Y203636D01*
G03X1885095Y203307I383J-1452D01*
G02X1884518Y203354I-266J299D01*
G03X1882333Y201305I-1169J-943D01*
G02X1882372Y200759I-271J-294D01*
G03X1884420Y201029I1167J-946D01*
G02X1884398Y201334I118J162D01*
G03X1884488Y201429I-1045J1080D01*
G02X1884810Y201403I152J-130D01*
G03X1887341Y201349I1283J781D01*
G02X1887957Y201409I333J-222D01*
G01X1895226Y194140D01*
X1895238Y194081D01*
G03X1896411Y192908I1472J299D01*
G01X1896470Y192896D01*
X1910701Y178665D01*
X1910712Y178604D01*
G03X1911924Y177392I1478J266D01*
G01X1911985Y177381D01*
X1915027Y174339D01*
Y154481D01*
G02X1914640Y154081I-400J0D01*
G03X1913770Y153767I50J-1501D01*
G02X1913196Y153855I-245J316D01*
G03X1912881Y151813I-1235J-855D01*
G02X1913455Y151725I245J-316D01*
G03X1913528Y151629I1231J860D01*
G02X1913253Y150977I-310J-253D01*
G03X1913265Y147784I139J-1596D01*
G02X1913632Y147355I-32J-399D01*
G03X1916395Y146928I1398J-106D01*
G02X1917067Y147119I389J-92D01*
G01X1918289Y145897D01*
X1930276D01*
X1931725Y144448D01*
Y132280D01*
G02X1931012Y132032I-400J1D01*
G03X1928620Y129907I-1256J-995D01*
G02X1928631Y129354I-283J-282D01*
G03X1928250Y128116I1105J-1018D01*
G02X1927868Y127657I-395J-59D01*
G03X1926785Y125170I50J-1501D01*
G02X1926762Y124620I-301J-263D01*
G03X1926398Y123031I1048J-1076D01*
G02X1926205Y122539I-376J-136D01*
G03X1928304Y121716I687J-1336D01*
G02X1928497Y122208I376J136D01*
G03X1928943Y124530I-687J1336D01*
G02X1928966Y125080I301J263D01*
G03X1929404Y126377I-1048J1076D01*
G02X1929786Y126836I395J59D01*
G03X1930856Y129338I-50J1501D01*
G02X1930875Y129891I298J267D01*
G03X1931012Y130042I-1116J1150D01*
G02X1931725Y129794I313J-249D01*
G01Y123375D01*
X1933489Y121611D01*
G02X1933162Y120931I-283J-282D01*
G03X1934491Y119602I-164J-1493D01*
G02X1935171Y119929I398J44D01*
G01X1951411Y103689D01*
X1951355Y103563D01*
G03X1953339Y101579I1371J-613D01*
G01X1953465Y101635D01*
X1958300Y96800D01*
Y81928D01*
X1956556Y80184D01*
G02X1955873Y80463I-283J283D01*
G03X1952731Y80009I-1602J-14D01*
G02X1952530Y79545I-385J-109D01*
G03X1952329Y79296I185J-355D01*
G02X1950473Y76896I-3857J1065D01*
G03X1950274Y76576I200J-346D01*
G02X1949875Y76202I-399J26D01*
G01X1946624D01*
X1946593Y76364D01*
G03X1943959Y77260I-1573J-304D01*
G02X1943433Y77256I-265J299D01*
G03X1941207Y77120I-1043J-1216D01*
G02X1940623Y77112I-296J269D01*
G03X1938359Y77154I-1153J-1112D01*
G02X1937806Y77151I-278J288D01*
G03X1935147Y76355I-1100J-1164D01*
G01X1935111Y76202D01*
X1913185D01*
X1913134Y76150D01*
X1911600D01*
X1909700Y74250D01*
X1898247D01*
G03X1897176Y74948I-1278J-790D01*
G02X1896836Y75408I55J396D01*
G03X1893893Y75303I-1482J243D01*
G02X1893600Y74823I-389J-92D01*
G03X1892761Y74268I361J-1458D01*
G01X1879475D01*
X1879431Y74407D01*
G03X1876569I-1431J-457D01*
G01X1876525Y74268D01*
X1874592D01*
X1868513Y80347D01*
X1861219D01*
X1858833Y82733D01*
Y100249D01*
X1852841Y106241D01*
X1852843Y106326D01*
G03Y106388I-1502J31D01*
G02X1853259Y106796I400J9D01*
G03X1851916Y108240I58J1401D01*
G02X1851479Y107854I-400J12D01*
G03X1851309Y107860I-138J-1496D01*
G01X1851224Y107858D01*
X1850173Y108909D01*
Y137987D01*
X1848971Y139189D01*
G02X1849122Y139849I283J282D01*
G03X1849627Y142581I-532J1511D01*
G02X1849616Y143180I259J304D01*
G03X1847495Y143139I-1084J1180D01*
G02X1847506Y142540I-259J-304D01*
G03X1847079Y141892I1084J-1179D01*
G02X1846419Y141741I-378J132D01*
G01X1843928Y144232D01*
Y167523D01*
X1838873Y172578D01*
X1799147D01*
X1799091Y172685D01*
G03X1796875Y173047I-1243J-648D01*
G02X1796321I-277J288D01*
G03X1794299Y172967I-973J-1010D01*
G02X1793722Y172945I-299J266D01*
G03X1791501Y172578I-974J-1008D01*
G01X1776650D01*
X1771531Y177697D01*
G02X1771627Y178334I283J283D01*
G03X1769681Y179029I-654J1240D01*
G02X1769313Y178473I-368J-156D01*
G01X1766404D01*
G02X1766020Y178984I0J400D01*
G03X1763326I-1347J390D01*
G02X1762942Y178473I-384J-111D01*
G01X1760035D01*
G02X1759667Y179029I0J400D01*
G03X1757083I-1292J545D01*
G02X1756715Y178473I-368J-156D01*
G01X1753706D01*
G02X1753322Y178984I0J400D01*
G03X1750628I-1347J390D01*
G02X1750244Y178473I-384J-111D01*
G01X1747437D01*
G02X1747069Y179029I0J400D01*
G03X1744485I-1292J545D01*
G02X1744117Y178473I-368J-156D01*
G01X1741108D01*
G02X1740724Y178984I0J400D01*
G03X1738030I-1347J390D01*
G02X1737646Y178473I-384J-111D01*
G01X1734838D01*
G02X1734470Y179029I0J400D01*
G03X1731886I-1292J545D01*
G02X1731518Y178473I-368J-156D01*
G01X1728423D01*
G02X1728041Y178990I0J400D01*
G03X1725359I-1341J410D01*
G02X1724977Y178473I-382J-117D01*
G01X1721131D01*
G02X1720736Y178931I1J400D01*
G03X1717808Y178729I-1486J219D01*
G01X1717816Y178702D01*
Y178473D01*
X1717555D01*
X1715533Y176451D01*
G02X1714902Y176536I-283J283D01*
G03X1712855Y174489I-1306J-741D01*
G02X1712940Y173858I-198J-348D01*
G01X1711660Y172578D01*
X1696229D01*
X1695274Y173534D01*
Y184263D01*
X1695223Y184313D01*
Y184537D01*
X1691100Y188660D01*
X1678643D01*
X1674177Y184194D01*
X1674159Y184182D01*
G03X1673730Y183753I753J-1182D01*
G01X1673718Y183735D01*
X1673529Y183546D01*
G02X1672901Y183629I-282J283D01*
G03X1670984Y181712I-1213J-704D01*
G02X1671067Y181084I-200J-346D01*
G01X1666040Y176057D01*
X1623408D01*
G02X1623144Y176757I0J400D01*
G03X1621870Y176451I-926J1052D01*
G01X1622020Y176412D01*
Y176057D01*
X1621667D01*
X1621224Y175614D01*
X1621007D01*
X1619316Y173922D01*
Y173706D01*
X1619304Y173694D01*
Y170170D01*
G03X1618604Y168969I702J-1214D01*
G01X1618603Y168887D01*
X1618415Y168699D01*
X1601147Y168698D01*
X1601105Y168719D01*
G03X1599875I-615J-1260D01*
G01X1599833Y168698D01*
X1586297D01*
X1583142Y165543D01*
Y111685D01*
G02X1582688Y111289I-400J0D01*
G03Y108511I-188J-1389D01*
G02X1583142Y108115I54J-396D01*
G01Y97688D01*
X1591494Y89336D01*
Y85771D01*
G02X1590829Y85472I-400J1D01*
G03X1588883Y85387I-929J-1050D01*
G02X1588319Y85370I-291J275D01*
G03X1588376Y83383I-960J-1022D01*
G02X1588940Y83400I291J-275D01*
G03X1590829Y83372I960J1022D01*
G02X1591494Y83073I265J-300D01*
G01Y79650D01*
G02X1590954Y79276I-400J0D01*
G03X1589067Y77840I-490J-1314D01*
G02X1588731Y77410I-398J-35D01*
G03X1589971Y74814I231J-1484D01*
G02X1590542Y74780I269J-296D01*
G03X1591332Y74324I1058J920D01*
G01X1591494Y74292D01*
Y71508D01*
X1591471Y71464D01*
G03Y70170I1244J-647D01*
G01X1591494Y70126D01*
Y68596D01*
X1590117Y67219D01*
X1580408D01*
G02X1580133Y67909I0J400D01*
G03X1578067I-1033J1091D01*
G02X1577792Y67219I-275J-290D01*
G01X1554416D01*
X1548265Y73370D01*
Y99580D01*
G02X1548729Y99974I400J-1D01*
G03Y102742I226J1384D01*
G02X1548265Y103136I-64J395D01*
G01Y103372D01*
X1548510D01*
X1548550Y103353D01*
G03X1548775Y106157I637J1360D01*
G02X1548265Y106541I-110J385D01*
G01Y113699D01*
G02X1548735Y114092I400J-1D01*
G03Y117050I265J1479D01*
G02X1548265Y117443I-70J394D01*
G01Y165970D01*
X1545537Y168698D01*
X1528510D01*
G03X1526490I-1010J-972D01*
G01X1470198D01*
X1466946Y171950D01*
X1452750D01*
X1452302Y171502D01*
X1452167Y171588D01*
G03X1451909Y171718I-802J-1270D01*
G02X1451911Y172092I72J187D01*
G03X1452450Y174559I-525J1407D01*
G02X1452430Y175102I283J282D01*
G03X1451993Y177268I-1065J912D01*
G02X1451808Y177791I179J358D01*
G03X1449904Y177118I-1276J581D01*
G02X1450089Y176595I-179J-358D01*
G03X1450316Y175084I1276J-581D01*
G02X1450304Y174541I-300J-265D01*
G03X1450554Y172248I1082J-1042D01*
G02X1450550Y171579I-221J-333D01*
G03X1450095Y169516I815J-1261D01*
G01X1450181Y169381D01*
X1450000Y169200D01*
Y165922D01*
X1449984Y165884D01*
G03Y164708I1382J-588D01*
G01X1450000Y164670D01*
Y152728D01*
G03Y150524I1021J-1102D01*
G01Y149494D01*
X1449984Y149456D01*
G03Y148354I1289J-551D01*
G01X1450000Y148316D01*
Y147074D01*
X1449979Y147032D01*
G03Y145778I1254J-627D01*
G01X1450000Y145736D01*
Y144489D01*
G03Y143033I1198J-728D01*
G01Y141939D01*
X1449978Y141896D01*
G03Y140626I1250J-635D01*
G01X1450000Y140583D01*
Y113369D01*
G03Y111081I973J-1144D01*
G01Y61600D01*
X1425199Y36799D01*
G02X1424528Y36982I-283J282D01*
G03X1422823Y35277I-1358J-347D01*
G02X1423006Y34606I-99J-388D01*
G01X1408102Y19702D01*
X1403385D01*
G02X1403212Y20462I1J400D01*
G03X1399820I-1696J3514D01*
G02X1399647Y19702I-174J-360D01*
G01X1398285D01*
X1396898Y18315D01*
Y10585D01*
X1397150Y10334D01*
Y2850D01*
X1389700Y-4600D01*
Y-4821D01*
X1389409D01*
X1389349Y-4752D01*
G03X1389077Y-6838I-1055J-923D01*
G02X1389700Y-7170I223J-332D01*
G01Y-21022D01*
X1388900Y-21822D01*
X1333500D01*
X1331100Y-19422D01*
Y69700D01*
X1318068Y82732D01*
G02X1318130Y83348I283J283D01*
G03X1318681Y84010I-830J1252D01*
G02X1319249Y84199I368J-157D01*
G03X1319286Y86821I751J1301D01*
G02X1318696Y87157I-190J352D01*
G03X1318366Y88039I-1501J-59D01*
G02X1318388Y88565I312J250D01*
G03X1316129Y88659I-1088J1035D01*
G02X1316107Y88133I-312J-250D01*
G03X1316105Y86064I1088J-1036D01*
G02X1316128Y85539I-290J-276D01*
G03X1316048Y85430I1170J-942D01*
G02X1315432Y85368I-333J221D01*
G01X1311536Y89264D01*
G02X1311764Y89943I283J283D01*
G03X1312681Y92430I-205J1488D01*
G02X1312679Y92960I298J266D01*
G03X1310478Y95003I-1127J993D01*
G02X1309938Y94974I-286J280D01*
G01X1309937D01*
G02X1309935Y95589I255J308D01*
G03X1308018Y95582I-963J1153D01*
G02X1308020Y94967I-255J-308D01*
G03X1307519Y94148I964J-1152D01*
G02X1306846Y93954I-390J89D01*
G01X1305400Y95400D01*
X1299800D01*
X1296200Y99000D01*
X1289000D01*
X1288774Y98774D01*
X1288669Y98794D01*
G03X1286907Y97032I-288J-1474D01*
G01X1286927Y96927D01*
X1285400Y95400D01*
X1093400D01*
X1080000Y108800D01*
X1050200D01*
X1050100Y108700D01*
X1015000D01*
X1001700Y95400D01*
X772800D01*
X772750Y95450D01*
X770050D01*
X767400Y98100D01*
X760100D01*
X758300Y96300D01*
Y89400D01*
X760500Y87200D01*
Y39500D01*
X757896Y36896D01*
G02X757277Y36961I-283J283D01*
G03X754889Y35494I-1177J-761D01*
G02X754544Y34892I-345J-202D01*
G01X749597D01*
G03X738989I-5304J-2914D01*
G01X738230D01*
G02X737875Y35476I0J400D01*
G03X737683Y37049I-1244J646D01*
G02X737688Y37583I300J264D01*
G03X735682Y39541I-1033J948D01*
G02X735128I-277J288D01*
G03X733103Y37604I-973J-1010D01*
G02X733098Y37070I-300J-264D01*
G03X732887Y35476I1033J-948D01*
G02X732532Y34892I-355J-184D01*
G01X703298D01*
G02X702905Y35363I1J400D01*
G03X702098Y36889I-1380J247D01*
G02X701960Y37517I164J365D01*
G03X700331Y37160I-1056J922D01*
G02X700469Y36532I-164J-365D01*
G03X700145Y35363I1056J-922D01*
G02X699752Y34892I-394J-71D01*
G01X673144D01*
X671509Y36527D01*
X646300D01*
X644000Y38827D01*
Y90548D01*
G02X644506Y90934I400J0D01*
G03X645617Y91060I398J1448D01*
G02X646122Y90955I190J-352D01*
G03X646148Y90923I1179J931D01*
G02X645916Y90275I-308J-255D01*
G03X645068Y87813I284J-1475D01*
G02Y87287I-302J-263D01*
G03X645818Y84847I1132J-987D01*
G02X646112Y84406I-102J-387D01*
G03X649092Y84374I1488J-206D01*
G02X649428Y84815I397J46D01*
G03X650332Y87287I-228J1485D01*
G02Y87813I302J263D01*
G03X650586Y89380I-1132J988D01*
G02X650797Y89902I369J155D01*
G03X650922Y89963I-595J1379D01*
G02X651469Y89794I191J-352D01*
G03X653443Y91841I1335J688D01*
G02X653425Y92556I170J362D01*
G03X652079Y92522I-707J1325D01*
G02X652097Y91807I-170J-362D01*
G03X652086Y91801I714J-1321D01*
G02X651539Y91970I-191J352D01*
G03X649250Y92442I-1335J-688D01*
G02X648640Y92568I-254J309D01*
G03X646591Y93204I-1336J-686D01*
G02X646086Y93309I-190J352D01*
G03X643441Y92723I-1182J-927D01*
G02X642769Y92531I-389J91D01*
G01X639700Y95600D01*
X616916D01*
X616413Y96103D01*
X616015Y96502D01*
X615998D01*
X615800Y96700D01*
X441800D01*
X429949Y108551D01*
X400143D01*
X390548Y98956D01*
Y98945D01*
X390470Y98867D01*
Y97516D01*
X389654Y96700D01*
X91400D01*
X91202Y96502D01*
X91085D01*
X90687Y96103D01*
X88651Y94067D01*
G02X87975Y94272I-283J283D01*
G03X86689Y92601I-1375J-272D01*
G01X86780Y92607D01*
X86985Y92401D01*
X86584Y92000D01*
X83365D01*
G02X83031Y92620I0J400D01*
G03X80691I-1170J772D01*
G02X80357Y92000I-334J-220D01*
G01X69762D01*
G03X68725Y92412I-1037J-1100D01*
G01X63725D01*
G03X62688Y92000I0J-1511D01*
G01X59399D01*
X32560Y65161D01*
X28914D01*
X28861Y65280D01*
G03X27904Y66114I-1373J-609D01*
G02X27630Y66608I111J384D01*
G03X27631Y67422I-1445J409D01*
G02X27913Y67916I385J107D01*
G03X27723Y70856I-388J1451D01*
G02X27378Y71297I53J397D01*
G03X27312Y71940I-1492J172D01*
G02X27677Y72466I379J126D01*
G03X27784Y75461I-51J1501D01*
G02X27427Y75860I43J398D01*
G03X27424Y75963I-1502J8D01*
G02X27760Y76384I399J26D01*
G03X28605Y78911I-235J1483D01*
G02X28759Y79567I287J279D01*
G03X28863Y79608I-462J1323D01*
G02X29394Y79398I162J-366D01*
G03X32088Y79979I1292J544D01*
G02X32490Y80389I400J10D01*
G03X32256Y83172I9J1402D01*
G02X31790Y83618I-70J394D01*
G03X31177Y84967I-1390J182D01*
G02Y85633I222J333D01*
G03Y87967I-777J1167D01*
G02Y88633I222J333D01*
G03X29426Y90808I-776J1167D01*
G02X28849Y90830I-278J288D01*
G03X27023Y88733I-1049J-930D01*
G02Y88067I-222J-333D01*
G03Y85733I777J-1167D01*
G02Y85067I-222J-333D01*
G03X27256Y82608I777J-1167D01*
G02X27366Y81940I-155J-369D01*
G03X27347Y81923I925J-1053D01*
G02X26809Y81921I-270J295D01*
G03X26817Y79846I-939J-1041D01*
G02X27355Y79848I270J-295D01*
G03X27506Y79729I941J1039D01*
G02X27409Y79365I-113J-165D01*
G03X26026Y77771I116J-1498D01*
G02X25690Y77350I-399J-26D01*
G03X25766Y74373I235J-1483D01*
G02X26123Y73974I-43J-398D01*
G03X26199Y73494I1502J-8D01*
G02X25834Y72968I-379J-126D01*
G03X25688Y69978I52J-1501D01*
G02X26033Y69537I-53J-397D01*
G03X26079Y68962I1492J-170D01*
G02X25797Y68468I-385J-107D01*
G03X25219Y65867I388J-1451D01*
G02X24962Y65161I-258J-306D01*
G01X13432D01*
X13426Y65355D01*
G03X13057Y66298I-1501J-44D01*
G02Y66824I302J263D01*
G03X10793I-1132J987D01*
G02Y66298I-302J-263D01*
G03X10424Y65355I1132J-987D01*
G01X10418Y65161D01*
X4870D01*
G02X4477Y65636I0J400D01*
G03X3131Y67302I-1377J264D01*
G02X2749Y67790I8J400D01*
G03X1351Y66698I-1367J310D01*
G02X1733Y66210I-8J-400D01*
G03X1723Y65636I1367J-311D01*
G02X1330Y65161I-393J-75D01*
G01X-836D01*
X-876Y65180D01*
G03X-2064I-594J-1270D01*
G01X-2104Y65161D01*
X-9262D01*
G03X-9411Y65368I-1207J-712D01*
G02X-9171Y66025I302J262D01*
G03X-10449Y66492I-218J1385D01*
G02X-10689Y65835I-302J-262D01*
G03X-11678Y65161I219J-1385D01*
G01X-12459D01*
G03X-14761I-1151J-801D01*
G01X-18806D01*
X-21822Y68177D01*
Y588800D01*
X-20124Y590498D01*
X-13778D01*
X-13725Y590381D01*
G03X-11158Y590421I1275J584D01*
G01X-11142Y590458D01*
X-6100Y595500D01*
X-5927D01*
G02X-5610Y594856I0J-400D01*
G03X-3390I1110J-856D01*
G02X-3073Y595500I317J244D01*
G01X4800D01*
X6300Y594000D01*
X42453D01*
G03X43967I757J1180D01*
G01X45759D01*
G03X47241I741J1190D01*
G01X58000D01*
X62000Y590000D01*
Y561573D01*
G03Y561427I1500J-73D01*
G01Y557573D01*
G03Y557427I1500J-73D01*
G01Y554573D01*
G03Y554427I1500J-73D01*
G01Y539200D01*
X64534Y536666D01*
X64402Y536525D01*
G03X64315Y536423I1098J-1025D01*
G02X63685I-315J246D01*
G03Y534577I-1185J-923D01*
G02X64315I315J-246D01*
G03X66525Y534402I1185J923D01*
G02X66803Y534397I136J-146D01*
G01X88898Y512302D01*
G03X92860Y508308I5785J1777D01*
G01X92907Y508293D01*
X94202Y506998D01*
X113172D01*
G03X115712I1270J802D01*
G01X420060D01*
X431372Y495686D01*
X434778D01*
X446090Y506998D01*
X615515D01*
X619900Y511383D01*
Y513387D01*
X620012Y513442D01*
G03Y515958I-620J1258D01*
G01X619900Y516013D01*
Y531180D01*
G02X620276Y531579I400J0D01*
G03Y534377I-84J1399D01*
G02X619900Y534776I24J399D01*
G01Y554826D01*
G03X619949Y556721I-1008J974D01*
G01X619900Y556777D01*
Y557200D01*
X621400Y558700D01*
X757100D01*
X758600Y557200D01*
Y510200D01*
X761650Y507150D01*
Y505750D01*
X763000Y504400D01*
X765002D01*
X767300Y506698D01*
X990000D01*
X1001104Y495594D01*
X1085566D01*
X1085665Y495694D01*
X1085684D01*
X1096689Y506698D01*
X1322315D01*
X1322316Y506700D01*
X1322800D01*
X1329000Y512900D01*
Y513384D01*
X1329002Y513385D01*
Y544721D01*
G03Y546589I-1046J934D01*
G01Y622880D01*
X1330700Y624578D01*
X1390700D01*
X1391800Y623478D01*
Y622510D01*
G02X1391285Y622127I-400J0D01*
G03Y619251I-434J-1438D01*
G02X1391800Y618868I115J-383D01*
G01Y602700D01*
X1402300Y592200D01*
X1429300D01*
X1438500Y601400D01*
Y613500D01*
X1437052Y614948D01*
G02Y615514I283J283D01*
G03X1437169Y615811I-283J283D01*
G02X1437776Y617015I1401J49D01*
G03X1437684Y617722I-226J330D01*
G02X1437118Y620188I506J1414D01*
G03X1436907Y620861I-286J280D01*
G02X1436091Y621308I278J1476D01*
G03X1435800Y621434I-291J-274D01*
G02X1435400Y621834I0J400D01*
G01Y623600D01*
X1436378Y624578D01*
G37*
G36*
G01X-20621Y661811D02*
G02X-19685Y662747I936J0D01*
G01X1972600D01*
Y637600D01*
X-20412D01*
G02X-20621Y638189I726J589D01*
G01Y661811D01*
G37*
G36*
G01X65259Y16324D02*
G03X63910Y18863I-1059J1065D01*
G01X63806Y18842D01*
X57600Y25048D01*
Y78400D01*
X59536Y80336D01*
X59673Y80246D01*
G03X61912Y82013I827J1254D01*
G02X62287Y82550I376J137D01*
G01X69450D01*
X69500Y82500D01*
X78500D01*
X84282Y88282D01*
X84322Y88298D01*
G03X85189Y89165I-536J1403D01*
G01X85190Y89166D01*
X85206Y89206D01*
X91500Y95500D01*
X383042D01*
X383092Y95375D01*
G03X385692I1300J525D01*
G01X385742Y95500D01*
X390772D01*
X391471Y96199D01*
Y98452D01*
X400522Y107503D01*
X429571D01*
X441574Y95500D01*
X615600D01*
X616650Y94450D01*
X628050D01*
X631100Y91400D01*
Y47200D01*
X639830Y38470D01*
G02X639439Y37802I-283J-283D01*
G03X643530Y30052I-1646J-5824D01*
G02X644229Y30165I379J-127D01*
G03X644475Y32226I1201J902D01*
G02X643822Y32501I-254J309D01*
G03X643617Y33624I-6030J-520D01*
G02X644285Y34015I385J108D01*
G01X644550Y33750D01*
X659636D01*
G02X660026Y33265I-1J-400D01*
G03X660012Y33188I1470J-307D01*
G02X659524Y32864I-395J65D01*
G03X660570Y31204I-324J-1364D01*
G02X661073Y31504I391J-84D01*
G03X662962Y33265I421J1442D01*
G02X663352Y33750I391J85D01*
G01X663550D01*
X667200Y30100D01*
Y24283D01*
G02X666505Y24013I-400J0D01*
G03Y21987I-1109J-1013D01*
G02X667200Y21717I295J-270D01*
G01Y600D01*
X664100Y-2500D01*
Y-16401D01*
G02X663478Y-16734I-400J0D01*
G03X661845Y-16789I-778J-1166D01*
G02X661264Y-16688I-244J317D01*
G03X660974Y-18643I-1264J-812D01*
G02X661559Y-18715I259J-304D01*
G03X663478Y-19066I1141J815D01*
G02X664100Y-19399I222J-333D01*
G01Y-20800D01*
X663100Y-21800D01*
X658446D01*
G02X658082Y-21234I0J400D01*
G03X655532I-1275J582D01*
G02X655168Y-21800I-364J-166D01*
G01X438076D01*
G02X437703Y-21258I1J400D01*
G03X435081I-1311J498D01*
G02X434708Y-21800I-374J-142D01*
G01X424587D01*
G02X424211Y-21264I0J400D01*
G03X421573I-1319J475D01*
G02X421197Y-21800I-376J-136D01*
G01X411219D01*
G02X410842Y-21266I0J400D01*
G03X408202I-1320J472D01*
G02X407825Y-21800I-377J-134D01*
G01X68900D01*
X68692Y-21592D01*
X68771Y-21458D01*
G03X67139Y-19409I-1207J713D01*
G02X66627Y-19118I-122J381D01*
G03X65372Y-17969I-1463J-338D01*
G01X65200Y-17944D01*
Y-15534D01*
G02X65697Y-15146I400J0D01*
G03Y-12232I364J1457D01*
G02X65200Y-11844I-97J388D01*
G01Y10364D01*
G03X65245Y12190I-1041J939D01*
G01X65200Y12245D01*
Y12410D01*
G02X65644Y12807I400J-1D01*
G03Y15593I156J1393D01*
G02X65200Y15990I-44J398D01*
G01Y16265D01*
X65259Y16324D01*
G37*
G36*
G01X101300Y301814D02*
G02X101912Y302153I400J0D01*
G03X102099Y302045I1594J2544D01*
G03X104901I1401J55D01*
G03X105824Y306600I-1401J2655D01*
G03X101912Y311047I-2324J1899D01*
G02X101300Y311386I-212J339D01*
G01Y313730D01*
X101981Y314411D01*
G02X102539Y314419I283J-282D01*
G03X106250Y319110I2061J2183D01*
G01Y376430D01*
X95100Y387580D01*
Y427700D01*
X97200Y429800D01*
X126110D01*
G02X126474Y429234I0J-400D01*
G03X126398Y429034I1456J-668D01*
G02X125878Y428774I-383J115D01*
G03X123812Y427786I-550J-1505D01*
G03X117549Y422941I-371J-5991D01*
G03X116303Y418333I4693J-3741D01*
G03X116435Y416365I1060J-917D01*
G02X116505Y415846I-265J-300D01*
G03X116354Y412813I2511J-1645D01*
G03X117331Y409175I2746J-1213D01*
G02X117366Y408557I-236J-323D01*
G03X119919Y403392I2033J-2209D01*
G03X121471Y402615I2062J2181D01*
G02X121690Y401942I-68J-394D01*
G03X123526Y402275I1150J-1115D01*
G02X123496Y402981I172J361D01*
G03X121460Y408529I-1515J2592D01*
G03X121167Y408773I-2063J-2180D01*
G02X121132Y409391I236J323D01*
G03X121762Y412988I-2032J2210D01*
G03X121850Y413210I-2745J1216D01*
G03X126656Y415132I392J5989D01*
G02X127274Y415094I293J-272D01*
G03X129500Y413025I6288J4533D01*
G01Y405720D01*
X133410Y401810D01*
Y400806D01*
X133401Y400777D01*
G03Y399815I1528J-481D01*
G01X133410Y399786D01*
Y205180D01*
X130230Y202000D01*
X119700D01*
X114400Y196700D01*
Y193500D01*
X113700Y192800D01*
X98100D01*
X95600Y195300D01*
Y202736D01*
G02X96050Y203132I400J-1D01*
G03Y206312I199J1590D01*
G02X95600Y206708I-50J397D01*
G01Y213800D01*
X96027Y214227D01*
X96081Y214240D01*
G03X98580Y216739I-806J3305D01*
G01X98593Y216793D01*
X101300Y219500D01*
Y221398D01*
G03Y226202I-1800J2402D01*
G01Y237724D01*
G03Y242876I-1542J2576D01*
G01Y292134D01*
G02X101773Y292527I400J0D01*
G03Y298429I549J2951D01*
G02X101300Y298822I-73J393D01*
G01Y301814D01*
G37*
G36*
G01X616600Y549744D02*
G02X616063Y549368I-400J0D01*
G03X614228Y548671I-514J-1411D01*
G02X613524I-352J191D01*
G03X610881I-1321J-714D01*
G02X610178I-352J190D01*
G03X607535I-1321J-714D01*
G02X606831I-352J191D01*
G03X604188I-1321J-714D01*
G02X603485I-352J190D01*
G03Y547243I-1322J-714D01*
G02X604188I351J-190D01*
G03X606831I1322J714D01*
G02X607535I352J-191D01*
G03X610178I1321J714D01*
G02X610881I352J-190D01*
G03X613524I1321J714D01*
G02X614228I352J-191D01*
G03X616063Y546546I1321J714D01*
G02X616600Y546170I137J-376D01*
G01Y538844D01*
G02X616063Y538468I-400J0D01*
G03X614228Y537771I-514J-1411D01*
G02X613524I-352J191D01*
G03X610881I-1321J-714D01*
G02X610178I-352J190D01*
G03X607535I-1321J-714D01*
G02X606831I-352J191D01*
G03X604188I-1321J-714D01*
G02X603485I-352J190D01*
G03Y536343I-1322J-714D01*
G02X604188I351J-190D01*
G03X606831I1322J714D01*
G02X607535I352J-191D01*
G03X610178I1321J714D01*
G02X610881I352J-190D01*
G03X613524I1321J714D01*
G02X614228I352J-191D01*
G03X616063Y535646I1321J714D01*
G02X616600Y535270I137J-376D01*
G01Y530686D01*
G02X616063Y530310I-400J0D01*
G03X614228Y529613I-514J-1411D01*
G02X613524I-352J191D01*
G03X610881I-1321J-714D01*
G02X610178I-352J190D01*
G03X607535I-1321J-714D01*
G02X606831I-352J191D01*
G03Y528185I-1321J-714D01*
G02X607535I352J-191D01*
G03X610178I1321J714D01*
G02X610881I352J-190D01*
G03X613524I1321J714D01*
G02X614228I352J-191D01*
G03X616063Y527488I1321J714D01*
G02X616600Y527112I137J-376D01*
G01Y519786D01*
G02X616063Y519410I-400J0D01*
G03X614228Y518713I-514J-1411D01*
G02X613524I-352J191D01*
G03X610881I-1321J-714D01*
G02X610178I-352J190D01*
G03X607535I-1321J-714D01*
G02X606831I-352J191D01*
G03Y517285I-1321J-714D01*
G02X607535I352J-191D01*
G03X610178I1321J714D01*
G02X610881I352J-190D01*
G03X613524I1321J714D01*
G02X614228I352J-191D01*
G03X616063Y516588I1321J714D01*
G02X616600Y516212I137J-376D01*
G01Y511944D01*
G02X616063Y511568I-400J0D01*
G03X614228Y510871I-514J-1411D01*
G02X613524I-352J191D01*
G03X610881I-1321J-714D01*
G02X610178I-352J190D01*
G03X607535I-1321J-714D01*
G02X606831I-352J191D01*
G03X604188I-1321J-714D01*
G02X603485I-352J190D01*
G03Y509443I-1322J-714D01*
G02X604188I351J-190D01*
G03X606831I1322J714D01*
G02X607535I352J-191D01*
G03X610178I1321J714D01*
G02X610881I352J-190D01*
G03X613524I1321J714D01*
G02X614228I352J-191D01*
G03X614926Y508790I1322J713D01*
G02X615043Y508143I-166J-364D01*
G01X614900Y508000D01*
X445373D01*
X437900Y500527D01*
Y500500D01*
X437159Y499759D01*
G02X436502Y499899I-283J283D01*
G03X434693Y498090I-1310J-499D01*
G02X434833Y497433I-143J-374D01*
G01X434163Y496763D01*
X432004D01*
X420767Y508000D01*
X390550D01*
G02X390314Y508723I0J400D01*
G03X391788Y511629I-2128J2906D01*
G01Y516529D01*
G03X384586I-3601J0D01*
G01Y511629D01*
G03X386060Y508723I3602J0D01*
G02X385824Y508000I-236J-323D01*
G01X115939D01*
X115902Y508153D01*
G03X115574Y508787I-1460J-353D01*
G02Y509313I302J263D01*
G03X113310I-1132J987D01*
G02Y508787I-302J-263D01*
G03X112982Y508153I1132J-987D01*
G01X112945Y508000D01*
X97745D01*
G02X97555Y508752I0J400D01*
G03X88884Y515810I-2872J5327D01*
G02X88218Y515642I-383J115D01*
G01X65700Y538160D01*
Y622100D01*
X68100Y624500D01*
X354997D01*
G02X355379Y623982I0J-400D01*
G03X358249I1435J-443D01*
G02X358631Y624500I382J118D01*
G01X385153D01*
G02X385535Y623982I0J-400D01*
G03X388405I1435J-443D01*
G02X388787Y624500I382J118D01*
G01X398106D01*
G02X398491Y623993I-1J-400D01*
G03X401157I1333J-434D01*
G02X401542Y624500I386J107D01*
G01X411606D01*
G02X411991Y623993I-1J-400D01*
G03X414657I1333J-434D01*
G02X415042Y624500I386J107D01*
G01X425611D01*
G02X425991Y623976I0J-400D01*
G03X428657I1333J-435D01*
G02X429037Y624500I380J124D01*
G01X444000D01*
Y623800D01*
X444394Y623406D01*
X444403Y623339D01*
G03X447159Y622732I1489J200D01*
G02X447833I337J-215D01*
G03X450598Y623429I1267J807D01*
G01X450603Y623503D01*
X451000Y623900D01*
Y624500D01*
X451516D01*
G02X451880Y623936I-1J-400D01*
G03X454620I1370J-616D01*
G02X454984Y624500I365J164D01*
G01X455176D01*
G02X455540Y623936I-1J-400D01*
G03X458280I1370J-616D01*
G02X458644Y624500I365J164D01*
G01X657900D01*
X664000Y618400D01*
Y599621D01*
G03Y597379I1000J-1121D01*
G01Y595901D01*
X667500Y592401D01*
Y589076D01*
X667499Y589064D01*
G03Y588736I1392J-164D01*
G01X667500Y588724D01*
Y564100D01*
X664300Y560900D01*
X618400D01*
X616600Y559100D01*
Y557586D01*
G02X616063Y557210I-400J0D01*
G03X614228Y556513I-514J-1411D01*
G02X613524I-352J191D01*
G03X610881I-1321J-714D01*
G02X610178I-352J190D01*
G03X607535I-1321J-714D01*
G02X606831I-352J191D01*
G03X604188I-1321J-714D01*
G02X603485I-352J190D01*
G03X600854Y556536I-1322J-714D01*
G02X600151Y556548I-348J196D01*
G03X600126Y555120I-1334J-691D01*
G02X600829Y555108I348J-196D01*
G03X603485Y555085I1334J691D01*
G02X604188I351J-190D01*
G03X606831I1322J714D01*
G02X607535I352J-191D01*
G03X610178I1321J714D01*
G02X610881I352J-190D01*
G03X613524I1321J714D01*
G02X614228I352J-191D01*
G03X616063Y554388I1321J714D01*
G02X616600Y554012I137J-376D01*
G01Y549744D01*
G37*
G36*
G01X379907Y192360D02*
G02X379543Y192926I0J400D01*
G03X376991I-1276J581D01*
G02X376627Y192360I-364J-166D01*
G01X359627D01*
G02X359263Y192926I0J400D01*
G03X356711I-1276J581D01*
G02X356347Y192360I-364J-166D01*
G01X133010D01*
X130600Y194770D01*
Y200954D01*
X134412Y204765D01*
Y366148D01*
X169250D01*
X170119Y365279D01*
Y210689D01*
X171283Y209525D01*
X193925D01*
X232100Y247700D01*
X254186Y247686D01*
X254200Y247700D01*
X262784D01*
G02X263093Y247047I-1J-400D01*
G03X265265I1086J-887D01*
G02X265574Y247700I310J253D01*
G01X266511D01*
X266562Y247576D01*
G03X269156I1297J533D01*
G01X269207Y247700D01*
X269844D01*
G02X270153Y247047I-1J-400D01*
G03X272325I1086J-887D01*
G02X272634Y247700I310J253D01*
G01X273271D01*
X273322Y247576D01*
G03X275916I1297J533D01*
G01X275967Y247700D01*
X276604D01*
G02X276913Y247047I-1J-400D01*
G03X279085I1086J-887D01*
G02X279394Y247700I310J253D01*
G01X280031D01*
X280082Y247576D01*
G03X282676I1297J533D01*
G01X282727Y247700D01*
X286791D01*
X286842Y247576D01*
G03X289436I1297J533D01*
G01X289487Y247700D01*
X289862D01*
X289900Y247662D01*
X293565Y247659D01*
X293617Y247541D01*
G03X296180Y247539I1282J568D01*
G01X296233Y247658D01*
X300326Y247655D01*
X300379Y247536D01*
G03X302938Y247535I1280J573D01*
G01X302991Y247653D01*
X304152Y247652D01*
X307086D01*
X307139Y247534D01*
G03X309697I1279J575D01*
G01X309750Y247652D01*
X310365D01*
G02X310683Y247010I0J-400D01*
G03X312913I1115J-850D01*
G02X313231Y247652I318J242D01*
G01X313846D01*
X313899Y247534D01*
G03X316457I1279J575D01*
G01X316510Y247652D01*
X320606D01*
X320659Y247534D01*
G03X323217I1279J575D01*
G01X323270Y247652D01*
X323885D01*
G02X324203Y247010I0J-400D01*
G03X326433I1115J-850D01*
G02X326751Y247652I318J242D01*
G01X327366D01*
X327419Y247534D01*
G03X329977I1279J575D01*
G01X330030Y247652D01*
X330645D01*
G02X330963Y247010I0J-400D01*
G03X333193I1115J-850D01*
G02X333511Y247652I318J242D01*
G01X334126D01*
X334179Y247534D01*
G03X336737I1279J575D01*
G01X336790Y247652D01*
X340886D01*
X340939Y247534D01*
G03X343497I1279J575D01*
G01X343550Y247652D01*
X344165D01*
G02X344483Y247010I0J-400D01*
G03X346713I1115J-850D01*
G02X347031Y247652I318J242D01*
G01X347646D01*
X347699Y247534D01*
G03X350257I1279J575D01*
G01X350310Y247652D01*
X350924D01*
G02X351242Y247010I0J-400D01*
G03X353472I1115J-850D01*
G02X353790Y247652I318J242D01*
G01X354405D01*
X354458Y247534D01*
G03X357016I1279J575D01*
G01X357069Y247652D01*
X357684D01*
G02X358002Y247010I0J-400D01*
G03X360232I1115J-850D01*
G02X360550Y247652I318J242D01*
G01X361165D01*
X361218Y247534D01*
G03X363776I1279J575D01*
G01X363829Y247652D01*
X364444D01*
G02X364762Y247010I0J-400D01*
G03X366992I1115J-850D01*
G02X367310Y247652I318J242D01*
G01X367925D01*
X367978Y247534D01*
G03X370536I1279J575D01*
G01X370589Y247652D01*
X371204D01*
G02X371522Y247010I0J-400D01*
G03X373752I1115J-850D01*
G02X374070Y247652I318J242D01*
G01X374685D01*
X374738Y247534D01*
G03X377296I1279J575D01*
G01X377349Y247652D01*
X377964D01*
G02X378282Y247010I0J-400D01*
G03X380512I1115J-850D01*
G02X380830Y247652I318J242D01*
G01X382052D01*
X385500Y251100D01*
X407500D01*
X408850Y249750D01*
Y245850D01*
G02X408285Y245486I-400J0D01*
G03Y242932I-579J-1277D01*
G02X408850Y242568I165J-364D01*
G01Y241950D01*
G02X408285Y241586I-400J0D01*
G03Y239032I-579J-1277D01*
G02X408850Y238668I165J-364D01*
G01Y238050D01*
G02X408285Y237686I-400J0D01*
G03Y235132I-579J-1277D01*
G02X408850Y234768I165J-364D01*
G01Y234150D01*
G02X408285Y233786I-400J0D01*
G03Y231232I-579J-1277D01*
G02X408850Y230868I165J-364D01*
G01Y230251D01*
G02X408285Y229887I-400J0D01*
G03Y227333I-579J-1277D01*
G02X408850Y226969I165J-364D01*
G01Y226350D01*
G02X408285Y225986I-400J0D01*
G03Y223432I-579J-1277D01*
G02X408850Y223068I165J-364D01*
G01Y218550D01*
G02X408285Y218186I-400J0D01*
G03Y215632I-579J-1277D01*
G02X408850Y215268I165J-364D01*
G01Y198260D01*
X402950Y192360D01*
X379907D01*
G37*
G36*
G01X134412Y368152D02*
Y402225D01*
X132869Y403767D01*
G02X133152Y404450I283J283D01*
G01X151350D01*
X152003Y403797D01*
X152015Y403736D01*
G03X153128Y402623I1377J264D01*
G01X153189Y402611D01*
X155000Y400800D01*
X166570D01*
X169000Y398370D01*
Y390236D01*
X168958Y390195D01*
Y369431D01*
X167680Y368152D01*
X134412D01*
G37*
G36*
G01X172447Y210814D02*
X171900Y211361D01*
Y363100D01*
X172500Y363700D01*
X214400D01*
X247801Y330300D01*
X266060D01*
G02X266460Y329924I1J-400D01*
G03X269258I1399J85D01*
G02X269658Y330300I399J-24D01*
G01X272500D01*
X273320Y329480D01*
X273335Y329445D01*
G03X274055Y328725I1284J564D01*
G01X274090Y328710D01*
X274626Y328174D01*
G02X274405Y327496I-283J-283D01*
G03X276005Y325896I214J-1386D01*
G02X276683Y326117I395J-62D01*
G01X276975Y325825D01*
G02X276967Y325251I-283J-283D01*
G03X279090Y323128I1032J-1091D01*
G02X279664Y323136I291J-275D01*
G01X279995Y322805D01*
X279955Y322688D01*
G03X281858Y320785I1424J-479D01*
G01X281975Y320825D01*
X284454Y318346D01*
G02X284302Y317685I-283J-283D01*
G03X286136Y316625I457J-1325D01*
G02X286529Y317100I393J75D01*
G01X287427D01*
X287472Y317076D01*
G03X288806I667J1233D01*
G01X288851Y317100D01*
X289749D01*
G02X290142Y316625I0J-400D01*
G03X292896I1377J-265D01*
G02X293289Y317100I393J75D01*
G01X294187D01*
X294232Y317076D01*
G03X295566I667J1233D01*
G01X295611Y317100D01*
X296509D01*
G02X296902Y316625I0J-400D01*
G03X299656I1377J-265D01*
G02X300049Y317100I393J75D01*
G01X300947D01*
X300992Y317076D01*
G03X302326I667J1233D01*
G01X302371Y317100D01*
X303269D01*
G02X303662Y316625I0J-400D01*
G03X306416I1377J-265D01*
G02X306809Y317100I393J75D01*
G01X307706D01*
X307751Y317076D01*
G03X309085I667J1233D01*
G01X309130Y317100D01*
X310028D01*
G02X310421Y316625I0J-400D01*
G03X313175I1377J-265D01*
G02X313568Y317100I393J75D01*
G01X314287D01*
G03X314712Y316881I892J1209D01*
G01X314758Y316866D01*
X315156Y316468D01*
G02X314941Y315791I-283J-283D01*
G03X316560Y314172I237J-1382D01*
G02X317237Y314387I394J-68D01*
G01X317587Y314037D01*
G02X317582Y313467I-283J-283D01*
G03X319565Y311484I976J-1007D01*
G02X320095Y311524I287J-278D01*
G01X320244D01*
G02X320620Y310988I0J-400D01*
G03X323256I1318J-479D01*
G02X323632Y311524I376J136D01*
G01X324274D01*
G03X326362I1044J936D01*
G01X327004D01*
G02X327380Y310988I0J-400D01*
G03X330016I1318J-479D01*
G02X330392Y311524I376J136D01*
G01X331034D01*
G03X333122I1044J936D01*
G01X333764D01*
G02X334140Y310988I0J-400D01*
G03X336639Y311265I1318J-479D01*
G01X336552Y311400D01*
X336995Y311842D01*
G02X337624Y311759I283J-283D01*
G03X338264Y313739I1214J701D01*
G02X337700Y314104I-164J365D01*
G01Y314716D01*
G02X338264Y315081I400J0D01*
G03X339775Y317403I574J1279D01*
G02X340043Y318100I268J297D01*
G01X340823D01*
X340862Y317951D01*
G03X343574I1356J358D01*
G01X343613Y318100D01*
X347482D01*
X347520Y317948D01*
G03X350436I1458J361D01*
G01X350474Y318100D01*
X374700D01*
X382100Y325500D01*
Y332200D01*
X376186Y338114D01*
G03X375641Y338659I-1299J-754D01*
G01X375500Y338800D01*
X375315D01*
X375289Y338807D01*
G03X374485I-402J-1447D01*
G01X374459Y338800D01*
X365400D01*
X363750Y340450D01*
Y341078D01*
X363769Y341119D01*
G03Y342299I-1272J590D01*
G01X363750Y342340D01*
Y342850D01*
X364001Y343101D01*
G02X364637Y343005I283J-283D01*
G03X366532Y344900I1240J655D01*
G02X366436Y345536I187J353D01*
G01X366750Y345850D01*
X367462D01*
G02X367860Y345485I0J-400D01*
G03X370654I1397J124D01*
G02X371052Y345850I398J-35D01*
G01X374222D01*
G02X374620Y345485I0J-400D01*
G03X377414I1397J124D01*
G02X377812Y345850I398J-35D01*
G01X380250D01*
X382526Y348126D01*
X382622Y348116D01*
G03X383861Y348620I155J1393D01*
G01X403887D01*
G02X404202Y347973I0J-400D01*
G03X406410I1104J-864D01*
G02X406725Y348620I315J247D01*
G01X408280D01*
X410104Y350444D01*
X410243Y350340D01*
G03X412206Y352303I843J1120D01*
G01X412101Y352442D01*
X412659Y353000D01*
X425295D01*
G02X425694Y352621I0J-400D01*
G03X428494I1400J75D01*
G02X428893Y353000I399J-21D01*
G01X432055D01*
G02X432454Y352621I0J-400D01*
G03X435254I1400J75D01*
G02X435653Y353000I399J-21D01*
G01X438814D01*
G02X439213Y352621I0J-400D01*
G03X442013I1400J75D01*
G02X442412Y353000I399J-21D01*
G01X445574D01*
G02X445973Y352621I0J-400D01*
G03X448773I1400J75D01*
G02X449172Y353000I399J-21D01*
G01X450800D01*
X450969Y352831D01*
G02X450701Y352148I-282J-283D01*
G03X452154Y350695I52J-1401D01*
G02X452837Y350963I400J-14D01*
G01X453303Y350497D01*
G02X453268Y349899I-282J-284D01*
G03X453754Y347446I865J-1103D01*
G01X453900Y347405D01*
Y341026D01*
X453895Y341004D01*
G03Y340390I1368J-307D01*
G01X453900Y340368D01*
Y337600D01*
X453347Y337047D01*
X453260Y337051D01*
G03X452213Y336682I-60J-1501D01*
G02X451687I-263J302D01*
G03X449670Y336643I-987J-1132D01*
G02X449060Y336717I-274J291D01*
G03X448830Y334807I-1260J-817D01*
G02X449440Y334733I274J-291D01*
G03X449894Y334283I1260J817D01*
G02X449962Y333662I-215J-338D01*
G01X428746Y312446D01*
X409846D01*
X408750Y311350D01*
Y297463D01*
G02X408099Y297151I-400J0D01*
G03X405894Y296965I-1005J-1247D01*
G02X405294I-300J265D01*
G03Y294843I-1200J-1061D01*
G02X405894I300J-265D01*
G03X408099Y294657I1200J1061D01*
G02X408750Y294345I251J-312D01*
G01Y280469D01*
G02X408099Y280157I-400J0D01*
G03X405894Y279971I-1005J-1247D01*
G02X405294I-300J265D01*
G03X402794Y279846I-1200J-1061D01*
G02X402144Y279847I-325J234D01*
G03X402142Y277978I-1302J-933D01*
G02X402792Y277977I325J-234D01*
G03X405294Y277849I1302J933D01*
G02X405894I300J-265D01*
G03X408099Y277663I1200J1061D01*
G02X408750Y277351I251J-312D01*
G01Y266753D01*
G02X408199Y266382I-400J0D01*
G03X406394Y265960I-605J-1483D01*
G02X405794I-300J265D01*
G03Y263838I-1200J-1061D01*
G02X406394I300J-265D01*
G03X408199Y263416I1200J1061D01*
G02X408750Y263045I151J-371D01*
G01Y253791D01*
X407300Y252341D01*
X384649D01*
X381257Y248950D01*
X381053D01*
G02X380686Y249508I0J400D01*
G03X378108I-1289J552D01*
G02X377741Y248950I-367J-158D01*
G01X377139D01*
G03X374895I-1122J-841D01*
G01X374293D01*
G02X373926Y249508I0J400D01*
G03X371348I-1289J552D01*
G02X370981Y248950I-367J-158D01*
G01X370501D01*
G03X368013I-1244J-841D01*
G01X367641D01*
G02X367270Y249499I0J400D01*
G03X364484I-1393J561D01*
G02X364113Y248950I-371J-149D01*
G01X363741D01*
G03X361253I-1244J-841D01*
G01X360881D01*
G02X360510Y249499I0J400D01*
G03X357724I-1393J561D01*
G02X357353Y248950I-371J-149D01*
G01X356859D01*
G03X354615I-1122J-841D01*
G01X354121D01*
G02X353750Y249499I0J400D01*
G03X350964I-1393J561D01*
G02X350593Y248950I-371J-149D01*
G01X350100D01*
G03X347856I-1122J-841D01*
G01X347362D01*
G02X346991Y249499I0J400D01*
G03X344205I-1393J561D01*
G02X343834Y248950I-371J-149D01*
G01X343340D01*
G03X341096I-1122J-841D01*
G01X340494D01*
G02X340127Y249508I0J400D01*
G03X337549I-1289J552D01*
G02X337182Y248950I-367J-158D01*
G01X336580D01*
G03X334336I-1122J-841D01*
G01X333734D01*
G02X333367Y249508I0J400D01*
G03X330789I-1289J552D01*
G02X330422Y248950I-367J-158D01*
G01X329820D01*
G03X327576I-1122J-841D01*
G01X326974D01*
G02X326607Y249508I0J400D01*
G03X324029I-1289J552D01*
G02X323662Y248950I-367J-158D01*
G01X323060D01*
G03X320816I-1122J-841D01*
G01X320322D01*
G02X319951Y249499I0J400D01*
G03X317165I-1393J561D01*
G02X316794Y248950I-371J-149D01*
G01X316422D01*
G03X313934I-1244J-841D01*
G01X309662D01*
G03X307174I-1244J-841D01*
G01X306695D01*
G02X306328Y249508I0J400D01*
G03X303750I-1289J552D01*
G02X303383Y248950I-367J-158D01*
G01X302781D01*
G03X300537I-1122J-841D01*
G01X299935D01*
G02X299568Y249508I0J400D01*
G03X296990I-1289J552D01*
G02X296623Y248950I-367J-158D01*
G01X296021D01*
G03X293777I-1122J-841D01*
G01X293175D01*
G02X292808Y249508I0J400D01*
G03X290230I-1289J552D01*
G02X289863Y248950I-367J-158D01*
G01X289261D01*
G03X287017I-1122J-841D01*
G01X286415D01*
G02X286048Y249508I0J400D01*
G03X283470I-1289J552D01*
G02X283103Y248950I-367J-158D01*
G01X282501D01*
G03X280257I-1122J-841D01*
G01X279655D01*
G02X279288Y249508I0J400D01*
G03X276710I-1289J552D01*
G02X276343Y248950I-367J-158D01*
G01X275741D01*
G03X273497I-1122J-841D01*
G01X272895D01*
G02X272528Y249508I0J400D01*
G03X269950I-1289J552D01*
G02X269583Y248950I-367J-158D01*
G01X268981D01*
G03X266737I-1122J-841D01*
G01X265835D01*
G02X265468Y249508I0J400D01*
G03X262890I-1289J552D01*
G02X262523Y248950I-367J-158D01*
G01X260950D01*
X260936Y248964D01*
X231736D01*
X193587Y210814D01*
X172447D01*
G37*
G36*
G01X273033Y331400D02*
G02X272635Y331835I1J400D01*
G03X269843I-1396J125D01*
G02X269445Y331400I-399J-35D01*
G01X268035D01*
X268023Y331401D01*
G03X267695I-164J-1392D01*
G01X267683Y331400D01*
X265973D01*
G02X265575Y331835I1J400D01*
G03X262783I-1396J125D01*
G02X262385Y331400I-399J-35D01*
G01X248400D01*
X214600Y365200D01*
X174500D01*
X174490Y365210D01*
X172820D01*
X169960Y368070D01*
Y389780D01*
X172500Y392320D01*
Y404800D01*
X174700Y407000D01*
X223200D01*
X267136Y363064D01*
X276590D01*
X276621Y362901D01*
G03X278164Y361768I1378J259D01*
G01X278261Y361779D01*
X280843Y359197D01*
G02X280742Y358558I-283J-283D01*
G03X282628Y356672I637J-1249D01*
G02X283267Y356773I356J-182D01*
G01X283729Y356311D01*
G03X285710Y354330I1030J-951D01*
G01X286739Y353301D01*
X286748Y353233D01*
G03X287963Y352018I1391J176D01*
G01X288031Y352009D01*
X288446Y351594D01*
G02X288158Y350911I-282J-283D01*
G03X289541Y349528I-19J-1402D01*
G02X290224Y349816I400J6D01*
G01X290741Y349299D01*
G02X290693Y348693I-283J-282D01*
G03X292902Y347327I826J-1133D01*
G01X292930Y347494D01*
X296868D01*
X296896Y347327D01*
G03X299662I1383J233D01*
G01X299690Y347494D01*
X303628D01*
X303656Y347327D01*
G03X306422I1383J233D01*
G01X306450Y347494D01*
X310287D01*
X310314Y347325D01*
G03X313282I1484J235D01*
G01X313309Y347494D01*
X315894D01*
X315900Y347487D01*
X316713D01*
X320870Y343330D01*
G02X320871Y342766I-283J-283D01*
G03X322995Y340642I1067J-1057D01*
G02X323559Y340641I281J-284D01*
G01X323987Y340213D01*
X323959Y340103D01*
G03X325572Y338382I1359J-343D01*
G01X325590Y338385D01*
X326905D01*
G02X327303Y337946I0J-400D01*
G03X330093I1395J-137D01*
G02X330491Y338385I398J39D01*
G01X331806D01*
X331824Y338382D01*
G03X332332I254J1378D01*
G01X332350Y338385D01*
X333665D01*
G02X334063Y337946I0J-400D01*
G03X336853I1395J-137D01*
G02X337251Y338385I398J39D01*
G01X338566D01*
X338584Y338382D01*
G03X339092I254J1378D01*
G01X339110Y338385D01*
X339485D01*
X339500Y338370D01*
X340424D01*
G02X340822Y337934I0J-400D01*
G03X343614I1396J-125D01*
G02X344012Y338370I398J36D01*
G01X345419D01*
X345431Y338369D01*
G03X345765I167J1391D01*
G01X345777Y338370D01*
X347184D01*
G02X347582Y337934I0J-400D01*
G03X350374I1396J-125D01*
G02X350772Y338370I398J36D01*
G01X351787D01*
X351821Y338357D01*
G03X352893I536J1403D01*
G01X352927Y338370D01*
X353943D01*
G02X354341Y337934I0J-400D01*
G03X357133I1396J-125D01*
G02X357531Y338370I398J36D01*
G01X358938D01*
X358950Y338369D01*
G03X359284I167J1391D01*
G01X359296Y338370D01*
X360602D01*
G02X361000Y337936I0J-400D01*
G03X363965Y338128I1497J-126D01*
G01X363961Y338149D01*
Y338370D01*
X364414D01*
X364985Y337798D01*
X372986D01*
G02X373385Y337390I-1J-400D01*
G03X375424Y335958I1502J-30D01*
G01X375546Y336004D01*
X381098Y330452D01*
Y326498D01*
X373783Y319183D01*
X358834D01*
G02X358461Y319725I1J400D01*
G03X355653I-1404J535D01*
G02X355280Y319183I-374J-142D01*
G01X350200D01*
G03X347756I-1222J-874D01*
G01X347268D01*
G02X346897Y319733I0J400D01*
G03X344299I-1299J527D01*
G02X343928Y319183I-371J-150D01*
G01X343314D01*
G03X341122I-1096J-874D01*
G01X338567D01*
X336666Y317282D01*
Y313500D01*
X335692Y312526D01*
X333489D01*
X333461Y312693D01*
G03X330695I-1383J-233D01*
G01X330667Y312526D01*
X326729D01*
X326701Y312693D01*
G03X323935I-1383J-233D01*
G01X323907Y312526D01*
X320674D01*
X315300Y317900D01*
X315140D01*
X314939Y318102D01*
X309820D01*
Y318303D01*
G03X307016I-1402J6D01*
G01Y318102D01*
X303061D01*
Y318303D01*
G03X300257I-1402J6D01*
G01Y318102D01*
X296301D01*
Y318303D01*
G03X293497I-1402J6D01*
G01Y318102D01*
X289541D01*
Y318303D01*
G03X286842Y318842I-1402J6D01*
G02X286189Y318711I-370J152D01*
G01X285900Y319000D01*
G02X285891Y319273I142J141D01*
G03X283772Y321392I-1132J987D01*
G02X283499Y321401I-132J151D01*
G01X282873Y322027D01*
X282878Y322117D01*
Y322118D01*
G03X281287Y323708I-1499J91D01*
G01X281197Y323703D01*
X278659Y326241D01*
G02X278732Y326865I282J283D01*
G03X276804Y328793I-733J1195D01*
G02X276180Y328720I-341J209D01*
G01X275743Y329157D01*
X275823Y329291D01*
G03X273773Y331127I-1204J718D01*
G01X273500Y331400D01*
X273033D01*
G37*
G36*
G01X316976Y349000D02*
G02X316577Y349424I0J400D01*
G03X313779I-1399J85D01*
G02X313380Y349000I-399J-24D01*
G01X310216D01*
G02X309817Y349424I0J400D01*
G03X307019I-1399J85D01*
G02X306620Y349000I-399J-24D01*
G01X294450D01*
X292723Y350727D01*
X292784Y350855D01*
G03X290914Y352725I-1265J605D01*
G01X290786Y352664D01*
X289371Y354079D01*
X289357Y354103D01*
G03X288810Y354640I-1218J-694D01*
G01X288194Y355256D01*
G02X288402Y355932I283J283D01*
G03X286762Y357572I-263J1377D01*
G02X286086Y357364I-393J75D01*
G01X285749Y357701D01*
G02Y358267I283J283D01*
G03X283766Y360250I-990J993D01*
G02X283200I-283J283D01*
G01X282706Y360744D01*
X282735Y360854D01*
G03X281024Y362565I-1356J355D01*
G01X280914Y362536D01*
X279250Y364200D01*
X278942D01*
X278887Y364245D01*
G03X277059Y364200I-888J-1085D01*
G01X268300D01*
X253100Y379400D01*
Y401400D01*
X257200Y405500D01*
X431400D01*
X432400Y406500D01*
X446522D01*
X446559Y406485D01*
G03X447623I532J1297D01*
G01X447660Y406500D01*
X450676D01*
X452038Y405138D01*
X452600Y404575D01*
Y356500D01*
X451749Y355649D01*
X451610Y355757D01*
G03X449352Y354693I-857J-1110D01*
G01X449345Y354500D01*
X445401D01*
X445394Y354693D01*
G03X442592I-1401J-46D01*
G01X442585Y354500D01*
X412828D01*
G02X412442Y355002I1J400D01*
G03X410683Y354017I-1356J358D01*
G02X410851Y353351I-115J-383D01*
G01X407500Y350000D01*
X384096D01*
X384042Y350114D01*
G03X381512I-1265J-605D01*
G01X381458Y350000D01*
X380900D01*
X379806Y348906D01*
X379699Y348929D01*
G03X378112Y348120I-302J-1369D01*
G01X378059Y348000D01*
X377437D01*
G02X377122Y348646I0J400D01*
G03X374912I-1105J863D01*
G02X374597Y348000I-315J-246D01*
G01X373975D01*
X373922Y348120D01*
G03X371352I-1285J-560D01*
G01X371299Y348000D01*
X370677D01*
G02X370362Y348646I0J400D01*
G03X368152I-1105J863D01*
G02X367837Y348000I-315J-246D01*
G01X367215D01*
X367162Y348120D01*
G03X364487Y347745I-1285J-560D01*
G01X364478Y347678D01*
X363443Y346643D01*
G03X361463Y344663I-946J-1034D01*
G01X361002Y344202D01*
G02X360364Y344302I-282J283D01*
G03X358475Y342413I-1247J-642D01*
G02X358575Y341775I-183J-356D01*
G01X356900Y340100D01*
X356299D01*
Y340419D01*
X356404Y340476D01*
G03X354697Y340768I-668J1233D01*
G02X354401Y340100I-296J-268D01*
G01X353724D01*
X353677Y340233D01*
G03X351037I-1320J-473D01*
G01X350990Y340100D01*
X350314D01*
G02X350018Y340768I0J400D01*
G03X347938I-1040J941D01*
G02X347642Y340100I-296J-268D01*
G01X346965D01*
X346918Y340233D01*
G03X344278I-1320J-473D01*
G01X344231Y340100D01*
X343554D01*
G02X343258Y340768I0J400D01*
G03X341178I-1040J941D01*
G02X340882Y340100I-296J-268D01*
G01X340205D01*
X340158Y340233D01*
G03X337518I-1320J-473D01*
G01X337471Y340100D01*
X336794D01*
G02X336498Y340768I0J400D01*
G03X334418I-1040J941D01*
G02X334122Y340100I-296J-268D01*
G01X333445D01*
X333398Y340233D01*
G03X330758I-1320J-473D01*
G01X330711Y340100D01*
X330034D01*
G02X329738Y340768I0J400D01*
G03X328031Y340476I-1039J941D01*
G01X328136Y340419D01*
Y340100D01*
X327400D01*
X322914Y344586D01*
X323027Y344726D01*
G03X321055Y346698I-1089J883D01*
G02X320788Y346712I-126J156D01*
G01X318500Y349000D01*
X316976D01*
G37*
G36*
G01X410300Y276997D02*
G02X410817Y277379I400J-1D01*
G03X412456Y277813I472J1531D01*
G02X413039I291J-273D01*
G03Y280007I1168J1097D01*
G02X412456I-291J273D01*
G03X410817Y280441I-1167J-1097D01*
G02X410300Y280823I-117J383D01*
G01Y293992D01*
G02X410819Y294374I400J0D01*
G03X412494Y294843I475J1530D01*
G02X413094I300J-265D01*
G03Y296965I1200J1061D01*
G02X412494I-300J265D01*
G03X410819Y297434I-1200J-1061D01*
G02X410300Y297816I-119J382D01*
G01Y310600D01*
X411000Y311300D01*
X443800D01*
X444098Y311002D01*
Y307585D01*
X444450Y307234D01*
Y307000D01*
X445650Y305800D01*
X445884D01*
X446085Y305598D01*
X468535D01*
X468580Y305460D01*
G03X471246I1333J436D01*
G01X471291Y305598D01*
X474915D01*
X476206Y306889D01*
G02X476778Y306883I283J-282D01*
G03X478760Y308865I1014J968D01*
G02X478754Y309437I276J289D01*
G01X479110Y309794D01*
G02X479788Y309574I283J-283D01*
G03X480571Y311064I1384J223D01*
G02X480000Y311425I-171J361D01*
G01Y312068D01*
G02X480571Y312429I400J0D01*
G03Y314963I601J1267D01*
G02X480000Y315324I-171J361D01*
G01Y315858D01*
G02X480562Y316223I400J0D01*
G03Y318969I610J1373D01*
G02X480000Y319334I-162J365D01*
G01Y319758D01*
G02X480562Y320123I400J0D01*
G03Y322869I610J1373D01*
G02X480000Y323234I-162J365D01*
G01Y323658D01*
G02X480562Y324023I400J0D01*
G03Y326769I610J1373D01*
G02X480000Y327134I-162J365D01*
G01Y327500D01*
X476102Y331398D01*
Y341690D01*
G02X476788Y341969I400J0D01*
G03Y343925I1004J978D01*
G02X476102Y344204I-286J279D01*
G01Y345450D01*
G02X476773Y345744I400J0D01*
G03Y347950I1019J1103D01*
G02X476102Y348244I-271J294D01*
G01Y349350D01*
G02X476773Y349644I400J0D01*
G03Y351850I1019J1103D01*
G02X476102Y352144I-271J294D01*
G01Y353390D01*
G02X476788Y353669I400J0D01*
G03X478090Y356017I1004J978D01*
G02X477892Y356691I85J391D01*
G01X478608Y357407D01*
G03X478657Y357444I-820J1137D01*
G03X478858Y357636I-863J1105D01*
G01X480492Y359270D01*
G03X482314Y359682I680J1226D01*
G01X486790D01*
G03X488253Y359131I1142J814D01*
G01X490787Y356596D01*
G02X490679Y355954I-283J-283D01*
G03X491930Y353333I633J-1307D01*
G02X492500Y352971I170J-362D01*
G01Y352367D01*
G02X491925Y352008I-400J1D01*
G03Y349486I-613J-1261D01*
G02X492500Y349127I175J-360D01*
G01Y348467D01*
G02X491925Y348108I-400J1D01*
G03Y345586I-613J-1261D01*
G02X492500Y345227I175J-360D01*
G01Y344623D01*
G02X491930Y344261I-400J0D01*
G03Y341633I-618J-1314D01*
G02X492500Y341271I170J-362D01*
G01Y340900D01*
X494336Y339064D01*
G02X494195Y338407I-283J-283D01*
G03X496003Y336599I497J-1311D01*
G02X496660Y336740I374J-142D01*
G01X496850Y336550D01*
X498650D01*
X500454Y334746D01*
G02X500455Y334182I-283J-283D01*
G03X502606Y332400I997J-986D01*
G01X503184D01*
X503385Y332198D01*
X503617D01*
Y331948D01*
X503594Y331904D01*
G03X506167Y331676I1238J-657D01*
G02X506547Y332198I381J122D01*
G01X507227D01*
G03X509197I985J998D01*
G01X509877D01*
G02X510257Y331676I-1J-400D01*
G03X512927I1335J-429D01*
G02X513307Y332198I381J122D01*
G01X513987D01*
G03X515957I985J998D01*
G01X516532D01*
G02X516915Y331683I0J-400D01*
G03X519789I1437J-436D01*
G02X520172Y332198I383J115D01*
G01X520676D01*
G03X522572Y332012I1055J998D01*
G01X522710Y332110D01*
X523660Y331160D01*
X523668Y331090D01*
G03X524954Y329804I1443J157D01*
G01X525024Y329796D01*
X525339Y329481D01*
G02X525068Y328798I-283J-283D01*
G03X526562Y327304I43J-1451D01*
G02X527245Y327575I400J-12D01*
G01X527661Y327159D01*
G02X527618Y326557I-283J-282D01*
G03X529652Y324523I873J-1161D01*
G02X530254Y324566I320J-240D01*
G01X530621Y324199D01*
X530560Y324071D01*
G03X532496Y322135I1311J-625D01*
G01X532624Y322196D01*
X534053Y320767D01*
X534065Y320748D01*
G03X534503Y320310I1186J748D01*
G01X534522Y320298D01*
X535091Y319729D01*
G02X534902Y319057I-282J-283D01*
G03X536712Y317247I349J-1461D01*
G02X537384Y317436I389J-93D01*
G01X537557Y317263D01*
G02X537560Y316700I-283J-283D01*
G03X539684Y314576I1071J-1053D01*
G02X540247Y314573I280J-286D01*
G01X540599Y314221D01*
X540567Y314108D01*
G03X542423Y312252I1444J-412D01*
G01X542536Y312284D01*
X545014Y309806D01*
G02X544877Y309151I-283J-283D01*
G03X546695Y307333I514J-1304D01*
G02X547350Y307470I372J-146D01*
G01X547780Y307040D01*
X547653Y306899D01*
G03X549774Y304778I1118J-1003D01*
G02X550049Y304771I134J-149D01*
G01X550661Y304159D01*
X550654Y304067D01*
G03X552271Y302450I1497J-120D01*
G01X552363Y302457D01*
X552595Y302225D01*
G02X552278Y301544I-283J-283D01*
G03X553648Y300174I-127J-1497D01*
G02X554329Y300491I398J34D01*
G01X555014Y299806D01*
G02X554975Y299206I-283J-283D01*
G03X556941Y297240I856J-1110D01*
G02X557541Y297279I317J-244D01*
G01X624687Y230133D01*
Y223214D01*
X630001Y217900D01*
X651900D01*
X659550Y225550D01*
Y242250D01*
X662100Y244800D01*
X700269D01*
G02X700653Y244289I0J-400D01*
G03X703347I1347J-389D01*
G02X703731Y244800I384J111D01*
G01X709159D01*
X709178Y244622D01*
G03X709671Y243699I1394J151D01*
G02X709683Y243097I-258J-306D01*
G03X711528Y243135I944J-1036D01*
G02X711516Y243737I258J306D01*
G03X711966Y244622I-944J1037D01*
G01X711985Y244800D01*
X732450D01*
X734900Y242350D01*
Y225606D01*
X734896Y225567D01*
Y225566D01*
G03Y224362I2941J-602D01*
G01X734900Y224342D01*
Y223006D01*
X734896Y222967D01*
Y222966D01*
G03Y221762I2941J-602D01*
G01X734900Y221742D01*
Y218850D01*
X735850Y217900D01*
X741708D01*
G03X744166I1229J674D01*
G01X748512D01*
X748554Y217896D01*
G03X749700I573J2947D01*
G01X749719Y217900D01*
X760800D01*
X764169Y214531D01*
X764055Y214391D01*
G03X766027Y212419I1089J-883D01*
G01X766167Y212533D01*
X768904Y209796D01*
Y209136D01*
X768891Y209101D01*
G03Y208099I1309J-501D01*
G01X768904Y208064D01*
Y205060D01*
X768903Y205051D01*
G03Y204809I1397J-121D01*
G01X768904Y204800D01*
Y192853D01*
X768744Y192820D01*
G03Y189876I300J-1472D01*
G01X768904Y189843D01*
Y179900D01*
X767096Y178092D01*
X647415D01*
X643748Y181759D01*
X633815D01*
X630148Y178092D01*
X588108D01*
X572500Y193700D01*
X413200D01*
X410300Y196600D01*
Y262957D01*
G02X410797Y263345I400J0D01*
G03X412388Y263838I390J1554D01*
G02X412988I300J-265D01*
G03X415389Y263839I1200J1061D01*
G02X415989I300J-265D01*
G03X418390Y263837I1201J1060D01*
G02X418988I299J-265D01*
G03X421274Y263721I1200J1062D01*
G02X421854Y263681I271J-294D01*
G03X424225Y263565I1238J1016D01*
G02X424788Y263567I283J-283D01*
G03X424778Y265842I1123J1142D01*
G02X424215Y265840I-283J283D01*
G03X422006Y265875I-1123J-1143D01*
G02X421426Y265915I-271J294D01*
G03X418988Y265961I-1239J-1016D01*
G02X418390I-299J265D01*
G03X415989Y265959I-1200J-1062D01*
G02X415389I-300J265D01*
G03X412988Y265960I-1201J-1060D01*
G02X412388I-300J265D01*
G03X410797Y266453I-1201J-1061D01*
G02X410300Y266841I-97J388D01*
G01Y276997D01*
G37*
G36*
G01X493600Y343233D02*
G02X494154Y343602I400J0D01*
G03Y346190I538J1294D01*
G02X493600Y346559I-154J369D01*
G01Y347133D01*
G02X494154Y347502I400J0D01*
G03Y350090I538J1294D01*
G02X493600Y350459I-154J369D01*
G01Y353504D01*
X493648Y353552D01*
Y354914D01*
G02X494191Y355287I400J-1D01*
G03X493293Y356499I501J1310D01*
G02X492612Y356188I-399J-28D01*
G01X492033Y356767D01*
G02X492093Y357382I283J283D01*
G03X490147Y359328I-781J1165D01*
G02X489532Y359268I-332J223D01*
G01X489097Y359703D01*
X489168Y359833D01*
G03X486572Y360836I-1236J662D01*
G01X486534Y360684D01*
X485730D01*
G02X485469Y361387I0J400D01*
G03X483635I-917J1060D01*
G02X483374Y360684I-261J-303D01*
G01X482570D01*
X482532Y360836D01*
G03X479770Y360459I-1360J-340D01*
G01X479773Y360373D01*
X478867Y359467D01*
X478726Y359593D01*
G03X476746Y357613I-934J-1046D01*
G02X476739Y357339I-149J-133D01*
G01X476373Y356973D01*
G02X475718Y357109I-283J283D01*
G03X474636Y355212I-1305J-513D01*
G02X475100Y354817I64J-395D01*
G01Y354475D01*
G02X474636Y354080I-400J0D01*
G03Y351312I-223J-1384D01*
G02X475100Y350917I64J-395D01*
G01Y350575D01*
G02X474636Y350180I-400J0D01*
G03Y347412I-223J-1384D01*
G02X475100Y347017I64J-395D01*
G01Y346776D01*
G02X474640Y346381I-400J0D01*
G03Y343411I-227J-1485D01*
G02X475100Y343016I60J-395D01*
G01Y342775D01*
G02X474636Y342380I-400J0D01*
G03Y339612I-223J-1384D01*
G02X475100Y339217I64J-395D01*
G01Y338875D01*
G02X474636Y338480I-400J0D01*
G03Y335712I-223J-1384D01*
G02X475100Y335317I64J-395D01*
G01Y330700D01*
X476849Y328951D01*
G02X476838Y328375I-283J-283D01*
G03X478226Y326014I954J-1028D01*
G02X478750Y325634I124J-380D01*
G01Y321260D01*
G02X478226Y320880I-400J0D01*
G03Y318214I-434J-1333D01*
G02X478750Y317834I124J-380D01*
G01Y317360D01*
G02X478226Y316980I-400J0D01*
G03Y314314I-434J-1333D01*
G02X478750Y313934I124J-380D01*
G01Y313565D01*
G02X478233Y313183I-400J0D01*
G03X477369Y310306I-441J-1436D01*
G02X477539Y309639I-113J-384D01*
G01X474500Y306600D01*
X471125D01*
G03X468701I-1212J-704D01*
G01X446500D01*
X445100Y308000D01*
Y314800D01*
X455636Y325336D01*
Y331306D01*
G02X456218Y331662I400J0D01*
G03Y334338I682J1338D01*
G02X455636Y334694I-182J356D01*
G01Y339339D01*
X455764Y339388D01*
G03Y342006I-501J1309D01*
G01X455636Y342055D01*
Y342764D01*
X455671Y342800D01*
Y349507D01*
G02X456374Y349768I400J0D01*
G03Y351726I1139J979D01*
G02X455671Y351987I-303J261D01*
G01Y403271D01*
X459679Y407279D01*
X466240D01*
X466264Y407106D01*
G03X469042I1389J190D01*
G01X469066Y407279D01*
X537081D01*
G02X537451Y406728I0J-400D01*
G03X540152Y406186I1299J-528D01*
G02X540835Y406465I400J-4D01*
G01X551641Y395659D01*
G02X551525Y395012I-283J-283D01*
G03X553516Y393021I626J-1365D01*
G02X554163Y393137I364J-167D01*
G01X557718Y389582D01*
X557728Y389518D01*
G03X558983Y388263I1484J229D01*
G01X559047Y388253D01*
X635900Y311400D01*
Y293900D01*
X638607Y291193D01*
X638502Y291054D01*
G03X640466Y289090I1120J-844D01*
G01X640605Y289195D01*
X647353Y282447D01*
G02X647158Y281774I-283J-283D01*
G03X646410Y279261I329J-1466D01*
G02X646406Y278700I-287J-278D01*
G03X648546Y278686I1063J-1061D01*
G02X648550Y279247I287J278D01*
G03X648953Y279979I-1062J1062D01*
G02X649626Y280174I390J-88D01*
G01X654635Y275165D01*
X654649Y275113D01*
G03X655713Y274049I1451J387D01*
G01X655765Y274035D01*
X657100Y272700D01*
Y251554D01*
X656994Y251498D01*
G03Y248846I706J-1326D01*
G01X657100Y248790D01*
Y227700D01*
X648860Y219460D01*
X630942D01*
X625744Y224658D01*
Y231049D01*
X614646Y242146D01*
Y242147D01*
X614015Y242778D01*
G02X614331Y243459I283J282D01*
G03X612959Y244831I125J1497D01*
G02X612278Y244515I-399J-33D01*
G01X556638Y300155D01*
G02X556692Y300765I283J282D01*
G03X554600Y302857I-861J1231D01*
G02X553990Y302803I-328J229D01*
G01X553506Y303287D01*
X553553Y303408D01*
G03X551612Y305349I-1402J539D01*
G01X551491Y305302D01*
X549005Y307788D01*
G02X549173Y308454I283J283D01*
G03X547428Y310199I-402J1343D01*
G02X546762Y310031I-383J115D01*
G01X546559Y310234D01*
G02X546537Y310776I283J283D01*
G03X544420Y312893I-1146J971D01*
G02X543878Y312915I-259J305D01*
G01X543470Y313323D01*
X543489Y313426D01*
G03X541741Y315174I-1478J270D01*
G01X541638Y315155D01*
X539145Y317648D01*
G02X539251Y318290I283J283D01*
G03X537374Y320167I-620J1257D01*
G02X536732Y320061I-359J177D01*
G01X536273Y320520D01*
X536376Y320659D01*
G03X534414Y322621I-1125J837D01*
G01X534275Y322518D01*
X533325Y323468D01*
X533320Y323543D01*
G03X531968Y324895I-1449J-97D01*
G01X531893Y324900D01*
X531530Y325263D01*
G02X531826Y325946I283J283D01*
G03X530470Y327302I45J1401D01*
G02X529787Y327006I-400J-13D01*
G01X529286Y327507D01*
G02X529336Y328115I283J283D01*
G03X527310Y330141I-845J1181D01*
G02X526702Y330091I-325J233D01*
G01X526337Y330456D01*
X526404Y330585D01*
G03X524449Y332540I-1293J662D01*
G01X524320Y332473D01*
X523593Y333200D01*
X523194D01*
X523172Y333375D01*
G03X520290I-1441J-179D01*
G01X520268Y333200D01*
X516385D01*
X516363Y333375D01*
G03X513581I-1391J-179D01*
G01X513559Y333200D01*
X509625D01*
X509603Y333375D01*
G03X506821I-1391J-179D01*
G01X506799Y333200D01*
X503800D01*
X501892Y335108D01*
G02X502019Y335759I283J283D01*
G03X500115Y337663I-567J1337D01*
G02X499464Y337536I-368J156D01*
G01X499000Y338000D01*
X497600D01*
X495777Y339823D01*
G02X495765Y340094I141J142D01*
G03X494154Y342290I-1073J901D01*
G02X493600Y342659I-154J369D01*
G01Y343233D01*
G37*
G36*
G01X740900Y251973D02*
Y249300D01*
X740271Y248671D01*
G03X738360Y246684I-771J-1171D01*
G01X737626Y245950D01*
X732837D01*
G02X732576Y246653I0J400D01*
G03X730748I-914J1063D01*
G02X730487Y245950I-261J-303D01*
G01X711334D01*
G03X709810I-762J-1177D01*
G01X662800D01*
X662000Y246750D01*
Y269900D01*
X657236Y274664D01*
X657313Y274797D01*
G03X655397Y276713I-1213J703D01*
G01X655264Y276636D01*
X644207Y287693D01*
G02X644342Y288347I283J283D01*
G03X642520Y290169I-519J1303D01*
G02X641866Y290034I-371J148D01*
G01X638000Y293900D01*
Y300650D01*
X638125Y300700D01*
G03Y303300I-525J1300D01*
G01X638000Y303350D01*
Y305650D01*
X638125Y305700D01*
G03Y308300I-525J1300D01*
G01X638000Y308350D01*
Y309790D01*
X637798Y309992D01*
G02X637966Y310658I283J283D01*
G03X636467Y312877I-405J1342D01*
G02X635872Y312844I-312J250D01*
G01X578390Y370326D01*
Y371370D01*
X578818Y371798D01*
X635215D01*
X635488Y372072D01*
X635626Y372210D01*
X636710D01*
X641800Y377300D01*
X714000D01*
X717220Y380520D01*
Y403860D01*
X719854Y406494D01*
X726785D01*
X726833Y406446D01*
X734363D01*
X734411Y406494D01*
X761011D01*
X761286Y406770D01*
X761380D01*
X763490Y408880D01*
X786741D01*
X786761Y408900D01*
X796151D01*
G03X798249I1049J930D01*
G01X803940D01*
G02X804257Y408256I0J-400D01*
G03X806477I1110J-856D01*
G02X806794Y408900I317J244D01*
G01X813250D01*
X813275Y408875D01*
X816445D01*
X817880Y407440D01*
Y369412D01*
X816770Y368302D01*
X786003D01*
X785612Y368693D01*
Y370905D01*
X785764Y370943D01*
G03Y373857I-364J1457D01*
G01X785612Y373895D01*
Y396198D01*
X782370Y399440D01*
X781531D01*
X781292Y399680D01*
X779137D01*
X779115Y399702D01*
X766485D01*
X766224Y399440D01*
X765850D01*
X762560Y396150D01*
X747830D01*
X740900Y389220D01*
Y377685D01*
G03Y375241I874J-1222D01*
G01Y316799D01*
G03Y314277I612J-1261D01*
G01Y300221D01*
X740769Y300173D01*
G03Y297539I481J-1317D01*
G01X740900Y297491D01*
Y254827D01*
G02X740256Y254510I-400J0D01*
G03Y252290I-856J-1110D01*
G02X740900Y251973I244J-317D01*
G37*
G36*
G01X626703Y425251D02*
X752649D01*
X753300Y424600D01*
X754600D01*
X761450Y417750D01*
Y408350D01*
X760596Y407496D01*
X733996D01*
X733948Y407448D01*
X727248D01*
X727200Y407496D01*
X623048D01*
X613325Y417219D01*
Y423419D01*
X615157Y425251D01*
X623697D01*
X623730Y425092D01*
G03X626670I1470J308D01*
G01X626703Y425251D01*
G37*
G36*
G01X759400Y89900D02*
Y95300D01*
X760300Y96200D01*
X762099D01*
G02X762499Y95790I0J-400D01*
G03X765501I1501J-40D01*
G02X765901Y96200I400J10D01*
G01X767780D01*
X769516Y94464D01*
G02X769377Y93808I-283J-283D01*
G03X770913Y93449I504J-1308D01*
G02X771207Y94120I294J271D01*
G01X771588D01*
G02X771933Y93518I0J-400D01*
G03X774523I1295J-761D01*
G02X774868Y94120I345J202D01*
G01X778281D01*
G02X778626Y93518I0J-400D01*
G03X781216I1295J-761D01*
G02X781561Y94120I345J202D01*
G01X785038D01*
G02X785332Y93449I0J-400D01*
G03X785347Y91535I1032J-949D01*
G02X785337Y90973I-290J-276D01*
G03X785292Y88873I1051J-1073D01*
G02Y88327I-292J-273D01*
G03X785348Y86216I1096J-1027D01*
G02X785363Y85655I-277J-288D01*
G03X787413I1025J-957D01*
G02X787428Y86216I292J273D01*
G03X787484Y88327I-1040J1084D01*
G02Y88873I292J273D01*
G03X787419Y90992I-1096J1027D01*
G02X787398Y91553I274J291D01*
G03X787396Y93449I-1034J947D01*
G02X787690Y94120I294J271D01*
G01X789993D01*
G02X790325Y93497I0J-400D01*
G03X790463Y91758I1163J-783D01*
G02X790447Y91197I-293J-272D01*
G03X790392Y89087I1041J-1083D01*
G02Y88541I-292J-273D01*
G03X790528Y86359I1096J-1027D01*
G02X790537Y85751I-256J-308D01*
G03X792409Y85736I928J-1051D01*
G02X792428Y86343I270J295D01*
G03X792584Y88541I-940J1171D01*
G02Y89087I292J273D01*
G03X792529Y91197I-1096J1027D01*
G02X792513Y91758I277J289D01*
G03X792651Y93497I-1025J956D01*
G02X792983Y94120I332J223D01*
G01X795013D01*
G02X795358Y93518I0J-400D01*
G03X797948I1295J-761D01*
G02X798293Y94120I345J202D01*
G01X801706D01*
G02X802051Y93518I0J-400D01*
G03X804641I1295J-761D01*
G02X804986Y94120I345J202D01*
G01X808399D01*
G02X808744Y93518I0J-400D01*
G03X811334I1295J-761D01*
G02X811679Y94120I345J202D01*
G01X815092D01*
G02X815437Y93518I0J-400D01*
G03X818027I1295J-761D01*
G02X818372Y94120I345J202D01*
G01X821849D01*
G02X822143Y93449I0J-400D01*
G03X822158Y91535I1032J-949D01*
G02X822148Y90973I-290J-276D01*
G03X822103Y88873I1051J-1073D01*
G02Y88327I-292J-273D01*
G03X822159Y86216I1096J-1027D01*
G02X822174Y85655I-277J-288D01*
G03X824224I1025J-957D01*
G02X824239Y86216I292J273D01*
G03X824295Y88327I-1040J1084D01*
G02Y88873I292J273D01*
G03X824230Y90992I-1096J1027D01*
G02X824209Y91553I274J291D01*
G03X824207Y93449I-1034J947D01*
G02X824501Y94120I294J271D01*
G01X826804D01*
G02X827136Y93497I0J-400D01*
G03X827274Y91758I1163J-783D01*
G02X827258Y91197I-293J-272D01*
G03X827203Y89087I1041J-1083D01*
G02Y88541I-292J-273D01*
G03X827339Y86359I1096J-1027D01*
G02X827348Y85751I-256J-308D01*
G03X829220Y85736I928J-1051D01*
G02X829239Y86343I270J295D01*
G03X829395Y88541I-940J1171D01*
G02Y89087I292J273D01*
G03X829340Y91197I-1096J1027D01*
G02X829324Y91758I277J289D01*
G03X829462Y93497I-1025J956D01*
G02X829794Y94120I332J223D01*
G01X831824D01*
G02X832169Y93518I0J-400D01*
G03X834759I1295J-761D01*
G02X835104Y94120I345J202D01*
G01X838517D01*
G02X838862Y93518I0J-400D01*
G03X841452I1295J-761D01*
G02X841797Y94120I345J202D01*
G01X845210D01*
G02X845555Y93518I0J-400D01*
G03X848145I1295J-761D01*
G02X848490Y94120I345J202D01*
G01X851903D01*
G02X852248Y93518I0J-400D01*
G03X854838I1295J-761D01*
G02X855183Y94120I345J202D01*
G01X858660D01*
G02X858954Y93449I0J-400D01*
G03X858969Y91535I1032J-949D01*
G02X858959Y90973I-290J-276D01*
G03X858914Y88873I1051J-1073D01*
G02Y88327I-292J-273D01*
G03X858970Y86216I1096J-1027D01*
G02X858985Y85655I-277J-288D01*
G03X861035I1025J-957D01*
G02X861050Y86216I292J273D01*
G03X861106Y88327I-1040J1084D01*
G02Y88873I292J273D01*
G03X861041Y90992I-1096J1027D01*
G02X861020Y91553I274J291D01*
G03X861018Y93449I-1034J947D01*
G02X861312Y94120I294J271D01*
G01X863615D01*
G02X863947Y93497I0J-400D01*
G03X864085Y91758I1163J-783D01*
G02X864069Y91197I-293J-272D01*
G03X864014Y89087I1041J-1083D01*
G02Y88541I-292J-273D01*
G03X864150Y86359I1096J-1027D01*
G02X864159Y85751I-256J-308D01*
G03X866031Y85736I928J-1051D01*
G02X866050Y86343I270J295D01*
G03X866206Y88541I-940J1171D01*
G02Y89087I292J273D01*
G03X866151Y91197I-1096J1027D01*
G02X866135Y91758I277J289D01*
G03X866273Y93497I-1025J956D01*
G02X866605Y94120I332J223D01*
G01X868633D01*
G02X868978Y93518I0J-400D01*
G03X871572I1297J-757D01*
G02X871917Y94120I345J202D01*
G01X875328D01*
G02X875673Y93518I0J-400D01*
G03X878263I1295J-761D01*
G02X878608Y94120I345J202D01*
G01X882021D01*
G02X882366Y93518I0J-400D01*
G03X884956I1295J-761D01*
G02X885301Y94120I345J202D01*
G01X888714D01*
G02X889059Y93518I0J-400D01*
G03X891649I1295J-761D01*
G02X891994Y94120I345J202D01*
G01X895471D01*
G02X895765Y93449I0J-400D01*
G03X895780Y91535I1032J-949D01*
G02X895770Y90973I-290J-276D01*
G03X895725Y88873I1051J-1073D01*
G02Y88327I-292J-273D01*
G03X895781Y86216I1096J-1027D01*
G02X895796Y85655I-277J-288D01*
G03X897846I1025J-957D01*
G02X897861Y86216I292J273D01*
G03X897917Y88327I-1040J1084D01*
G02Y88873I292J273D01*
G03X897852Y90992I-1096J1027D01*
G02X897831Y91553I274J291D01*
G03X897829Y93449I-1034J947D01*
G02X898123Y94120I294J271D01*
G01X900426D01*
G02X900758Y93497I0J-400D01*
G03X900896Y91758I1163J-783D01*
G02X900880Y91197I-293J-272D01*
G03X900825Y89087I1041J-1083D01*
G02Y88541I-292J-273D01*
G03X900961Y86359I1096J-1027D01*
G02X900970Y85751I-256J-308D01*
G03X902842Y85736I928J-1051D01*
G02X902861Y86343I270J295D01*
G03X903017Y88541I-940J1171D01*
G02Y89087I292J273D01*
G03X902962Y91197I-1096J1027D01*
G02X902946Y91758I277J289D01*
G03X903084Y93497I-1025J956D01*
G02X903416Y94120I332J223D01*
G01X905446D01*
G02X905791Y93518I0J-400D01*
G03X908381I1295J-761D01*
G02X908726Y94120I345J202D01*
G01X912139D01*
G02X912484Y93518I0J-400D01*
G03X915074I1295J-761D01*
G02X915419Y94120I345J202D01*
G01X918832D01*
G02X919177Y93518I0J-400D01*
G03X921767I1295J-761D01*
G02X922112Y94120I345J202D01*
G01X925525D01*
G02X925870Y93518I0J-400D01*
G03X928460I1295J-761D01*
G02X928805Y94120I345J202D01*
G01X932282D01*
G02X932576Y93449I0J-400D01*
G03X932591Y91535I1032J-949D01*
G02X932581Y90973I-290J-276D01*
G03X932536Y88873I1051J-1073D01*
G02Y88327I-292J-273D01*
G03X932592Y86216I1096J-1027D01*
G02X932607Y85655I-277J-288D01*
G03X934657I1025J-957D01*
G02X934672Y86216I292J273D01*
G03X934728Y88327I-1040J1084D01*
G02Y88873I292J273D01*
G03X934663Y90992I-1096J1027D01*
G02X934642Y91553I274J291D01*
G03X934640Y93449I-1034J947D01*
G02X934934Y94120I294J271D01*
G01X937237D01*
G02X937569Y93497I0J-400D01*
G03X937707Y91758I1163J-783D01*
G02X937691Y91197I-293J-272D01*
G03X937636Y89087I1041J-1083D01*
G02Y88541I-292J-273D01*
G03X937772Y86359I1096J-1027D01*
G02X937781Y85751I-256J-308D01*
G03X939653Y85736I928J-1051D01*
G02X939672Y86343I270J295D01*
G03X939828Y88541I-940J1171D01*
G02Y89087I292J273D01*
G03X939773Y91197I-1096J1027D01*
G02X939757Y91758I277J289D01*
G03X939895Y93497I-1025J956D01*
G02X940227Y94120I332J223D01*
G01X942257D01*
G02X942602Y93518I0J-400D01*
G03X945192I1295J-761D01*
G02X945537Y94120I345J202D01*
G01X948950D01*
G02X949295Y93518I0J-400D01*
G03X951885I1295J-761D01*
G02X952230Y94120I345J202D01*
G01X955828D01*
G02X956151Y93484I0J-400D01*
G03X958415I1132J-827D01*
G02X958738Y94120I323J236D01*
G01X962399D01*
G02X962731Y93496I0J-400D01*
G03X965221I1245J-839D01*
G02X965553Y94120I332J224D01*
G01X969029D01*
G02X969374Y93518I0J-400D01*
G03X971964I1295J-761D01*
G02X972309Y94120I345J202D01*
G01X982415D01*
G02X982760Y93518I0J-400D01*
G03X985350I1295J-761D01*
G02X985695Y94120I345J202D01*
G01X989108D01*
G02X989453Y93518I0J-400D01*
G03X992043I1295J-761D01*
G02X992388Y94120I345J202D01*
G01X1002383D01*
G02X1002728Y93518I0J-400D01*
G03X1004546Y94165I1295J-761D01*
G02X1004403Y94823I139J375D01*
G01X1017180Y107600D01*
X1079400D01*
X1092800Y94200D01*
X1099591D01*
G02X1099925Y93581I-1J-400D01*
G03X1102437I1256J-824D01*
G02X1102771Y94200I335J219D01*
G01X1106284D01*
G02X1106618Y93581I-1J-400D01*
G03X1109130I1256J-824D01*
G02X1109464Y94200I335J219D01*
G01X1113069D01*
G02X1113345Y93511I-1J-400D01*
G03X1113299Y91535I971J-1011D01*
G02X1113289Y90973I-290J-276D01*
G03X1113244Y88873I1051J-1073D01*
G02Y88327I-292J-273D01*
G03X1113300Y86216I1096J-1027D01*
G02X1113315Y85655I-277J-288D01*
G03X1115365I1025J-957D01*
G02X1115380Y86216I292J273D01*
G03X1115436Y88327I-1040J1084D01*
G02Y88873I292J273D01*
G03X1115371Y90992I-1096J1027D01*
G02X1115350Y91553I274J291D01*
G03X1115287Y93511I-1034J947D01*
G02X1115563Y94200I277J289D01*
G01X1118002D01*
G02X1118321Y93559I0J-400D01*
G03X1118415Y91758I1119J-845D01*
G02X1118399Y91197I-293J-272D01*
G03X1118344Y89087I1041J-1083D01*
G02Y88541I-292J-273D01*
G03X1118480Y86359I1096J-1027D01*
G02X1118489Y85751I-256J-308D01*
G03X1120361Y85736I928J-1051D01*
G02X1120380Y86343I270J295D01*
G03X1120536Y88541I-940J1171D01*
G02Y89087I292J273D01*
G03X1120481Y91197I-1096J1027D01*
G02X1120465Y91758I277J289D01*
G03X1120559Y93559I-1025J956D01*
G02X1120878Y94200I319J241D01*
G01X1123016D01*
G02X1123350Y93581I-1J-400D01*
G03X1125862I1256J-824D01*
G02X1126196Y94200I335J219D01*
G01X1129709D01*
G02X1130043Y93581I-1J-400D01*
G03X1132555I1256J-824D01*
G02X1132889Y94200I335J219D01*
G01X1136402D01*
G02X1136736Y93581I-1J-400D01*
G03X1139248I1256J-824D01*
G02X1139582Y94200I335J219D01*
G01X1143095D01*
G02X1143429Y93581I-1J-400D01*
G03X1145941I1256J-824D01*
G02X1146275Y94200I335J219D01*
G01X1149881D01*
G02X1150157Y93511I-1J-400D01*
G03X1150111Y91535I971J-1011D01*
G02X1150101Y90973I-290J-276D01*
G03X1150056Y88873I1051J-1073D01*
G02Y88327I-292J-273D01*
G03X1150112Y86216I1096J-1027D01*
G02X1150127Y85655I-277J-288D01*
G03X1152177I1025J-957D01*
G02X1152192Y86216I292J273D01*
G03X1152248Y88327I-1040J1084D01*
G02Y88873I292J273D01*
G03X1152183Y90992I-1096J1027D01*
G02X1152162Y91553I274J291D01*
G03X1152099Y93511I-1034J947D01*
G02X1152375Y94200I277J289D01*
G01X1154814D01*
G02X1155133Y93559I0J-400D01*
G03X1155227Y91758I1119J-845D01*
G02X1155211Y91197I-293J-272D01*
G03X1155156Y89087I1041J-1083D01*
G02Y88541I-292J-273D01*
G03X1155292Y86359I1096J-1027D01*
G02X1155301Y85751I-256J-308D01*
G03X1157173Y85736I928J-1051D01*
G02X1157192Y86343I270J295D01*
G03X1157348Y88541I-940J1171D01*
G02Y89087I292J273D01*
G03X1157293Y91197I-1096J1027D01*
G02X1157277Y91758I277J289D01*
G03X1157371Y93559I-1025J956D01*
G02X1157690Y94200I319J241D01*
G01X1159827D01*
G02X1160161Y93581I-1J-400D01*
G03X1162673I1256J-824D01*
G02X1163007Y94200I335J219D01*
G01X1166520D01*
G02X1166854Y93581I-1J-400D01*
G03X1169366I1256J-824D01*
G02X1169700Y94200I335J219D01*
G01X1173213D01*
G02X1173547Y93581I-1J-400D01*
G03X1176059I1256J-824D01*
G02X1176393Y94200I335J219D01*
G01X1179906D01*
G02X1180240Y93581I-1J-400D01*
G03X1182752I1256J-824D01*
G02X1183086Y94200I335J219D01*
G01X1186692D01*
G02X1186968Y93511I-1J-400D01*
G03X1186922Y91535I971J-1011D01*
G02X1186912Y90973I-290J-276D01*
G03X1186867Y88873I1051J-1073D01*
G02Y88327I-292J-273D01*
G03X1186923Y86216I1096J-1027D01*
G02X1186938Y85655I-277J-288D01*
G03X1188988I1025J-957D01*
G02X1189003Y86216I292J273D01*
G03X1189059Y88327I-1040J1084D01*
G02Y88873I292J273D01*
G03X1188994Y90992I-1096J1027D01*
G02X1188973Y91553I274J291D01*
G03X1188910Y93511I-1034J947D01*
G02X1189186Y94200I277J289D01*
G01X1191625D01*
G02X1191944Y93559I0J-400D01*
G03X1192038Y91758I1119J-845D01*
G02X1192022Y91197I-293J-272D01*
G03X1191967Y89087I1041J-1083D01*
G02Y88541I-292J-273D01*
G03X1192103Y86359I1096J-1027D01*
G02X1192112Y85751I-256J-308D01*
G03X1193984Y85736I928J-1051D01*
G02X1194003Y86343I270J295D01*
G03X1194159Y88541I-940J1171D01*
G02Y89087I292J273D01*
G03X1194104Y91197I-1096J1027D01*
G02X1194088Y91758I277J289D01*
G03X1194182Y93559I-1025J956D01*
G02X1194501Y94200I319J241D01*
G01X1196638D01*
G02X1196972Y93581I-1J-400D01*
G03X1199484I1256J-824D01*
G02X1199818Y94200I335J219D01*
G01X1203331D01*
G02X1203665Y93581I-1J-400D01*
G03X1206177I1256J-824D01*
G02X1206511Y94200I335J219D01*
G01X1210024D01*
G02X1210358Y93581I-1J-400D01*
G03X1212870I1256J-824D01*
G02X1213204Y94200I335J219D01*
G01X1216717D01*
G02X1217051Y93581I-1J-400D01*
G03X1219563I1256J-824D01*
G02X1219897Y94200I335J219D01*
G01X1223503D01*
G02X1223779Y93511I-1J-400D01*
G03X1223733Y91535I971J-1011D01*
G02X1223723Y90973I-290J-276D01*
G03X1223678Y88873I1051J-1073D01*
G02Y88327I-292J-273D01*
G03X1223734Y86216I1096J-1027D01*
G02X1223749Y85655I-277J-288D01*
G03X1225799I1025J-957D01*
G02X1225814Y86216I292J273D01*
G03X1225870Y88327I-1040J1084D01*
G02Y88873I292J273D01*
G03X1225805Y90992I-1096J1027D01*
G02X1225784Y91553I274J291D01*
G03X1225721Y93511I-1034J947D01*
G02X1225997Y94200I277J289D01*
G01X1228436D01*
G02X1228755Y93559I0J-400D01*
G03X1228849Y91758I1119J-845D01*
G02X1228833Y91197I-293J-272D01*
G03X1228778Y89087I1041J-1083D01*
G02Y88541I-292J-273D01*
G03X1228914Y86359I1096J-1027D01*
G02X1228923Y85751I-256J-308D01*
G03X1230795Y85736I928J-1051D01*
G02X1230814Y86343I270J295D01*
G03X1230970Y88541I-940J1171D01*
G02Y89087I292J273D01*
G03X1230915Y91197I-1096J1027D01*
G02X1230899Y91758I277J289D01*
G03X1230993Y93559I-1025J956D01*
G02X1231312Y94200I319J241D01*
G01X1233449D01*
G02X1233783Y93581I-1J-400D01*
G03X1236295I1256J-824D01*
G02X1236629Y94200I335J219D01*
G01X1240142D01*
G02X1240476Y93581I-1J-400D01*
G03X1242988I1256J-824D01*
G02X1243322Y94200I335J219D01*
G01X1246905D01*
G02X1247224Y93560I-1J-400D01*
G03X1249626I1201J-903D01*
G02X1249945Y94200I320J240D01*
G01X1250428D01*
G02X1250726Y93533I0J-400D01*
G03X1252816I1045J-934D01*
G02X1253114Y94200I298J267D01*
G01X1253643D01*
G02X1253953Y93547I0J-400D01*
G03X1256439Y91885I1164J-949D01*
G02X1257143I352J-191D01*
G03X1259786I1321J714D01*
G02X1260489I352J-190D01*
G03X1263132I1322J714D01*
G02X1263836I352J-191D01*
G03X1266322Y93547I1322J713D01*
G02X1266632Y94200I310J253D01*
G01X1267149D01*
G02X1267467Y93557I0J-400D01*
G03X1269695I1114J-851D01*
G02X1270013Y94200I318J243D01*
G01X1283480D01*
G02X1283723Y93483I-1J-400D01*
G03X1290579Y93830I3680J-4805D01*
G01X1290484Y93888D01*
Y94200D01*
X1290800D01*
X1292200Y95600D01*
X1297300D01*
X1298700Y94200D01*
X1302200D01*
X1302300Y94100D01*
X1304700D01*
X1322659Y76141D01*
X1322517Y75999D01*
X1322516D01*
G03X1324499Y74016I984J-999D01*
G01Y74017D01*
X1324641Y74159D01*
X1326396Y72404D01*
G02X1326398Y71841I-283J-283D01*
G03X1326458Y69674I1069J-1055D01*
G02X1326464Y69088I-269J-296D01*
G03X1326442Y66934I1036J-1088D01*
G02Y66366I-282J-284D01*
G03X1328558I1058J-1066D01*
G02Y66934I282J284D01*
G03X1328509Y69112I-1058J1066D01*
G02X1328503Y69698I269J296D01*
G03X1328522Y69717I-1053J1072D01*
G02X1329085Y69715I280J-285D01*
G01X1329900Y68900D01*
Y-19700D01*
X1327779Y-21821D01*
X734021D01*
X733950Y-21750D01*
X714450D01*
X711600Y-18900D01*
Y-17738D01*
G02X712167Y-17375I400J0D01*
G03X712252Y-17411I628J1364D01*
G02X712489Y-17906I-144J-373D01*
G03X714405Y-17057I1335J-427D01*
G02X714198Y-16550I166J364D01*
G03X712282Y-14600I-1402J539D01*
G02X711749Y-14282I-137J376D01*
G03X711619Y-13855I-1486J-219D01*
G01X711600Y-13814D01*
Y-12557D01*
X711616Y-12519D01*
G03Y-11417I-1289J551D01*
G01X711600Y-11379D01*
Y5712D01*
G03Y8488I-800J1388D01*
G01Y22114D01*
G02X711799Y22314I200J0D01*
G03X712894Y22851I-8J1402D01*
G02X713548Y22816I315J-247D01*
G03X715914Y22578I1275J794D01*
G02X716541Y22520I291J-275D01*
G03X716743Y24284I1179J759D01*
G02X716119Y24369I-279J287D01*
G03X715895Y24662I-1296J-759D01*
G02X715944Y25265I285J280D01*
G03X715663Y27685I-830J1130D01*
G02X715536Y28336I156J368D01*
G01X718600Y31400D01*
X738266D01*
X738288Y31225D01*
G03X750298I6005J753D01*
G01X750320Y31400D01*
X755400D01*
X761600Y37600D01*
Y58531D01*
G02X762315Y58777I400J0D01*
G03Y60623I1185J923D01*
G02X761600Y60869I-315J246D01*
G01Y77013D01*
G02X762294Y77283I400J-1D01*
G03X764278Y79518I1106J1017D01*
G02X764254Y80149I234J325D01*
G03X762300Y82149I-903J1072D01*
G02X761600Y82413I-300J265D01*
G01Y87700D01*
X759400Y89900D01*
G37*
G36*
G01X1289826Y507700D02*
G02X1289677Y508471I1J400D01*
G03X1285129I-2274J5608D01*
G02X1284980Y507700I-150J-371D01*
G01X1096274D01*
X1085269Y496695D01*
X1021505D01*
X1021450Y496750D01*
X1001750D01*
X990800Y507700D01*
X765800D01*
G02X765411Y508193I0J400D01*
G03X765082Y509527I-1461J347D01*
G02Y510053I302J263D01*
G03X764571Y512408I-1132J987D01*
G02X764508Y513100I166J364D01*
G03X763087Y512992I-802J1150D01*
G02X763129Y512298I-176J-359D01*
G03X762818Y510053I821J-1258D01*
G02Y509527I-302J-263D01*
G03X762554Y509095I1131J-988D01*
G02X761900Y508960I-371J148D01*
G01X760420Y510440D01*
Y558810D01*
X757730Y561500D01*
X720100D01*
X703800Y577800D01*
X699200D01*
X697800Y579200D01*
Y580497D01*
G03Y582303I-1200J903D01*
G01Y592800D01*
X708000Y603000D01*
X708100D01*
X710587Y605487D01*
Y605774D01*
X710882D01*
X710942Y605701D01*
G03X711010Y605623I1165J947D01*
G02Y605077I-292J-273D01*
G03X713202I1096J-1027D01*
G02Y605623I292J273D01*
G03X713440Y607340I-1096J1027D01*
G02X713656Y607898I355J183D01*
G03X714226Y608277I-525J1407D01*
G02X714852Y608223I292J-274D01*
G03X715012Y610079I1254J827D01*
G02X714386Y610133I-292J274D01*
G03X711798Y608616I-1254J-827D01*
G02X711582Y608058I-355J-183D01*
G03X711222Y607865I523J-1408D01*
G02X710587Y608188I-235J323D01*
G01Y614443D01*
G02X711095Y614828I400J0D01*
G03X712996Y616137I405J1446D01*
G02X713416Y616500I398J-36D01*
G03X712004Y618137I84J1500D01*
G02X711584Y617774I-398J36D01*
G03X711453Y617775I-77J-1500D01*
G02X711158Y618458I-12J400D01*
G01X717277Y624577D01*
X726223D01*
G02X726596Y624035I-1J-400D01*
G03X729404I1404J-535D01*
G02X729777Y624577I374J142D01*
G01X1044723D01*
G02X1045096Y624035I-1J-400D01*
G03X1047904I1404J-535D01*
G02X1048277Y624577I374J142D01*
G01X1325823D01*
X1328000Y622400D01*
Y547249D01*
G02X1327819Y547050I-200J0D01*
G03X1326702Y546282I137J-1395D01*
G02X1326000Y546257I-358J179D01*
G03X1326070Y544861I-1293J-765D01*
G02X1326771Y544906I363J-168D01*
G03X1327819Y544260I1185J749D01*
G02X1328000Y544061I-19J-199D01*
G01Y513800D01*
X1321900Y507700D01*
X1289826D01*
G37*
G36*
G01X787427Y202050D02*
X784967Y204510D01*
Y365751D01*
X785514Y366298D01*
X818100D01*
X819000Y365398D01*
Y211400D01*
X820900Y209500D01*
X843600D01*
X881750Y247650D01*
X912352D01*
G02X912671Y247008I0J-400D01*
G03X914903I1116J-848D01*
G02X915222Y247650I319J242D01*
G01X916136D01*
X916189Y247532D01*
G03X918745I1278J577D01*
G01X918798Y247650D01*
X919412D01*
G02X919731Y247008I0J-400D01*
G03X921963I1116J-848D01*
G02X922282Y247650I319J242D01*
G01X922896D01*
X922949Y247532D01*
G03X925505I1278J577D01*
G01X925558Y247650D01*
X926172D01*
G02X926491Y247008I0J-400D01*
G03X928723I1116J-848D01*
G02X929042Y247650I319J242D01*
G01X929656D01*
X929709Y247532D01*
G03X932265I1278J577D01*
G01X932318Y247650D01*
X936416D01*
X936469Y247532D01*
G03X939025I1278J577D01*
G01X939078Y247650D01*
X943176D01*
X943229Y247532D01*
G03X945785I1278J577D01*
G01X945838Y247650D01*
X949936D01*
X949989Y247532D01*
G03X952545I1278J577D01*
G01X952598Y247650D01*
X956695D01*
X956748Y247532D01*
G03X959304I1278J577D01*
G01X959357Y247650D01*
X959971D01*
G02X960290Y247008I0J-400D01*
G03X962522I1116J-848D01*
G02X962841Y247650I319J242D01*
G01X963455D01*
X963508Y247532D01*
G03X966064I1278J577D01*
G01X966117Y247650D01*
X970215D01*
X970268Y247532D01*
G03X972824I1278J577D01*
G01X972877Y247650D01*
X973491D01*
G02X973810Y247008I0J-400D01*
G03X976042I1116J-848D01*
G02X976361Y247650I319J242D01*
G01X976975D01*
X977028Y247532D01*
G03X978288Y246707I1278J577D01*
G02X978486Y246507I-2J-200D01*
G01Y245811D01*
G02X978288Y245611I-200J0D01*
G03X976977Y243764I18J-1402D01*
G01X977016Y243646D01*
X975132Y241762D01*
X973802D01*
X973216Y241176D01*
G02X972625Y241204I-283J283D01*
G03X971528Y238907I-1079J-895D01*
G02X971726Y238707I-2J-200D01*
G01Y236933D01*
X972044Y236615D01*
Y236203D01*
X971752Y235912D01*
X970321D01*
X969790Y235380D01*
G02X969210Y235396I-282J283D01*
G03X966860Y233949I-1044J-936D01*
G01X966908Y233827D01*
X965092Y232012D01*
X963562D01*
X963030Y231479D01*
G02X962450Y231495I-282J283D01*
G03X960100Y230049I-1044J-936D01*
G01X960147Y229928D01*
X958206Y227986D01*
Y225334D01*
X958524Y225016D01*
Y224503D01*
X958030Y224010D01*
X956700D01*
X956317Y223627D01*
G02X955727Y223654I-283J283D01*
G03X953318Y222313I-1080J-894D01*
G01X953358Y222196D01*
X952891Y221729D01*
G02X952311Y221745I-282J283D01*
G03X949961Y220299I-1044J-936D01*
G01X950009Y220177D01*
X947992Y218160D01*
X946561D01*
X946177Y217776D01*
G02X945586Y217804I-283J283D01*
G03X943428I-1079J-895D01*
G02X942837Y217776I-308J255D01*
G01X942453Y218160D01*
X939801D01*
X938052Y216412D01*
X937442D01*
X935625Y218228D01*
X935673Y218350D01*
G03X933061I-1306J510D01*
G01X933109Y218228D01*
X932657Y217776D01*
G02X932066Y217804I-283J283D01*
G03X929908I-1079J-895D01*
G02X929317Y217776I-308J255D01*
G01X928865Y218228D01*
X928913Y218350D01*
G03X926301I-1306J510D01*
G01X926349Y218228D01*
X924532Y216412D01*
X921272D01*
X921247Y216418D01*
G03X920900Y216462I-348J-1358D01*
G01X915062D01*
X904296Y205696D01*
X826770D01*
X823125Y202050D01*
X820564D01*
X820562Y202248D01*
G03X817358I-1602J-18D01*
G01X817356Y202050D01*
X816888D01*
X815944Y202994D01*
X810162D01*
G02X809763Y203421I0J400D01*
G03X806816Y202666I-1598J109D01*
G02X806479Y202050I-337J-216D01*
G01X805068D01*
G02X804681Y202554I-1J400D01*
G03X801587I-1547J415D01*
G02X801200Y202050I-386J-104D01*
G01X799321D01*
X799290Y202212D01*
G03X796144I-1573J-305D01*
G01X796113Y202050D01*
X793924D01*
G03X791104I-1410J-760D01*
G01X787427D01*
G37*
G36*
G01X769406Y209900D02*
Y210004D01*
X766443Y212966D01*
X766480Y213082D01*
G03X765908Y214684I-1336J426D01*
G02X765901Y215351I217J336D01*
G03X763718Y216623I-785J1161D01*
G02X763037Y216372I-399J32D01*
G01X762652Y216757D01*
G02X762776Y217406I283J282D01*
G03X758828Y218961I-1196J2754D01*
G02X758461Y218402I-367J-159D01*
G01X744342D01*
X744339Y218598D01*
G03X741535I-1402J-24D01*
G01X741532Y218402D01*
X736716D01*
X736517Y218600D01*
Y233401D01*
X740096Y236980D01*
Y244554D01*
X740246Y244592D01*
G03X742406Y248252I-746J2908D01*
G01X742400Y248276D01*
Y253294D01*
G03Y253506I-3000J106D01*
G01Y296083D01*
G03X743754Y300512I-1150J2773D01*
G02X744030Y301129I333J221D01*
G03X742894Y307018I-431J2971D01*
G02X742400Y307407I-94J389D01*
G01Y312667D01*
X742532Y312715D01*
G03Y318361I-1020J2823D01*
G01X742400Y318409D01*
Y374988D01*
G03Y377938I-626J1475D01*
G01Y388800D01*
X748400Y394800D01*
X763000D01*
X766900Y398700D01*
X778700D01*
X778722Y398678D01*
X780877D01*
X783970Y395585D01*
Y373124D01*
X783951Y373083D01*
G03Y371717I1449J-683D01*
G01X783970Y371676D01*
Y366170D01*
X783966Y366166D01*
Y220426D01*
X776957Y213418D01*
X776899Y213406D01*
G03X776171Y213004I283J-1373D01*
G02X775593I-289J277D01*
G03X773298Y211470I-1011J-971D01*
G02X772931Y210910I-367J-160D01*
G01X770759D01*
X769791Y209942D01*
X769747Y209927D01*
G03X769708Y209913I454J-1327D01*
G01X769674Y209900D01*
X769406D01*
G37*
G36*
G01X965237Y194010D02*
G02X965636Y193587I0J-400D01*
G03X968436I1400J-80D01*
G02X968835Y194010I399J23D01*
G01X1005696D01*
G02X1006095Y193588I0J-400D01*
G03X1009095I1500J-81D01*
G02X1009494Y194010I399J22D01*
G01X1025976D01*
G02X1026375Y193588I0J-400D01*
G03X1029375I1500J-81D01*
G02X1029774Y194010I399J22D01*
G01X1041414D01*
G03X1043598I1092J1031D01*
G01X1205830D01*
X1210680Y189160D01*
Y175359D01*
X1210222Y174902D01*
X793056D01*
X792441Y175517D01*
Y177118D01*
X793352Y178029D01*
X819563D01*
X835544Y194010D01*
X950127D01*
G03X952385I1129J831D01*
G01X965237D01*
G37*
G36*
G01X822208Y210800D02*
X820400Y212608D01*
Y363500D01*
X821300Y364400D01*
X841101D01*
G02X841434Y363778I0J-400D01*
G03X843573Y361990I1166J-778D01*
G02X844127I277J-288D01*
G03X846073I973J1010D01*
G02X846627I277J-288D01*
G03X848766Y363778I973J1010D01*
G02X849099Y364400I333J222D01*
G01X863308D01*
X897209Y330500D01*
X915667D01*
G02X916067Y330080I0J-400D01*
G03X918867I1400J-71D01*
G02X919267Y330500I400J20D01*
G01X922427D01*
G02X922827Y330080I0J-400D01*
G03X924529Y328640I1400J-71D01*
G01X924636Y328664D01*
X927119Y326181D01*
G02X926998Y325533I-283J-282D01*
G03X928980Y323551I609J-1373D01*
G02X929628Y323672I366J-162D01*
G01X930005Y323295D01*
X929885Y323154D01*
G03X931932Y321107I1102J-945D01*
G01X932073Y321227D01*
X932872Y320428D01*
X932867Y320339D01*
G03X934446Y318760I1500J-79D01*
G01X934535Y318765D01*
X935900Y317400D01*
X936680D01*
G03X938814I1067J909D01*
G01X939443D01*
G02X939816Y316858I-1J-400D01*
G03X942438I1311J-498D01*
G02X942811Y317400I374J142D01*
G01X943440D01*
G03X945574I1067J909D01*
G01X946203D01*
G02X946576Y316858I-1J-400D01*
G03X949198I1311J-498D01*
G02X949571Y317400I374J142D01*
G01X950200D01*
G03X952334I1067J909D01*
G01X952963D01*
G02X953336Y316858I-1J-400D01*
G03X955958I1311J-498D01*
G02X956331Y317400I374J142D01*
G01X956959D01*
G03X959093I1067J909D01*
G01X959722D01*
G02X960095Y316858I-1J-400D01*
G03X962717I1311J-498D01*
G02X963090Y317400I374J142D01*
G01X963590D01*
G03X964405Y316856I1196J909D01*
G01X964458Y316842D01*
X964823Y316477D01*
G02X964595Y315798I-283J-283D01*
G03X966175Y314218I191J-1389D01*
G02X966854Y314446I396J-55D01*
G01X967230Y314070D01*
G02X967218Y313493I-283J-283D01*
G03X969199Y311512I948J-1033D01*
G02X969776Y311524I294J-271D01*
G01X970000Y311300D01*
X970257D01*
Y311062D01*
X970243Y311026D01*
G03X972915Y310813I1303J-517D01*
G02X973305Y311300I390J87D01*
G01X974139D01*
G03X975713I787J1160D01*
G01X976547D01*
G02X976937Y310813I0J-400D01*
G03X979675I1369J-304D01*
G02X980065Y311300I390J87D01*
G01X980899D01*
G03X982473I787J1160D01*
G01X983307D01*
G02X983697Y310813I0J-400D01*
G03X986099Y311457I1369J-304D01*
G02X986111Y312011I294J271D01*
G01X986413Y312313D01*
G02X987084Y312126I283J-283D01*
G03X987632Y313602I1362J334D01*
G02X987000Y313927I-232J326D01*
G01Y314893D01*
G02X987632Y315218I400J-1D01*
G03X989463Y317325I814J1141D01*
G02X989753Y318000I290J275D01*
G01X990451D01*
X990497Y317864D01*
G03X993155I1329J445D01*
G01X993201Y318000D01*
X997109D01*
X997153Y317860D01*
G03X1000019I1433J449D01*
G01X1000063Y318000D01*
X1023400D01*
X1031000Y325600D01*
Y332900D01*
X1025805Y338095D01*
X1025792Y338117D01*
G03X1025252Y338657I-1297J-757D01*
G01X1025230Y338670D01*
X1025000Y338900D01*
X1014500D01*
X1013150Y340250D01*
Y340772D01*
X1013195Y340827D01*
G03Y342591I-1090J882D01*
G01X1013150Y342646D01*
Y343050D01*
X1013488Y343388D01*
G02X1014151Y343228I282J-283D01*
G03X1015917Y344994I1334J432D01*
G02X1015757Y345657I123J381D01*
G01X1015846Y345746D01*
X1017457D01*
X1017464Y345554D01*
G03X1020266I1401J55D01*
G01X1020273Y345746D01*
X1024217D01*
X1024224Y345554D01*
G03X1027026I1401J55D01*
G01X1027033Y345746D01*
X1029754D01*
X1032134Y348126D01*
X1032230Y348116D01*
G03X1033530Y348700I155J1393D01*
G01X1053666D01*
G02X1053943Y348011I0J-400D01*
G03X1055885I971J-1011D01*
G02X1056162Y348700I277J289D01*
G01X1058700D01*
X1060159Y350159D01*
X1060274Y350122D01*
G03X1062032Y351880I420J1338D01*
G01X1061995Y351995D01*
X1062600Y352600D01*
X1075293D01*
X1075324Y352437D01*
G03X1078080I1378J259D01*
G01X1078111Y352600D01*
X1082053D01*
X1082084Y352437D01*
G03X1084840I1378J259D01*
G01X1084871Y352600D01*
X1088812D01*
X1088843Y352437D01*
G03X1091599I1378J259D01*
G01X1091630Y352600D01*
X1095572D01*
X1095603Y352437D01*
G03X1098359I1378J259D01*
G01X1098390Y352600D01*
X1100800D01*
X1101125Y352275D01*
X1100898Y352048D01*
X1100782Y352084D01*
G03X1101698Y351168I-421J-1337D01*
G01X1101662Y351284D01*
X1101889Y351511D01*
X1102362Y351038D01*
Y349050D01*
X1102359Y349034D01*
G03Y348558I1382J-238D01*
G01X1102362Y348542D01*
Y341362D01*
X1099501Y338501D01*
X1099417Y338503D01*
G03X1097889Y336975I-26J-1502D01*
G01X1097891Y336891D01*
X1085431Y324431D01*
G02X1084763Y324606I-283J283D01*
G03X1082788Y322631I-1543J-432D01*
G02X1082963Y321963I-108J-385D01*
G01X1074300Y313300D01*
X1060400D01*
X1058400Y311300D01*
Y297257D01*
G02X1057714Y296978I-400J0D01*
G03X1055367Y296920I-1147J-1119D01*
G02X1054767I-300J265D01*
G03Y294798I-1200J-1061D01*
G02X1055367I300J-265D01*
G03X1057714Y294740I1200J1061D01*
G02X1058400Y294461I286J-279D01*
G01Y280343D01*
G02X1057721Y280057I-400J0D01*
G03X1055344Y279902I-1119J-1147D01*
G02X1054717I-314J248D01*
G03X1052039Y279652I-1258J-992D01*
G02X1051322Y279670I-354J186D01*
G03X1051287Y278257I-1455J-671D01*
G02X1052004Y278239I354J-186D01*
G03X1054717Y277918I1455J671D01*
G02X1055344I314J-248D01*
G03X1057721Y277763I1258J992D01*
G02X1058400Y277477I279J-286D01*
G01Y266735D01*
G02X1057841Y266368I-400J0D01*
G03X1056002Y265960I-639J-1469D01*
G02X1055402I-300J265D01*
G03Y263838I-1200J-1061D01*
G02X1056002I300J-265D01*
G03X1057841Y263430I1200J1061D01*
G02X1058400Y263063I159J-367D01*
G01Y254041D01*
X1057950Y253591D01*
X1056828Y252470D01*
X1028946D01*
X1027753D01*
X1023935Y248652D01*
X1023738D01*
G02X1023407Y249275I1J400D01*
G03X1021083I-1162J785D01*
G02X1020752Y248652I-332J-223D01*
G01X1020271D01*
X1020217Y248764D01*
G03X1017513I-1352J-655D01*
G01X1017459Y248652D01*
X1017098D01*
G02X1016758Y249264I-1J400D01*
G03X1014212I-1273J796D01*
G02X1013872Y248652I-339J-212D01*
G01X1013511D01*
X1013457Y248764D01*
G03X1010753I-1352J-655D01*
G01X1010699Y248652D01*
X1010338D01*
G02X1009998Y249264I-1J400D01*
G03X1007452I-1273J796D01*
G02X1007112Y248652I-339J-212D01*
G01X1006643D01*
X1006587Y248759D01*
G03X1004103I-1242J-650D01*
G01X1004047Y248652D01*
X1003578D01*
G02X1003238Y249264I-1J400D01*
G03X1000692I-1273J796D01*
G02X1000352Y248652I-339J-212D01*
G01X999884D01*
X999828Y248759D01*
G03X997344I-1242J-650D01*
G01X997288Y248652D01*
X996819D01*
G02X996479Y249264I-1J400D01*
G03X994789Y251503I-1273J796D01*
G02X994278Y251887I-111J384D01*
G01Y252009D01*
G03X994275Y252116I-2452J-15D01*
G02X994786Y252518I400J18D01*
G03X993747Y254318I420J1442D01*
G02X993144Y254076I-388J95D01*
G03X992877Y254224I-1320J-2066D01*
G02X992777Y254879I171J361D01*
G03X990875I-951J1030D01*
G02X990775Y254224I-271J-294D01*
G03X990432Y254025I1055J-2213D01*
G02X989814Y254267I-227J329D01*
G03X987306Y253144I-1368J-307D01*
G02X986981Y252512I-325J-232D01*
G01X986381D01*
X986326Y252624D01*
G03X983806I-1260J-615D01*
G01X983751Y252512D01*
X983387D01*
X982232Y251357D01*
X982116Y251394D01*
G03X980323Y250387I-430J-1334D01*
G03X979187Y249742I599J-2377D01*
G01X978851Y249407D01*
X978734Y249444D01*
G03X977064Y248759I-428J-1335D01*
G01X977008Y248652D01*
X976419D01*
G02X976088Y249275I1J400D01*
G03X973764I-1162J785D01*
G02X973433Y248652I-332J-223D01*
G01X972844D01*
X972788Y248759D01*
G03X970304I-1242J-650D01*
G01X970248Y248652D01*
X969779D01*
G02X969439Y249264I-1J400D01*
G03X966893I-1273J796D01*
G02X966553Y248652I-339J-212D01*
G01X966192D01*
X966138Y248764D01*
G03X963434I-1352J-655D01*
G01X963380Y248652D01*
X959432D01*
X959378Y248764D01*
G03X956674I-1352J-655D01*
G01X956620Y248652D01*
X956140D01*
G02X955809Y249275I1J400D01*
G03X953485I-1162J785D01*
G02X953154Y248652I-332J-223D01*
G01X952565D01*
X952509Y248759D01*
G03X950025I-1242J-650D01*
G01X949969Y248652D01*
X949380D01*
G02X949049Y249275I1J400D01*
G03X946725I-1162J785D01*
G02X946394Y248652I-332J-223D01*
G01X945805D01*
X945749Y248759D01*
G03X943265I-1242J-650D01*
G01X943209Y248652D01*
X942620D01*
G02X942289Y249275I1J400D01*
G03X939965I-1162J785D01*
G02X939634Y248652I-332J-223D01*
G01X939045D01*
X938989Y248759D01*
G03X936505I-1242J-650D01*
G01X936449Y248652D01*
X935860D01*
G02X935529Y249275I1J400D01*
G03X933205I-1162J785D01*
G02X932874Y248652I-332J-223D01*
G01X932285D01*
X932229Y248759D01*
G03X929745I-1242J-650D01*
G01X929689Y248652D01*
X929100D01*
G02X928769Y249275I1J400D01*
G03X926445I-1162J785D01*
G02X926114Y248652I-332J-223D01*
G01X925525D01*
X925469Y248759D01*
G03X922985I-1242J-650D01*
G01X922929Y248652D01*
X922340D01*
G02X922009Y249275I1J400D01*
G03X919685I-1162J785D01*
G02X919354Y248652I-332J-223D01*
G01X918765D01*
X918709Y248759D01*
G03X916225I-1242J-650D01*
G01X916169Y248652D01*
X915280D01*
G02X914949Y249275I1J400D01*
G03X912625I-1162J785D01*
G02X912294Y248652I-332J-223D01*
G01X881335D01*
X881194Y248510D01*
X880890D01*
X843181Y210800D01*
X822208D01*
G37*
G36*
G01X949108Y318402D02*
G02X948851Y319108I0J400D01*
G03X946923I-964J1152D01*
G02X946666Y318402I-257J-306D01*
G01X945915D01*
X945885Y318565D01*
G03X943129I-1378J-256D01*
G01X943099Y318402D01*
X942348D01*
G02X942091Y319108I0J400D01*
G03X940163I-964J1152D01*
G02X939906Y318402I-257J-306D01*
G01X939155D01*
X939125Y318565D01*
G03X936526Y318999I-1378J-256D01*
G02X935895Y318913I-348J197D01*
G01X935522Y319286D01*
X935614Y319422D01*
G03X933529Y321507I-1246J839D01*
G01X933393Y321415D01*
X932431Y322377D01*
X932420Y322441D01*
Y322442D01*
G03X931219Y323642I-1433J-233D01*
G01X931155Y323653D01*
X930781Y324027D01*
G02X931047Y324709I283J282D01*
G03X929586Y326170I-60J1401D01*
G02X928904Y325904I-400J17D01*
G01X928443Y326365D01*
G02X928478Y326961I283J282D01*
G03X926508Y328931I-871J1099D01*
G02X925912Y328896I-314J248D01*
G01X925462Y329346D01*
G03X923564Y331244I-1235J663D01*
G01X923408Y331400D01*
X923316D01*
X923215Y331502D01*
X922647D01*
G02X922248Y331914I1J400D01*
G03X919446I-1401J46D01*
G02X919047Y331502I-400J-12D01*
G01X915587D01*
G02X915188Y331914I1J400D01*
G03X912386I-1401J46D01*
G02X911987Y331502I-400J-12D01*
G01X897906D01*
X864208Y365200D01*
X863924D01*
X863723Y365402D01*
X821398D01*
X818930Y367870D01*
Y404430D01*
X821500Y407000D01*
X872808D01*
X915208Y364600D01*
X922915D01*
X922970Y364489D01*
G03X925256Y364157I1257J620D01*
G02X925832Y364168I293J-272D01*
G01X926305Y363695D01*
X926269Y363579D01*
G03X928026Y361822I1338J-419D01*
G01X928142Y361858D01*
X930699Y359301D01*
G02X930543Y358639I-283J-283D01*
G03X932317Y356865I444J-1330D01*
G02X932979Y357021I379J-127D01*
G01X933371Y356629D01*
G02Y356347I-142J-141D01*
G03X935354Y354364I996J-987D01*
G02X935636I141J-142D01*
G01X936364Y353636D01*
G03X937974Y352026I1383J-227D01*
G01X940565Y349435D01*
G02X940470Y348799I-283J-283D01*
G03X942461Y347128I657J-1239D01*
G01X942476Y347173D01*
X942651Y347349D01*
X942900Y347100D01*
X943073D01*
G02X943391Y346458I0J-400D01*
G03X945623I1116J-849D01*
G02X945941Y347100I318J242D01*
G01X946556D01*
X946610Y346982D01*
G03X949164I1277J578D01*
G01X949218Y347100D01*
X949833D01*
G02X950151Y346458I0J-400D01*
G03X952383I1116J-849D01*
G02X952701Y347100I318J242D01*
G01X953316D01*
X953370Y346982D01*
G03X955924I1277J578D01*
G01X955978Y347100D01*
X956592D01*
G02X956910Y346458I0J-400D01*
G03X959142I1116J-849D01*
G02X959460Y347100I318J242D01*
G01X959971D01*
X960022Y346978D01*
G03X962790I1384J582D01*
G01X962841Y347100D01*
X967684D01*
X971055Y343729D01*
G02X970935Y343081I-283J-283D01*
G03X972918Y341098I611J-1372D01*
G02X973566Y341218I365J-163D01*
G01X973976Y340808D01*
X973857Y340667D01*
G03X976240Y339270I1069J-907D01*
G01X976289Y339400D01*
X976954D01*
G02X977254Y338736I0J-400D01*
G03X979358I1052J-927D01*
G02X979658Y339400I300J264D01*
G01X980324D01*
X980372Y339270D01*
G03X983000I1314J490D01*
G01X983048Y339400D01*
X983714D01*
G02X984014Y338736I0J-400D01*
G03X986118I1052J-927D01*
G02X986418Y339400I300J264D01*
G01X987084D01*
X987132Y339270D01*
G03X989760I1314J490D01*
G01X989808Y339400D01*
X990474D01*
G02X990774Y338736I0J-400D01*
G03X992878I1052J-927D01*
G02X993178Y339400I300J264D01*
G01X993844D01*
X993892Y339270D01*
G03X996520I1314J490D01*
G01X996568Y339400D01*
X997234D01*
G02X997534Y338736I0J-400D01*
G03X999638I1052J-927D01*
G02X999938Y339400I300J264D01*
G01X1000507D01*
G03X1003423I1458J360D01*
G01X1003993D01*
G02X1004293Y338736I0J-400D01*
G03X1006397I1052J-927D01*
G02X1006697Y339400I300J264D01*
G01X1007363D01*
X1007411Y339270D01*
G03X1010039I1314J490D01*
G01X1010087Y339400D01*
X1010622D01*
G02X1010934Y338750I0J-400D01*
G03X1013605Y337886I1171J-941D01*
G01X1013600Y337975D01*
X1013805Y338179D01*
X1014085Y337898D01*
X1022599D01*
G02X1022997Y337469I-1J-400D01*
G03X1025466Y336214I1498J-109D01*
G02X1026008Y336192I259J-305D01*
G01X1029998Y332202D01*
Y326015D01*
X1023188Y319204D01*
X1008450D01*
G02X1008075Y319742I0J400D01*
G03X1005255I-1410J518D01*
G02X1004880Y319204I-375J-138D01*
G01X999792D01*
G03X997380I-1206J-895D01*
G01X996884D01*
G02X996512Y319750I0J400D01*
G03X993900I-1306J510D01*
G02X993528Y319204I-372J-146D01*
G01X992905D01*
G03X990747I-1079J-895D01*
G01X988196D01*
X986274Y317282D01*
Y317049D01*
X985998Y316774D01*
Y313315D01*
X985138Y312454D01*
X983099D01*
X983078Y312630D01*
G03X980294I-1392J-170D01*
G01X980273Y312454D01*
X976339D01*
X976318Y312630D01*
G03X973534I-1392J-170D01*
G01X973513Y312454D01*
X970262D01*
X964315Y318402D01*
X959434D01*
X959404Y318565D01*
G03X956648I-1378J-256D01*
G01X956618Y318402D01*
X952675D01*
X952645Y318565D01*
G03X949889I-1378J-256D01*
G01X949859Y318402D01*
X949108D01*
G37*
G36*
G01X1062218Y354000D02*
G02X1061880Y354613I1J400D01*
G03X1060617Y353960I-1186J747D01*
G02X1060878Y353278I-22J-399D01*
G01X1060440Y352840D01*
X1060384Y352827D01*
G03X1059327Y351770I310J-1367D01*
G01X1059314Y351714D01*
X1057600Y350000D01*
X1033704D01*
X1033650Y350114D01*
G03X1031120I-1265J-605D01*
G01X1031066Y350000D01*
X1030100D01*
X1029063Y348963D01*
X1028982Y348962D01*
G03X1027965Y348500I23J-1402D01*
G01X1027320D01*
G02X1026944Y349035I1J400D01*
G03X1024306I-1319J474D01*
G02X1023930Y348500I-377J-135D01*
G01X1023285D01*
G03X1021205I-1040J-940D01*
G01X1020560D01*
G02X1020184Y349035I1J400D01*
G03X1017546I-1319J474D01*
G02X1017170Y348500I-377J-135D01*
G01X1016525D01*
G03X1014205Y346987I-1040J-940D01*
G01X1014262Y346862D01*
X1013820Y346420D01*
G02X1013219Y346460I-283J283D01*
G03X1011254Y344495I-1114J-851D01*
G02X1011294Y343894I-243J-318D01*
G01X1010809Y343409D01*
G02X1010127Y343685I-282J283D01*
G03X1008700Y342258I-1402J-25D01*
G02X1008976Y341576I-7J-400D01*
G01X1008553Y341153D01*
X1008490Y341142D01*
G03X1008339Y341108I232J-1383D01*
G01X1008312Y341100D01*
X1007135D01*
G02X1006738Y341546I0J400D01*
G03X1003952I-1393J163D01*
G02X1003555Y341100I-397J-46D01*
G01X1002378D01*
X1002351Y341108D01*
G03X1001579I-386J-1348D01*
G01X1001552Y341100D01*
X1000376D01*
G02X999979Y341546I0J400D01*
G03X997193I-1393J163D01*
G02X996796Y341100I-397J-46D01*
G01X995619D01*
X995592Y341108D01*
G03X994820I-386J-1348D01*
G01X994793Y341100D01*
X993616D01*
G02X993219Y341546I0J400D01*
G03X990433I-1393J163D01*
G02X990036Y341100I-397J-46D01*
G01X988859D01*
X988832Y341108D01*
G03X988060I-386J-1348D01*
G01X988033Y341100D01*
X986856D01*
G02X986459Y341546I0J400D01*
G03X983673I-1393J163D01*
G02X983276Y341100I-397J-46D01*
G01X982099D01*
X982072Y341108D01*
G03X981300I-386J-1348D01*
G01X981273Y341100D01*
X980096D01*
G02X979699Y341546I0J400D01*
G03X976913I-1393J163D01*
G02X976516Y341100I-397J-46D01*
G01X975339D01*
X975312Y341108D01*
G03X975108Y341150I-384J-1348D01*
G01X975041Y341159D01*
X972328Y343872D01*
G02X972374Y344478I282J283D01*
G03X970415Y346437I-828J1131D01*
G02X969809Y346391I-323J236D01*
G01X966600Y349600D01*
X966195D01*
X966165Y349764D01*
G03X963407I-1379J-255D01*
G01X963377Y349600D01*
X959435D01*
X959405Y349764D01*
G03X956647I-1379J-255D01*
G01X956617Y349600D01*
X952676D01*
X952646Y349764D01*
G03X949888I-1379J-255D01*
G01X949858Y349600D01*
X945916D01*
X945886Y349764D01*
G03X943229Y350086I-1379J-255D01*
G02X942582Y349968I-364J165D01*
G01X939151Y353399D01*
X939147Y353476D01*
G03X937814Y354809I-1400J-67D01*
G01X937737Y354813D01*
X937320Y355230D01*
G02X937635Y355911I283J282D01*
G03X936349Y357197I112J1398D01*
G02X935668Y356882I-399J-32D01*
G01X935077Y357473D01*
G02X935139Y358090I283J283D01*
G03X933197Y360032I-772J1170D01*
G02X932580Y359970I-334J221D01*
G01X932145Y360405D01*
X932217Y360536D01*
G03X930314Y362439I-1230J673D01*
G01X930183Y362367D01*
X928933Y363617D01*
X928918Y363657D01*
G03X928104Y364471I-1311J-497D01*
G01X928064Y364486D01*
X925300Y367250D01*
X914750D01*
X874500Y407500D01*
Y409500D01*
X1098750D01*
X1099200Y409050D01*
Y398333D01*
G03Y396761I1161J-786D01*
G01Y394433D01*
G03Y392861I1161J-786D01*
G01Y390533D01*
G03Y388961I1161J-786D01*
G01Y386633D01*
G03Y385061I1161J-786D01*
G01Y382733D01*
G03Y381161I1161J-786D01*
G01Y378833D01*
G03Y377261I1161J-786D01*
G01Y374932D01*
G03Y373360I1161J-786D01*
G01Y371033D01*
G03Y369461I1161J-786D01*
G01Y367133D01*
G03Y365561I1161J-786D01*
G01Y363233D01*
G03Y361661I1161J-786D01*
G01Y359333D01*
G03Y357761I1161J-786D01*
G01Y355433D01*
G03X1098960Y354687I1161J-785D01*
G01X1098957Y354607D01*
X1098350Y354000D01*
X1097497D01*
X1097464Y354012D01*
G03X1096498I-483J-1316D01*
G01X1096465Y354000D01*
X1095386D01*
G02X1094990Y354455I0J400D01*
G03X1092212I-1389J192D01*
G02X1091816Y354000I-396J-55D01*
G01X1090737D01*
X1090704Y354012D01*
G03X1089738I-483J-1316D01*
G01X1089705Y354000D01*
X1083978D01*
X1083945Y354012D01*
G03X1082979I-483J-1316D01*
G01X1082946Y354000D01*
X1077218D01*
X1077185Y354012D01*
G03X1076219I-483J-1316D01*
G01X1076186Y354000D01*
X1062218D01*
G37*
G36*
G01X914354Y202050D02*
G02X914071Y202733I0J400D01*
G01X916447Y205108D01*
X918164D01*
X919257Y206202D01*
G02X919830Y206194I283J-283D01*
G03X921927Y206265I1017J965D01*
G02X922517Y206292I307J-256D01*
G01X922968Y205841D01*
X922921Y205720D01*
G03X925556Y205655I1306J-510D01*
G01X925517Y205773D01*
X927401Y207656D01*
X927913D01*
X929728Y205841D01*
X929681Y205720D01*
G03X932316Y205655I1306J-510D01*
G01X932277Y205773D01*
X934161Y207656D01*
X934673D01*
X936488Y205841D01*
X936441Y205720D01*
G03X939076Y205655I1306J-510D01*
G01X939037Y205773D01*
X940921Y207656D01*
X941433D01*
X943248Y205841D01*
X943201Y205720D01*
G03X945836Y205655I1306J-510D01*
G01X945797Y205773D01*
X947681Y207656D01*
X949111D01*
X951061Y209606D01*
X952418D01*
X954571Y211760D01*
X955973D01*
X957720Y213506D01*
X959249D01*
X961200Y215458D01*
X962530D01*
X964479Y217406D01*
X965910D01*
X967986Y219483D01*
Y221158D01*
G02X968184Y221358I200J0D01*
G03X969495Y223205I-18J1402D01*
G01X969456Y223323D01*
X969922Y223789D01*
G02X970502Y223773I282J-283D01*
G03X972852Y225220I1044J936D01*
G01X972804Y225342D01*
X974620Y227158D01*
X976150D01*
X976682Y227690D01*
G02X977262Y227674I282J-283D01*
G03X979612Y229120I1044J936D01*
G01X979565Y229241D01*
X980016Y229692D01*
G02X980606Y229665I283J-283D01*
G03X981704Y231961I1080J894D01*
G02X981506Y232161I2J200D01*
G01Y233936D01*
X981188Y234254D01*
Y234666D01*
X981682Y235160D01*
X983012D01*
X984759Y236906D01*
X986190D01*
X988266Y238983D01*
Y241635D01*
X987948Y241953D01*
Y242466D01*
X988240Y242758D01*
X989570D01*
X990155Y243343D01*
G02X990746Y243315I283J-283D01*
G03X991844Y245611I1080J894D01*
G02X991646Y245811I2J200D01*
G01Y246018D01*
X992517Y246889D01*
X992539Y246902D01*
G03X993104Y247532I-713J1207D01*
G01X993157Y247650D01*
X993771D01*
G02X994090Y247008I0J-400D01*
G03X996322I1116J-848D01*
G02X996641Y247650I319J242D01*
G01X997255D01*
X997308Y247532D01*
G03X999864I1278J577D01*
G01X999917Y247650D01*
X1000530D01*
G02X1000849Y247008I0J-400D01*
G03X1003081I1116J-848D01*
G02X1003400Y247650I319J242D01*
G01X1004014D01*
X1004067Y247532D01*
G03X1006623I1278J577D01*
G01X1006676Y247650D01*
X1007290D01*
G02X1007609Y247008I0J-400D01*
G03X1009841I1116J-848D01*
G02X1010160Y247650I319J242D01*
G01X1010774D01*
X1010827Y247532D01*
G03X1013383I1278J577D01*
G01X1013436Y247650D01*
X1014050D01*
G02X1014369Y247008I0J-400D01*
G03X1016601I1116J-848D01*
G02X1016920Y247650I319J242D01*
G01X1017534D01*
X1017587Y247532D01*
G03X1020143I1278J577D01*
G01X1020196Y247650D01*
X1020810D01*
G02X1021129Y247008I0J-400D01*
G03X1023361I1116J-848D01*
G02X1023680Y247650I319J242D01*
G01X1024350D01*
X1028168Y251468D01*
X1057300D01*
X1058650Y250118D01*
Y245749D01*
G02X1058042Y245407I-400J0D01*
G03Y243011I-728J-1198D01*
G02X1058650Y242669I208J-342D01*
G01Y241849D01*
G02X1058042Y241507I-400J0D01*
G03Y239111I-728J-1198D01*
G02X1058650Y238769I208J-342D01*
G01Y237949D01*
G02X1058042Y237607I-400J0D01*
G03Y235211I-728J-1198D01*
G02X1058650Y234869I208J-342D01*
G01Y234049D01*
G02X1058042Y233707I-400J0D01*
G03Y231311I-728J-1198D01*
G02X1058650Y230969I208J-342D01*
G01Y230150D01*
G02X1058042Y229808I-400J0D01*
G03Y227412I-728J-1198D01*
G02X1058650Y227070I208J-342D01*
G01Y226249D01*
G02X1058042Y225907I-400J0D01*
G03Y223511I-728J-1198D01*
G02X1058650Y223169I208J-342D01*
G01Y218449D01*
G02X1058042Y218107I-400J0D01*
G03Y215711I-728J-1198D01*
G02X1058650Y215369I208J-342D01*
G01Y205850D01*
X1054900Y202100D01*
X1050918D01*
G02X1050555Y202669I0J400D01*
G03X1048013I-1271J591D01*
G02X1047650Y202100I-363J-169D01*
G01X1044158D01*
G02X1043795Y202669I0J400D01*
G03X1041253I-1271J591D01*
G02X1040890Y202100I-363J-169D01*
G01X1033543D01*
G03X1031227I-1158J-791D01*
G01X1017119D01*
G02X1016756Y202669I0J400D01*
G03X1014214I-1271J591D01*
G02X1013851Y202100I-363J-169D01*
G01X996840D01*
G02X996477Y202669I0J400D01*
G03X993935I-1271J591D01*
G02X993572Y202100I-363J-169D01*
G01X991300D01*
X991250Y202050D01*
X990057D01*
G02X989699Y202629I0J400D01*
G03X987193I-1253J629D01*
G02X986835Y202050I-358J-179D01*
G01X981589D01*
G03X979523I-1033J-792D01*
G01X974998D01*
G03X972618I-1190J-742D01*
G01X959216D01*
G03X956836I-1190J-741D01*
G01X945697D01*
G03X943317I-1190J-741D01*
G01X942737D01*
G02X942379Y202630I-1J400D01*
G03X939875I-1252J630D01*
G02X939517Y202050I-357J-180D01*
G01X938937D01*
G03X936557I-1190J-741D01*
G01X935977D01*
G02X935619Y202630I-1J400D01*
G03X933115I-1252J630D01*
G02X932757Y202050I-357J-180D01*
G01X932177D01*
G03X929797I-1190J-741D01*
G01X925417D01*
G03X923037I-1190J-741D01*
G01X922457D01*
G02X922099Y202630I-1J400D01*
G03X919595I-1252J630D01*
G02X919237Y202050I-357J-180D01*
G01X914354D01*
G37*
G36*
G01X1059402Y277276D02*
G02X1060033Y277602I400J0D01*
G03X1062036Y277725I925J1308D01*
G02X1062574I269J-296D01*
G03Y280095I1078J1185D01*
G02X1062036I-269J296D01*
G03X1060033Y280218I-1078J-1185D01*
G02X1059402Y280544I-231J326D01*
G01Y294106D01*
G02X1059994Y294456I400J-1D01*
G03X1061967Y294798I773J1403D01*
G02X1062567I300J-265D01*
G03Y296920I1200J1061D01*
G02X1061967I-300J265D01*
G03X1059994Y297262I-1200J-1061D01*
G02X1059402Y297612I-192J351D01*
G01Y310402D01*
X1061100Y312100D01*
X1075000D01*
X1082600Y319700D01*
X1113378D01*
X1113425Y319568D01*
G03X1116282Y319659I1414J507D01*
G01X1116338Y319852D01*
X1116864Y319700D01*
X1125993D01*
X1125999Y319506D01*
G03X1128542Y320360I1401J41D01*
G01X1128444Y320497D01*
X1128823Y320876D01*
G02X1129458Y320783I283J-283D01*
G03X1130359Y322938I1322J713D01*
G02X1129847Y323322I-112J384D01*
G01Y323570D01*
G02X1130359Y323954I400J0D01*
G03X1129836Y326564I421J1442D01*
G01X1128775Y327625D01*
X1128762Y327679D01*
G03X1128574Y328114I-1363J-331D01*
G03X1127522Y328744I-1174J-767D01*
G01X1127450Y328750D01*
X1126800Y329400D01*
Y334300D01*
X1125100Y336000D01*
Y336198D01*
X1125140Y336252D01*
G03X1125100Y337991I-1119J844D01*
G01Y340101D01*
G03Y341891I-1079J895D01*
G01Y343851D01*
G03Y345941I-1079J1045D01*
G01Y347901D01*
G03Y349691I-1079J895D01*
G01Y351801D01*
G03Y353591I-1079J895D01*
G01Y355100D01*
X1127162Y357162D01*
X1127257Y357152D01*
G03X1128795Y358690I143J1395D01*
G01X1128785Y358785D01*
X1129647Y359647D01*
X1129788Y359505D01*
G03X1132180Y360421I992J991D01*
G02X1132579Y360800I399J-21D01*
G01X1135741D01*
G02X1136140Y360421I0J-400D01*
G03X1137769Y359113I1400J75D01*
G01X1137870Y359130D01*
X1140500Y356500D01*
Y356096D01*
X1140373Y356046D01*
G03Y353248I547J-1399D01*
G01X1140500Y353198D01*
Y352091D01*
X1140377Y352040D01*
G03Y349454I543J-1293D01*
G01X1140500Y349403D01*
Y348191D01*
X1140377Y348140D01*
G03Y345554I543J-1293D01*
G01X1140500Y345503D01*
Y344396D01*
X1140373Y344346D01*
G03Y341548I547J-1399D01*
G01X1140500Y341498D01*
Y340391D01*
X1140377Y340340D01*
G03X1141746Y337914I544J-1293D01*
G01X1141885Y338015D01*
X1142900Y337000D01*
X1142908Y336932D01*
G03X1145454Y336300I1392J164D01*
G01X1148100D01*
X1150134Y334266D01*
X1150130Y334262D01*
X1150006Y334121D01*
G03X1151325Y331819I1054J-925D01*
G02X1151800Y331426I75J-393D01*
G01Y323400D01*
X1153814Y321386D01*
G02X1153733Y320758I-283J-283D01*
G03X1155651Y318840I707J-1211D01*
G02X1156279Y318921I345J-202D01*
G01X1156720Y318480D01*
X1156635Y318345D01*
G03X1158270Y316268I1185J-749D01*
G02X1158798Y315889I128J-379D01*
G01Y315403D01*
G02X1158270Y315024I-400J0D01*
G03Y312368I-450J-1328D01*
G02X1158798Y311989I128J-379D01*
G01Y311609D01*
G02X1158276Y311228I-400J0D01*
G03Y308366I-456J-1431D01*
G02X1158798Y307985I122J-381D01*
G01Y307502D01*
X1158901Y307399D01*
X1158655Y307154D01*
X1158524Y307223D01*
G03X1159319Y305991I-704J-1327D01*
G02X1160001Y306299I399J25D01*
G01X1160464Y305836D01*
G02X1160395Y305215I-283J-283D01*
G03X1162468Y303142I805J-1268D01*
G02X1163089Y303211I338J-214D01*
G01X1163454Y302846D01*
X1163375Y302712D01*
G03X1165843Y301387I1205J-717D01*
G01X1165897Y301500D01*
X1169800D01*
X1173300Y298000D01*
X1174600D01*
X1177260Y295340D01*
X1177117Y295197D01*
G03X1179100Y293214I982J-1001D01*
G02X1179384Y293216I143J-140D01*
G01X1180097Y292503D01*
X1180086Y292407D01*
G03X1181639Y290854I1393J-160D01*
G01X1181735Y290865D01*
X1182700Y289900D01*
X1183507D01*
X1183558Y289774D01*
G03X1186160I1301J522D01*
G01X1186211Y289900D01*
X1186855D01*
G02X1187162Y289244I-1J-400D01*
G03X1189316I1077J-897D01*
G02X1189623Y289900I308J256D01*
G01X1190267D01*
X1190318Y289774D01*
G03X1192920I1301J522D01*
G01X1192971Y289900D01*
X1193615D01*
G02X1193922Y289244I-1J-400D01*
G03X1196076I1077J-897D01*
G02X1196383Y289900I308J256D01*
G01X1196924D01*
X1196972Y289770D01*
G03X1199786I1407J526D01*
G01X1199834Y289900D01*
X1200375D01*
G02X1200682Y289244I-1J-400D01*
G03X1202836I1077J-897D01*
G02X1203143Y289900I308J256D01*
G01X1204087D01*
X1204138Y289774D01*
G03X1206740I1301J522D01*
G01X1206791Y289900D01*
X1207500D01*
X1207502Y289898D01*
X1272502D01*
X1274150Y288250D01*
Y256895D01*
G02X1273969Y256696I-200J0D01*
G03Y253904I131J-1396D01*
G02X1274150Y253705I-19J-199D01*
G01Y241350D01*
X1273883Y241083D01*
X1273742Y241222D01*
G03X1273492Y239023I-981J-1002D01*
G02X1274100Y238682I208J-341D01*
G01Y237220D01*
G03Y235372I1054J-924D01*
G01Y227300D01*
X1275700Y225700D01*
Y195100D01*
X1269100Y188500D01*
X1251300D01*
X1251100Y188600D01*
X1242795D01*
G03X1240629I-1083J-890D01*
G01X1239300D01*
X1228000Y199900D01*
X1227992Y199969D01*
G03X1227596Y200827I-1492J-168D01*
G02Y201373I292J273D01*
G03X1225000Y202479I-1096J1027D01*
G02X1224601Y202100I-399J21D01*
G01X1198680D01*
G03X1196304I-1188J-744D01*
G01X1189746D01*
X1189740Y202294D01*
G03X1186738I-1501J-47D01*
G01X1186732Y202100D01*
X1183380D01*
G02X1182981Y202510I1J400D01*
G03X1179977I-1502J37D01*
G02X1179578Y202100I-400J-10D01*
G01X1176620D01*
G02X1176221Y202510I1J400D01*
G03X1173217I-1502J37D01*
G02X1172818Y202100I-400J-10D01*
G01X1062100D01*
X1060100Y204100D01*
Y251300D01*
X1059300Y252100D01*
Y253525D01*
X1059402Y253626D01*
Y262890D01*
G02X1059921Y263271I400J-1D01*
G03X1061602Y263738I481J1528D01*
G02X1062202I300J-265D01*
G03X1064524Y263655I1200J1061D01*
G02X1065103Y263636I280J-285D01*
G03X1065178Y265844I1197J1065D01*
G02X1064599Y265863I-280J285D01*
G03X1062202Y265860I-1197J-1064D01*
G02X1061602I-300J265D01*
G03X1059921Y266327I-1200J-1061D01*
G02X1059402Y266708I-119J382D01*
G01Y277276D01*
G37*
G36*
G01X1152802Y329938D02*
G02X1153476Y330229I400J0D01*
G03Y332265I964J1018D01*
G02X1152802Y332556I-274J291D01*
G01Y333007D01*
X1152700Y333108D01*
Y333500D01*
X1152228Y333972D01*
X1152217Y333988D01*
G03X1151852Y334353I-1157J-792D01*
G01X1151836Y334364D01*
X1151233Y334967D01*
G02X1151420Y335638I283J283D01*
G03X1149558Y337121I-360J1458D01*
G01X1149557Y337040D01*
X1149358Y336842D01*
X1149200Y337000D01*
X1148816D01*
X1148515Y337302D01*
X1145695D01*
X1145656Y337451D01*
G03X1143751Y338386I-1356J-355D01*
G01X1143653Y338347D01*
X1142050Y339950D01*
Y341958D01*
G03Y343936I-1130J989D01*
G01Y346017D01*
G03Y347677I-1130J830D01*
G01Y349917D01*
G03Y351577I-1130J830D01*
G01Y353658D01*
G03Y355636I-1130J989D01*
G01Y356350D01*
X1141502Y356898D01*
Y356915D01*
X1141319Y357097D01*
X1141485Y357263D01*
X1141517Y357278D01*
G03X1139758Y359332I-597J1269D01*
G02X1139144Y359273I-331J224D01*
G01X1138709Y359708D01*
X1138778Y359838D01*
G03X1136882Y361734I-1238J658D01*
G01X1136752Y361665D01*
X1136615Y361802D01*
X1135945D01*
G02X1135549Y362256I0J400D01*
G03X1132771I-1389J191D01*
G02X1132375Y361802I-396J-54D01*
G01X1131292D01*
X1131259Y361814D01*
G03X1129470Y360994I-478J-1318D01*
G01X1129454Y360954D01*
X1128205Y359705D01*
X1128073Y359777D01*
G03X1126170Y357874I-673J-1230D01*
G01X1126242Y357742D01*
X1125807Y357307D01*
G02X1125191Y357369I-283J283D01*
G03X1123914Y355198I-1170J-773D01*
G02X1124098Y354999I-16J-199D01*
G01Y354293D01*
G02X1123914Y354094I-200J0D01*
G03Y351298I107J-1398D01*
G02X1124098Y351099I-16J-199D01*
G01Y350393D01*
G02X1123914Y350194I-200J0D01*
G03Y347398I107J-1398D01*
G02X1124098Y347199I-16J-199D01*
G01Y346594D01*
G02X1123913Y346394I-200J-1D01*
G03Y343398I108J-1498D01*
G02X1124098Y343198I-15J-199D01*
G01Y342593D01*
G02X1123914Y342394I-200J0D01*
G03Y339598I107J-1398D01*
G02X1124098Y339399I-16J-199D01*
G01Y338693D01*
G02X1123914Y338494I-200J0D01*
G03X1123917Y335698I107J-1398D01*
G01X1123991Y335692D01*
X1125050Y334634D01*
Y334600D01*
X1125798Y333852D01*
Y328985D01*
X1125900Y328884D01*
Y328600D01*
X1126287Y328213D01*
X1126204Y328079D01*
G03X1128260Y326240I1196J-732D01*
G01X1128846Y325654D01*
Y322346D01*
X1128165Y321665D01*
X1120922D01*
X1120885Y321819D01*
G03X1118157I-1364J-323D01*
G01X1118120Y321665D01*
X1114854D01*
G02X1114570Y322346I1J400D01*
G03X1112430I-1070J1054D01*
G02X1112146Y321665I-285J-281D01*
G01X1094525D01*
X1094200Y321990D01*
Y322407D01*
G02X1094511Y322573I200J-1D01*
G03X1096642Y322890I891J1331D01*
G02X1097242Y322913I310J-253D01*
G03X1099520Y322869I1161J1104D01*
G02X1100079I280J-286D01*
G03X1100082Y325161I1121J1145D01*
G02X1099523I-279J286D01*
G03X1097162Y325031I-1121J-1144D01*
G02X1096562Y325008I-310J253D01*
G03X1094760Y325372I-1161J-1104D01*
G02X1094200Y325738I-160J366D01*
G01Y331784D01*
X1098335Y335919D01*
X1098474Y335811D01*
G03X1100441Y335927I917J1190D01*
G02X1101053Y335863I279J-286D01*
G03X1101250Y337774I1247J837D01*
G02X1100638Y337838I-279J286D01*
G03X1100581Y337918I-1251J-831D01*
G01X1100473Y338057D01*
X1102866Y340450D01*
G02X1103531Y340284I283J-283D01*
G03X1104009Y341803I1340J413D01*
G02X1103364Y342118I-245J316D01*
G01Y346995D01*
G02X1103758Y347394I400J-1D01*
G03Y350198I-17J1402D01*
G02X1103364Y350597I6J400D01*
G01Y350895D01*
G02X1103758Y351294I400J-1D01*
G03X1103476Y354073I-18J1402D01*
G02X1103000Y354465I-76J393D01*
G01Y354827D01*
G02X1103476Y355219I400J-1D01*
G03Y357973I265J1377D01*
G02X1103000Y358365I-76J393D01*
G01Y358727D01*
G02X1103476Y359119I400J-1D01*
G03Y361873I265J1377D01*
G02X1103000Y362265I-76J393D01*
G01Y362627D01*
G02X1103476Y363019I400J-1D01*
G03Y365773I265J1377D01*
G02X1103000Y366165I-76J393D01*
G01Y366527D01*
G02X1103476Y366919I400J-1D01*
G03Y369673I265J1377D01*
G02X1103000Y370065I-76J393D01*
G01Y370428D01*
G02X1103476Y370820I400J-1D01*
G03Y373574I265J1377D01*
G02X1103000Y373966I-76J393D01*
G01Y374327D01*
G02X1103476Y374719I400J-1D01*
G03Y377473I265J1377D01*
G02X1103000Y377865I-76J393D01*
G01Y378227D01*
G02X1103476Y378619I400J-1D01*
G03Y381373I265J1377D01*
G02X1103000Y381765I-76J393D01*
G01Y382127D01*
G02X1103476Y382519I400J-1D01*
G03Y385273I265J1377D01*
G02X1103000Y385665I-76J393D01*
G01Y386027D01*
G02X1103476Y386419I400J-1D01*
G03Y389173I265J1377D01*
G02X1103000Y389565I-76J393D01*
G01Y389927D01*
G02X1103476Y390319I400J-1D01*
G03Y393073I265J1377D01*
G02X1103000Y393465I-76J393D01*
G01Y407000D01*
X1104130Y408130D01*
X1115512D01*
G02X1115900Y407634I0J-400D01*
G03X1118622I1361J-338D01*
G02X1119010Y408130I388J96D01*
G01X1184189D01*
G02X1184588Y407746I-1J-400D01*
G03X1187390I1401J54D01*
G02X1187789Y408130I400J-16D01*
G01X1195590D01*
X1195617Y407962D01*
G03X1195686Y407693I1483J237D01*
G02X1195364Y407162I-376J-135D01*
G03X1196307Y404590I191J-1389D01*
G02X1196838Y404496I214J-338D01*
G03X1198567Y406813I1191J915D01*
G02X1198371Y407400I143J374D01*
G03X1198583Y407962I-1271J800D01*
G01X1198610Y408130D01*
X1202470D01*
X1215020Y420680D01*
X1312380D01*
X1315000Y423300D01*
X1315651D01*
G02X1315897Y422585I0J-400D01*
G03X1315688Y420413I923J-1185D01*
G02Y419887I-302J-263D01*
G03X1317807Y417768I1132J-987D01*
G02X1318333I263J-302D01*
G03X1318217Y419919I987J1132D01*
G02X1317923I-147J136D01*
G03X1317839Y420003I-1103J-1019D01*
G02Y420297I136J147D01*
G03X1317743Y422585I-1019J1103D01*
G02X1317989Y423300I246J315D01*
G01X1336281D01*
X1337602Y421979D01*
X1337598Y421975D01*
Y359500D01*
X1329430Y351332D01*
X1329406Y351318D01*
G03X1328882Y350794I694J-1218D01*
G01X1328868Y350770D01*
X1326986Y348888D01*
X1326850Y348980D01*
G03X1324766Y346896I-836J-1248D01*
G01X1324858Y346760D01*
X1317500Y339402D01*
X1219494D01*
X1213991Y333899D01*
G02X1213374Y333963I-282J283D01*
G03X1211433Y332022I-1174J-767D01*
G02X1211497Y331405I-219J-335D01*
G01X1203769Y323677D01*
G02X1203103Y323846I-283J283D01*
G03X1201359Y322102I-1344J-400D01*
G02X1201528Y321436I-114J-383D01*
G01X1198600Y318508D01*
X1196684D01*
G02X1196310Y319050I0J400D01*
G03X1193688I-1311J497D01*
G02X1193314Y318508I-374J-142D01*
G01X1192812D01*
G03X1190426I-1193J-912D01*
G01X1189924D01*
G02X1189550Y319050I0J400D01*
G03X1186928I-1311J497D01*
G02X1186554Y318508I-374J-142D01*
G01X1186052D01*
G03X1183666I-1193J-912D01*
G01X1183164D01*
G02X1182790Y319050I0J400D01*
G03X1180168I-1311J497D01*
G02X1179794Y318508I-374J-142D01*
G01X1179164D01*
G03X1177034I-1065J-912D01*
G01X1176510D01*
G02X1176134Y319042I1J400D01*
G03X1173304I-1415J505D01*
G02X1172928Y318508I-377J-134D01*
G01X1172404D01*
G03X1170274I-1065J-912D01*
G01X1169645D01*
G02X1169271Y319050I0J400D01*
G03X1166649I-1311J497D01*
G02X1166275Y318508I-374J-142D01*
G01X1165645D01*
G03X1163515I-1065J-912D01*
G01X1162885D01*
G02X1162511Y319050I0J400D01*
G03X1159889I-1311J497D01*
G02X1159515Y318508I-374J-142D01*
G01X1158885D01*
G03X1157880Y318997I-1065J-912D01*
G01X1157802Y319000D01*
X1155146Y321656D01*
G02X1155209Y322274I282J283D01*
G03X1153476Y324464I-769J1172D01*
G02X1152802Y324755I-274J291D01*
G01Y329938D01*
G37*
G36*
G01X1383279Y402353D02*
G02X1382725I-277J288D01*
G03X1380779I-973J-1010D01*
G02X1380225I-277J288D01*
G03X1378573Y402570I-973J-1010D01*
G02X1378029Y402727I-194J350D01*
G03X1375827Y403063I-1229J-674D01*
G02X1375273I-277J288D01*
G03X1373105Y402786I-973J-1010D01*
G02X1372417Y402796I-341J209D01*
G03X1372395Y401367I-1217J-696D01*
G02X1373083Y401357I341J-209D01*
G03X1375273Y401043I1217J696D01*
G02X1375827I277J-288D01*
G03X1377479Y400826I973J1010D01*
G02X1378023Y400669I194J-350D01*
G03X1380225Y400333I1229J674D01*
G02X1380779I277J-288D01*
G03X1380866Y400256I972J1011D01*
G02X1380872Y399951I-126J-155D01*
G03X1380768Y397951I928J-1051D01*
G02X1380701Y397352I-295J-270D01*
G03X1382532Y397149I799J-1152D01*
G02X1382599Y397748I295J270D01*
G03X1382773Y397890I-797J1154D01*
G02X1383327I277J-288D01*
G03X1383475Y397766I972J1010D01*
G01Y393793D01*
X1383325Y393754D01*
G03X1382555Y393272I375J-1454D01*
G02X1381945I-305J259D01*
G03Y391328I-1145J-972D01*
G02X1382555I305J-259D01*
G03X1383325Y390846I1145J972D01*
G01X1383475Y390807D01*
Y383879D01*
G03Y382035I1056J-922D01*
G01Y369042D01*
G02X1382840Y368719I-400J1D01*
G03Y366449I-823J-1135D01*
G02X1383475Y366126I235J-324D01*
G01Y360384D01*
X1383453Y360341D01*
G03Y359059I1247J-641D01*
G01X1383475Y359016D01*
Y337375D01*
X1372000Y325900D01*
X1339900D01*
X1332498Y318498D01*
X1332367Y318570D01*
G03X1330407Y316407I-717J-1320D01*
G01X1305947Y291947D01*
G02X1305265Y292255I-283J283D01*
G03X1305267Y292399I-1399J91D01*
G02X1305644Y292813I400J15D01*
G03X1304063Y294173I-85J1500D01*
G02X1303709Y293738I-398J-37D01*
G03X1302724Y291532I157J-1393D01*
G02X1302398Y290900I-326J-232D01*
G01X1207916D01*
X1207915Y290902D01*
X1206704D01*
G03X1204174I-1265J-606D01*
G01X1203293D01*
G02X1202952Y291511I0J400D01*
G03X1200566I-1193J736D01*
G02X1200225Y290902I-341J-209D01*
G01X1199754D01*
G03X1197004I-1375J-606D01*
G01X1196533D01*
G02X1196192Y291511I0J400D01*
G03X1193806I-1193J736D01*
G02X1193465Y290902I-341J-209D01*
G01X1192884D01*
G03X1190354I-1265J-606D01*
G01X1189773D01*
G02X1189432Y291511I0J400D01*
G03X1187046I-1193J736D01*
G02X1186705Y290902I-341J-209D01*
G01X1186124D01*
G03X1183594I-1265J-606D01*
G01X1183198D01*
X1182645Y291455D01*
X1182715Y291586D01*
G03X1180818Y293483I-1236J661D01*
G01X1180687Y293413D01*
X1179413Y294687D01*
X1179397Y294725D01*
G03X1178628Y295494I-1298J-529D01*
G01X1178590Y295510D01*
X1178071Y296029D01*
G02X1178297Y296708I283J283D01*
G03X1176711Y298294I-198J1388D01*
G02X1176032Y298068I-396J57D01*
G01X1175659Y298441D01*
G02X1175671Y299017I283J282D01*
G03X1173336Y300276I-952J1030D01*
G02X1172658Y300058I-395J65D01*
G01X1172304Y300413D01*
G02X1172310Y300984I283J283D01*
G03X1170080Y302613I-971J1011D01*
G01X1170025Y302502D01*
X1165894D01*
X1165839Y302613D01*
G03X1164499Y303396I-1259J-617D01*
G01X1164410Y303390D01*
X1161900Y305900D01*
Y306632D01*
G03Y309062I-700J1215D01*
G01Y310418D01*
G03Y313076I-700J1329D01*
G01Y314432D01*
G03X1162307Y316507I-700J1215D01*
G01X1162850Y317050D01*
X1163283D01*
X1163339Y316943D01*
G03X1165821I1241J653D01*
G01X1165877Y317050D01*
X1166463D01*
G02X1166795Y316427I0J-400D01*
G03X1169125I1165J-780D01*
G02X1169457Y317050I332J223D01*
G01X1170042D01*
X1170098Y316943D01*
G03X1172580I1241J653D01*
G01X1172636Y317050D01*
X1173222D01*
G02X1173554Y316427I0J-400D01*
G03X1175884I1165J-780D01*
G02X1176216Y317050I332J223D01*
G01X1176802D01*
X1176858Y316943D01*
G03X1179340I1241J653D01*
G01X1179396Y317050D01*
X1179863D01*
G02X1180203Y316439I0J-400D01*
G03X1182755I1276J-792D01*
G02X1183095Y317050I340J211D01*
G01X1183454D01*
X1183509Y316938D01*
G03X1186209I1350J658D01*
G01X1186264Y317050D01*
X1186623D01*
G02X1186963Y316439I0J-400D01*
G03X1189515I1276J-792D01*
G02X1189855Y317050I340J211D01*
G01X1190214D01*
X1190269Y316938D01*
G03X1192969I1350J658D01*
G01X1193024Y317050D01*
X1193502D01*
G02X1193834Y316427I0J-400D01*
G03X1196164I1165J-780D01*
G02X1196496Y317050I332J223D01*
G01X1198950D01*
X1220300Y338400D01*
X1318104D01*
G02X1318504Y338006I0J-400D01*
G03X1320180Y339400I1402J19D01*
G02X1319975Y340075I78J392D01*
G01X1326133Y346233D01*
X1326201Y346242D01*
G03X1327504Y347545I-187J1490D01*
G01X1327513Y347613D01*
X1329051Y349151D01*
X1329192Y349032D01*
G03X1330931Y348971I908J1068D01*
G02X1331469Y348912I237J-322D01*
G03X1331515Y350938I1131J988D01*
G02X1331211Y350955I-145J138D01*
G03X1331168Y351008I-1110J-856D01*
G01X1331049Y351149D01*
X1338600Y358700D01*
Y421560D01*
X1353546Y436506D01*
G02X1354111I283J-283D01*
G03X1356094Y438489I989J994D01*
G02Y439054I283J282D01*
G01X1362620Y445580D01*
X1396520D01*
X1398578Y443522D01*
X1398548Y443410D01*
G03X1399200Y440130I3620J-985D01*
G01Y426200D01*
X1395467Y422467D01*
X1395444Y422454D01*
G03X1394933Y421942I703J-1213D01*
G01X1394919Y421919D01*
X1393250Y420250D01*
Y420200D01*
X1384823Y411773D01*
X1384793Y411758D01*
G03X1384406Y411474I624J-1256D01*
G02X1383836Y411467I-288J277D01*
G03X1381919Y411520I-987J-996D01*
G02X1381386Y411522I-265J299D01*
G03X1379457Y411470I-937J-1043D01*
G02X1378898Y411464I-283J283D01*
G03X1376930Y411436I-970J-1013D01*
G02X1376333Y411467I-285J281D01*
G03X1374160Y411486I-1094J-877D01*
G02X1373560Y411468I-308J255D01*
G03X1371513Y411472I-1025J-956D01*
G02X1370930I-291J274D01*
G03X1368761Y411321I-1023J-959D01*
G02X1368112Y411313I-327J230D01*
G03X1365986Y411465I-1128J-832D01*
G02X1365413Y411469I-285J281D01*
G03X1363306Y411369I-1010J-973D01*
G02X1362674Y411375I-314J248D01*
G03X1360748Y411671I-1116J-848D01*
G02X1360178Y411785I-231J326D01*
G03X1357973Y410075I-1188J-745D01*
G02X1357955Y409507I-290J-275D01*
G03X1357899Y407509I955J-1027D01*
G02X1357915Y406971I-288J-278D01*
G03X1357658Y405593I1065J-912D01*
G02X1357414Y405082I-377J-134D01*
G03X1356863Y404725I466J-1322D01*
G02X1356220Y404812I-290J275D01*
G03X1353953Y405106I-1238J-658D01*
G02X1353366I-294J272D01*
G03X1351314Y403195I-1028J-953D01*
G02X1351292Y402627I-292J-273D01*
G03X1350962Y401015I947J-1034D01*
G02X1350771Y400490I-365J-165D01*
G03X1352322Y398189I608J-1263D01*
G02X1352909Y398135I269J-296D01*
G03X1354981Y397961I1115J850D01*
G02X1355544Y397944I273J-293D01*
G03X1357618Y397990I1016J966D01*
G02X1358239Y397968I302J-263D01*
G03X1360584Y398126I1121J842D01*
G02X1361225Y398203I349J-196D01*
G03X1363491Y399813I1025J956D01*
G02X1363713Y400377I354J186D01*
G03X1362284Y402716I-463J1323D01*
G02X1361662Y402805I-276J290D01*
G03X1359852Y403368I-1212J-705D01*
G02X1359282Y403737I-170J362D01*
G03X1359202Y404227I-1402J23D01*
G02X1359446Y404738I377J134D01*
G03X1359991Y407031I-466J1322D01*
G02X1359975Y407569I288J278D01*
G03X1359787Y409574I-1065J911D01*
G02X1359797Y409893I125J156D01*
G03X1359800Y409896I-990J993D01*
G02X1360370Y409782I231J-326D01*
G03X1362655Y409654I1188J745D01*
G02X1363287Y409648I314J-248D01*
G03X1365401Y409512I1116J848D01*
G02X1365974Y409508I285J-281D01*
G03X1368130Y409673I1010J973D01*
G02X1368779Y409681I327J-230D01*
G03X1370929Y409553I1128J832D01*
G02X1371512I291J-274D01*
G03X1373614Y409616I1023J959D01*
G02X1374214Y409634I308J-255D01*
G03X1376237Y409605I1025J956D01*
G02X1376834Y409574I285J-281D01*
G03X1378920Y409460I1094J877D01*
G02X1379479Y409466I283J-283D01*
G03X1381379Y409430I970J1013D01*
G02X1381912Y409428I265J-299D01*
G03X1383025Y409080I937J1043D01*
G02X1383475Y408683I50J-397D01*
G01Y402510D01*
G03X1383279Y402353I775J-1168D01*
G37*
G36*
G01X1389498Y398898D02*
X1413592D01*
X1413623Y398736D01*
G03X1413794Y398285I1377J264D01*
G02X1413513Y397686I-344J-204D01*
G03X1414941Y397017I222J-1384D01*
G02X1415222Y397616I344J204D01*
G03X1416377Y398736I-222J1384D01*
G01X1416408Y398898D01*
X1427715D01*
X1427716Y398900D01*
X1427800D01*
X1431202Y402302D01*
Y435222D01*
G02X1431665Y435617I400J0D01*
G03Y438583I235J1483D01*
G02X1431202Y438978I-63J395D01*
G01Y440200D01*
X1431201Y440201D01*
Y440601D01*
X1430087Y441715D01*
G03X1430219Y441908I-1087J885D01*
G02X1430570Y441902I174J-99D01*
G03X1430704Y443509I1330J698D01*
G02X1430078Y443496I-318J242D01*
G03X1428244Y443781I-1078J-896D01*
G01X1428108Y443694D01*
X1420702Y451100D01*
Y466615D01*
X1420443Y466873D01*
Y466900D01*
X1417143Y470200D01*
X1411200D01*
X1398000Y483400D01*
Y536141D01*
G02X1398678Y536428I400J0D01*
G03Y538590I1043J1081D01*
G02X1398000Y538877I-278J287D01*
G01Y539700D01*
X1420594Y562294D01*
X1420730Y562203D01*
G03X1422812Y564285I830J1252D01*
G01X1422721Y564421D01*
X1443641Y585341D01*
X1453459D01*
X1460293Y592175D01*
G02X1460927Y592085I283J-282D01*
G03X1461069Y591875I1227J677D01*
G02X1461043Y591341I-310J-253D01*
G03X1460952Y589469I996J-987D01*
G02X1460928Y588936I-310J-253D01*
G03X1460864Y587045I1002J-980D01*
G02X1460853Y586512I-304J-260D01*
G03X1460768Y584699I1025J-957D01*
G02X1460730Y584168I-316J-244D01*
G03X1460641Y582252I977J-1005D01*
G02X1460629Y581719I-304J-260D01*
G03X1462719Y581672I1024J-957D01*
G02X1462731Y582205I304J260D01*
G03X1462817Y584019I-1024J958D01*
G02X1462855Y584550I316J244D01*
G03X1462944Y586467I-977J1006D01*
G02X1462955Y587000I304J260D01*
G03X1463017Y588841I-1025J956D01*
G02X1463041Y589374I310J253D01*
G03X1463125Y591240I-1002J980D01*
G02X1463151Y591774I310J253D01*
G03X1461414Y593951I-996J987D01*
G02X1460802Y594290I-212J339D01*
G01Y603255D01*
X1460952Y603294D01*
G03X1463129Y605540I-751J2906D01*
G03X1462577Y608033I290J1372D01*
G03X1460952Y609106I-2377J-1833D01*
G01X1460802Y609145D01*
Y621798D01*
G02X1461002Y621998I200J0D01*
G03X1462276Y623980I-2J1402D01*
G02X1462640Y624546I364J166D01*
G01X1550417D01*
G02X1550791Y624006I0J-400D01*
G03X1553605I1407J-527D01*
G02X1553979Y624546I374J140D01*
G01X1555766D01*
G02X1556146Y624023I0J-400D01*
G03X1558832Y622737I1429J-464D01*
G02X1559499Y622740I334J-219D01*
G03X1562180Y624026I1248J836D01*
G02X1562561Y624546I382J120D01*
G01X1564779D01*
G02X1565145Y623985I0J-400D01*
G03X1567689Y622439I1376J-602D01*
G02X1568315Y622436I312J-251D01*
G03X1570865Y623982I1181J929D01*
G02X1571229Y624546I365J164D01*
G01X1838300D01*
X1839500Y623346D01*
Y604800D01*
X1851600Y592700D01*
X1866872D01*
G02X1867151Y592014I-1J-400D01*
G03X1866998Y590038I1049J-1075D01*
G02X1866705Y589399I-320J-240D01*
G03X1867946Y588808I95J-1399D01*
G02X1868257Y589438I327J230D01*
G03X1869249Y592014I-57J1501D01*
G02X1869528Y592700I280J286D01*
G01X1877700D01*
X1886100Y601100D01*
Y623383D01*
X1887295Y624578D01*
X1967224D01*
G02X1974391Y618872I0J-7354D01*
G01Y598823D01*
G02X1973783Y598482I-400J0D01*
G03Y595918I-783J-1282D01*
G02X1974391Y595577I208J-341D01*
G01Y566683D01*
G02X1973741Y566371I-400J0D01*
G03Y564029I-941J-1171D01*
G02X1974391Y563717I250J-312D01*
G01Y553957D01*
G02X1973704Y553678I-400J0D01*
G03X1971735Y551683I-1004J-978D01*
G02X1971721Y551089I-275J-291D01*
G03X1973720Y548847I979J-1139D01*
G02X1974391Y548553I271J-294D01*
G01Y538283D01*
G02X1973741Y537971I-400J0D01*
G03Y535629I-941J-1171D01*
G02X1974391Y535317I250J-312D01*
G01Y440102D01*
G02X1968526Y434511I-7167J1647D01*
G01X1937403D01*
X1932514Y439400D01*
Y448323D01*
G03Y454035I-2195J2856D01*
G01Y458335D01*
X1927540Y463309D01*
X1926036D01*
X1925870Y463476D01*
X1733785D01*
X1729036Y468225D01*
G02X1729182Y468883I283J282D01*
G03X1727383Y470682I-482J1317D01*
G02X1726725Y470536I-376J137D01*
G01X1725262Y471999D01*
X1724992D01*
X1724918Y472074D01*
X1723834D01*
X1723792Y472220D01*
G03X1720902I-1445J-409D01*
G01X1720860Y472074D01*
X1720502D01*
X1720483Y472253D01*
G03X1717695I-1394J-149D01*
G01X1717676Y472074D01*
X1682088D01*
G02X1681736Y472663I0J400D01*
G03X1679479Y474286I-1236J662D01*
G02X1678925Y474260I-291J275D01*
G03X1677930Y471805I-924J-1055D01*
G02X1678193Y471123I-20J-400D01*
G01X1666093Y459023D01*
X1666022D01*
G02X1665920Y458850I-385J110D01*
G01X1663577Y456507D01*
G02X1662910Y456676I-283J283D01*
G03X1660359Y455240I-1440J-425D01*
G02X1660370Y454715I-296J-269D01*
G03X1660119Y453216I1152J-963D01*
G01X1660165Y453095D01*
X1656107Y449037D01*
Y403321D01*
G02X1655518Y402969I-400J1D01*
G03X1653715Y400616I-709J-1324D01*
G02X1653722Y400076I-292J-274D01*
G03X1653800Y398133I1048J-931D01*
G02X1653820Y397576I-277J-289D01*
G03X1655519Y395399I1041J-939D01*
G02X1656107Y395046I188J-353D01*
G01Y295502D01*
X1658349Y293260D01*
Y291952D01*
X1656107Y289710D01*
Y287959D01*
X1656106Y287948D01*
G03Y287652I1394J-148D01*
G01X1656107Y287641D01*
Y285611D01*
X1628560Y258064D01*
G02X1628018Y258043I-282J283D01*
G03X1625900Y255925I-975J-1143D01*
G02X1625879Y255383I-304J-260D01*
G01X1611968Y241472D01*
X1608437D01*
X1608397Y241621D01*
G03X1608367Y241723I-1551J-401D01*
G02X1608614Y241978I190J64D01*
G03X1607560Y243235I437J1437D01*
G02X1607100Y242792I-397J-48D01*
G03X1605301Y241622I-251J-1582D01*
G01X1605261Y241473D01*
X1604650D01*
X1604649Y241472D01*
X1576185D01*
X1576128Y241576D01*
G03X1573672I-1228J-676D01*
G01X1573615Y241472D01*
X1561793D01*
X1559511Y239190D01*
Y237711D01*
X1559344Y237683D01*
G03X1558193Y236522I233J-1382D01*
G01X1558166Y236354D01*
X1544168D01*
X1544125Y236495D01*
G03X1541255I-1435J-445D01*
G01X1541212Y236354D01*
X1539336D01*
X1539288Y236485D01*
G03X1536656I-1316J-485D01*
G01X1536608Y236354D01*
X1527468D01*
X1523322Y240500D01*
G02X1523575Y241182I283J283D01*
G03X1522646Y243714I-105J1398D01*
G02X1522011Y244038I-235J324D01*
G01Y248589D01*
X1517500Y253100D01*
X1507488D01*
G02X1507146Y253707I0J400D01*
G03X1504746I-1200J725D01*
G02X1504404Y253100I-342J-207D01*
G01X1485452D01*
G03X1483948I-752J-1300D01*
G01X1480499D01*
G02X1480166Y253722I0J400D01*
G03X1477792Y253788I-1166J778D01*
G02X1477669Y253251I-344J-204D01*
G03X1477477Y253100I829J-1252D01*
G01X1474861D01*
X1474839Y253105D01*
G03X1474201I-319J-1365D01*
G01X1474179Y253100D01*
X1472438D01*
X1472398Y253247D01*
G03X1469928Y253946I-1447J-401D01*
G02X1469388Y253942I-272J293D01*
G03X1467092Y253250I-938J-1042D01*
G01X1467054Y253100D01*
X1466547D01*
Y253314D01*
X1466549Y253329D01*
G03X1466012Y254708I-1486J215D01*
G02X1465935Y255246I252J311D01*
G03X1463751Y254936I-1235J854D01*
G02X1463828Y254398I-252J-311D01*
G03X1463561Y253509I1235J-855D01*
G02X1463162Y253100I-400J-9D01*
G01X1459956D01*
G02X1459700Y253807I0J400D01*
G03X1457900I-900J1075D01*
G02X1457644Y253100I-256J-307D01*
G01X1453818D01*
G02X1453478Y253710I0J400D01*
G03X1450922I-1278J790D01*
G02X1450582Y253100I-340J-210D01*
G01X1447724D01*
X1447690Y253113D01*
G03X1446618I-536J-1403D01*
G01X1446584Y253100D01*
X1441113D01*
X1441091Y253275D01*
G03X1440096Y254445I-1391J-175D01*
G02X1439830Y254955I113J383D01*
G03X1438992Y256713I-1330J445D01*
G02X1438837Y257356I141J374D01*
G03X1437308Y256987I-1037J944D01*
G02X1437463Y256344I-141J-374D01*
G03X1438104Y254055I1037J-944D01*
G02X1438370Y253545I-113J-383D01*
G03X1438309Y253275I1331J-442D01*
G01X1438287Y253100D01*
X1435360D01*
G02X1434992Y253655I1J400D01*
G03X1432408I-1292J545D01*
G02X1432040Y253100I-369J-155D01*
G01X1429994D01*
X1404016Y227122D01*
X1399964D01*
G02X1399661Y227783I0J400D01*
G03X1399932Y228264I-1062J915D01*
G02X1400591Y228427I380J-124D01*
G03X1400233Y229871I974J1008D01*
G02X1399574Y229708I-380J124D01*
G03X1397333Y228099I-974J-1008D01*
G02X1397022Y227531I-361J-171D01*
G03X1396718Y227460I188J-1490D01*
G02X1396228Y227661I-131J378D01*
G03X1393407Y227284I-1347J-664D01*
G01X1393375Y227122D01*
X1277220D01*
X1275733Y228609D01*
Y232538D01*
G02X1276243Y232922I400J-1D01*
G03X1276870Y235651I385J1348D01*
G02X1276542Y236101I68J394D01*
G03X1275733Y237573I-1388J195D01*
G01Y249177D01*
G02X1276437Y249436I400J-1D01*
G03Y251256I1067J910D01*
G02X1275733Y251515I-304J260D01*
G01Y251721D01*
X1275889Y251756D01*
G03Y254490I-312J1367D01*
G01X1275733Y254525D01*
Y287433D01*
X1277080Y288780D01*
X1304320D01*
X1331321Y315781D01*
X1331421Y315766D01*
G03X1333134Y317479I229J1484D01*
G01X1333119Y317579D01*
X1333620Y318080D01*
Y318100D01*
X1340418Y324898D01*
X1372415D01*
X1372434Y324918D01*
X1372900D01*
X1386200Y338218D01*
Y343254D01*
G02X1386800Y343600I400J-1D01*
G03X1387328Y343360I1500J2600D01*
G02X1387422Y342650I-130J-378D01*
G03X1389038Y342619I786J-1161D01*
G02X1389161Y343324I237J322D01*
G03X1390532Y344192I-861J2876D01*
G02X1391200Y344075I297J-267D01*
G03X1391879Y345857I1300J525D01*
G02X1391302Y346214I-177J359D01*
G03X1391295Y346402I-3002J-18D01*
G02X1391726Y346828I399J27D01*
G03X1390468Y348926I119J1497D01*
G02X1389890Y348746I-367J160D01*
G03X1389374Y349003I-1590J-2546D01*
G02X1389292Y349707I143J373D01*
G03X1387612Y349779I-792J1157D01*
G02X1387470Y349085I-253J-310D01*
G03X1386800Y348800I831J-2884D01*
G02X1386200Y349146I-200J347D01*
G01Y395600D01*
X1389498Y398898D01*
G37*
G36*
G01X1453044Y102443D02*
G03Y105133I-396J1345D01*
G01X1452900Y105175D01*
Y108155D01*
G03Y110845I-668J1345D01*
G01Y138014D01*
X1452923Y138057D01*
G03Y139443I-1333J693D01*
G01X1452900Y139486D01*
Y169056D01*
X1454445Y170601D01*
X1465796D01*
X1467800Y168597D01*
Y164302D01*
G03Y161898I900J-1202D01*
G01Y132477D01*
G03Y129923I790J-1277D01*
G01Y129508D01*
X1467744Y129450D01*
G03X1467800Y127452I1011J-971D01*
G01Y69505D01*
X1467798Y69504D01*
Y60898D01*
X1449700Y42800D01*
Y42700D01*
X1442939Y35939D01*
X1442804Y36022D01*
G03X1440875Y34093I-737J-1192D01*
G01X1440958Y33958D01*
X1421515Y14515D01*
G02X1420963Y14502I-283J283D01*
G03X1418762Y14088I-945J-1036D01*
G02X1418082Y14028I-358J177D01*
G03X1415627Y13981I-1211J-889D01*
G02X1414965I-331J224D01*
G03X1412438Y13921I-1244J-842D01*
G02X1411758Y13916I-342J208D01*
G03X1409384Y13917I-1187J-746D01*
G02X1408704Y13921I-339J213D01*
G03X1408719Y12382I-1282J-782D01*
G02X1409399Y12400I346J-201D01*
G03X1411743Y12401I1172J770D01*
G02X1412423Y12383I334J-219D01*
G03X1414965Y12297I1298J756D01*
G02X1415627I331J-224D01*
G03X1418238Y12518I1244J842D01*
G02X1418917Y12599I364J-166D01*
G03X1418983Y12522I1097J873D01*
G02X1418970Y11970I-296J-269D01*
G01X1417000Y10000D01*
X1414700D01*
X1414600Y9900D01*
X1411871D01*
G03X1409329I-1271J-800D01*
G01X1406610D01*
X1406599Y10088D01*
G03X1404113Y11132I-1499J-88D01*
G02X1403587I-263J302D01*
G03X1401613I-987J-1132D01*
G02X1401087I-263J302D01*
G03X1398817Y10782I-987J-1132D01*
G02X1398193Y10707I-341J208D01*
G01X1397900Y11000D01*
Y17900D01*
X1398700Y18700D01*
X1409700D01*
X1452900Y61900D01*
Y71950D01*
G02X1453282Y72349I400J0D01*
G03X1454241Y72788I-61J1401D01*
G02X1454833Y72777I291J-274D01*
G03X1454869Y74662I1056J923D01*
G02X1454277Y74673I-291J274D01*
G03X1453282Y75151I-1056J-923D01*
G02X1452900Y75550I18J399D01*
G01Y81891D01*
G02X1453384Y82282I400J0D01*
G03Y85218I316J1468D01*
G02X1452900Y85609I-84J391D01*
G01Y92807D01*
G02X1453407Y93192I400J0D01*
G03X1453623Y93149I400J1447D01*
G02X1453946Y92607I-50J-397D01*
G03X1455533Y93555I1401J-542D01*
G02X1455210Y94097I50J397D01*
G03X1453407Y96086I-1401J542D01*
G02X1452900Y96471I-107J385D01*
G01Y102401D01*
X1453044Y102443D01*
G37*
G36*
G01X1841257Y153478D02*
G02X1840607Y153166I-400J0D01*
G03X1838199Y151676I-940J-1172D01*
G02X1837657Y151221I-391J-85D01*
G03X1838558Y150148I-567J-1391D01*
G02X1839100Y150603I391J85D01*
G03X1840607Y150822I567J1391D01*
G02X1841257Y150510I250J-312D01*
G01Y142850D01*
X1847291Y136816D01*
Y136016D01*
G03X1847184Y135940I815J-1261D01*
G02X1846875Y136029I-122J159D01*
G03X1846222Y134200I-1406J-529D01*
G02X1846775Y134043I201J-346D01*
G03X1847291Y133484I1326J706D01*
G01Y124324D01*
G02X1846548Y124119I-400J0D01*
G03X1839943Y127860I-6605J-3960D01*
G01X1833443D01*
G03Y112456I0J-7702D01*
G01X1839943D01*
G03X1846548Y116197I0J7701D01*
G02X1847291Y115992I343J-205D01*
G01Y108144D01*
X1856446Y98989D01*
Y92542D01*
X1856324Y92490D01*
G03Y89910I549J-1290D01*
G01X1856446Y89858D01*
Y88766D01*
X1856312Y88719D01*
G03Y86075I466J-1322D01*
G01X1856446Y86028D01*
Y81157D01*
X1859553Y78050D01*
X1866533D01*
X1872333Y72250D01*
X1892955D01*
G03X1894967I1006J1115D01*
G01X1896080D01*
G03X1897860I890J1210D01*
G01X1910650D01*
X1913600Y75200D01*
X1928698D01*
G02X1928950Y74490I0J-400D01*
G03X1928897Y72050I1011J-1243D01*
G02X1928934Y71490I-266J-299D01*
G03X1931270Y69302I1217J-1042D01*
G02X1931830I280J-286D01*
G03X1933990Y69229I1120J1145D01*
G02X1934510I260J-304D01*
G03X1936590I1040J1218D01*
G02X1937110I260J-304D01*
G03X1939311Y69343I1040J1218D01*
G02X1939871Y69363I290J-275D01*
G03X1942070Y69402I1079J1184D01*
G02X1942630I280J-286D01*
G03X1944809Y71749I1120J1145D01*
G02X1944769Y72308I265J300D01*
G03X1944831Y72384I-1210J1050D01*
G02X1945141Y72396I160J-120D01*
G03X1947391Y72229I1209J1051D01*
G02X1947911Y72230I261J-303D01*
G03X1950132Y74530I1040J1218D01*
G02X1950427Y75200I295J270D01*
G01X1954020D01*
X1959725Y80905D01*
Y97975D01*
X1954061Y103639D01*
X1954047Y103665D01*
G03X1953441Y104271I-1321J-715D01*
G01X1953415Y104285D01*
X1933409Y124291D01*
Y126203D01*
G02X1933964Y126572I400J0D01*
G03Y129342I580J1385D01*
G02X1933409Y129711I-155J369D01*
G01Y145227D01*
X1933286Y145350D01*
X1933507Y145572D01*
X1933616Y145545D01*
G03X1935326Y146201I384J1555D01*
G02X1935670Y146178I165J-113D01*
G03X1935780Y145993I1429J724D01*
G02X1935605Y145398I-330J-226D01*
G03X1937459Y144811I581J-1385D01*
G02X1937659Y145399I339J213D01*
G03X1937936Y148267I-559J1501D01*
G02X1937890Y148917I208J341D01*
G03X1936181Y148862I-890J1083D01*
G02X1936178Y148210I-233J-325D01*
G03X1935925Y147989I922J-1310D01*
G02X1935305Y148029I-294J271D01*
G03X1932400Y147181I-1305J-929D01*
G02X1931718Y146918I-399J20D01*
G01X1931320Y147316D01*
X1919238D01*
X1918671Y147883D01*
X1918900Y148111D01*
X1919017Y148073D01*
G03X1918276Y150393I467J1427D01*
G02X1917609Y150430I-321J238D01*
G03X1917135Y150931I-1299J-754D01*
G01Y170466D01*
X1917118Y170483D01*
Y175287D01*
X1913593Y178812D01*
X1913592Y178893D01*
G03X1912213Y180272I-1402J-23D01*
G01X1912132Y180273D01*
X1898204Y194201D01*
X1898209Y194291D01*
G03X1896621Y195879I-1499J89D01*
G01X1896531Y195874D01*
X1893907Y198498D01*
G02X1893896Y199052I283J283D01*
G03X1894288Y199946I-1105J1017D01*
G02X1894774Y200304I399J-32D01*
G03X1896183Y202810I326J1466D01*
G02X1896291Y203444I289J277D01*
G03X1894531Y203745I-676J1341D01*
G02X1894423Y203111I-289J-277D01*
G03X1893603Y201893I677J-1341D01*
G02X1893117Y201535I-399J32D01*
G03X1891774Y201174I-326J-1466D01*
G02X1891220Y201185I-271J294D01*
G01X1886892Y205513D01*
Y209191D01*
X1887056Y209221D01*
G03X1887906Y211462I-256J1379D01*
G02X1887954Y212006I315J246D01*
G03X1887076Y214622I-1002J1119D01*
G02X1886892Y214821I16J199D01*
G01Y241532D01*
X1913639D01*
X1913657Y241528D01*
G03X1916059Y244381I380J2118D01*
G02X1916435Y244918I376J137D01*
G01X1947619D01*
G02X1947869Y244206I0J-400D01*
G03X1946598Y241555I2131J-2652D01*
G01Y239155D01*
G03X1953251Y238154I3402J0D01*
G01X1953852D01*
G02X1954244Y237673I0J-400D01*
G03X1959543Y236615I2646J-547D01*
G02X1960225Y236815I393J-76D01*
G03X1959666Y239000I1665J1590D01*
G02X1958972Y238849I-386J104D01*
G03X1957841Y239655I-2081J-1724D01*
G02X1957616Y240190I141J374D01*
G03X1956631Y244206I-3116J1365D01*
G02X1956881Y244918I250J312D01*
G01X1964212D01*
X1964680Y244450D01*
Y241120D01*
X1966430Y239370D01*
X1974004D01*
X1974554Y238820D01*
Y210614D01*
X1974130Y210190D01*
X1966370D01*
X1964630Y208450D01*
Y205350D01*
X1966070Y203910D01*
X1974244D01*
X1974554Y203600D01*
Y144634D01*
G02X1973912Y144316I-400J1D01*
G03Y141924I-908J-1196D01*
G02X1974554Y141606I242J-319D01*
G01Y58814D01*
X1972680Y56940D01*
X1958578D01*
G02X1958194Y57449I1J400D01*
G03X1955306Y61270I-2888J819D01*
G01X1950206D01*
G03X1947318Y57449I0J-3002D01*
G02X1946934Y56940I-385J-109D01*
G01X1905290D01*
X1903120Y54770D01*
Y52760D01*
G02X1902523Y52412I-400J0D01*
G03X1897805Y48998I-1578J-2786D01*
G02X1897250Y48554I-392J-79D01*
G03Y42706I-1305J-2924D01*
G02X1897805Y42262I163J-365D01*
G03X1897771Y41214I3140J-626D01*
G02X1897224Y40790I-397J-53D01*
G03X1897035Y34415I-1279J-3152D01*
G02X1897561Y33995I128J-379D01*
G03Y33289I3384J-353D01*
G02X1897035Y32869I-398J-41D01*
G03Y26423I-1090J-3223D01*
G02X1897561Y26003I128J-379D01*
G03X1897588Y25098I3384J-352D01*
G02X1897055Y24658I-394J-65D01*
G03X1897250Y18730I-1110J-3004D01*
G02X1897805Y18286I163J-365D01*
G03Y17030I3140J-628D01*
G02X1897250Y16586I-392J-79D01*
G03Y10738I-1305J-2924D01*
G02X1897805Y10294I163J-365D01*
G03Y9038I3140J-628D01*
G02X1897250Y8594I-392J-79D01*
G03Y2746I-1305J-2924D01*
G02X1897805Y2302I163J-365D01*
G03Y1046I3140J-628D01*
G02X1897250Y602I-392J-79D01*
G03Y-5246I-1305J-2924D01*
G02X1897805Y-5690I163J-365D01*
G03X1902461Y-9139I3140J-628D01*
G02X1903050Y-9491I189J-352D01*
G01Y-11370D01*
X1905390Y-13710D01*
X1918970D01*
X1919670Y-14410D01*
Y-21330D01*
X1919211Y-21789D01*
X1894866D01*
G02X1894491Y-21251I1J400D01*
G03X1891671I-1410J516D01*
G02X1891296Y-21789I-376J-138D01*
G01X1888989D01*
X1887600Y-20400D01*
Y-1200D01*
X1876500Y9900D01*
X1850000D01*
X1839834Y-266D01*
Y-21055D01*
X1839100Y-21789D01*
X1437289D01*
X1436384Y-20884D01*
Y3156D01*
X1437655Y4427D01*
Y8882D01*
X1435500Y11037D01*
Y26300D01*
X1442909Y33709D01*
X1442919Y33717D01*
G03X1443180Y33978I-852J1113D01*
G01X1443188Y33988D01*
X1468800Y59600D01*
Y69089D01*
X1471400Y71689D01*
X1548350D01*
X1554119Y65920D01*
X1591099D01*
X1592756Y67577D01*
Y69405D01*
X1592926Y69431D01*
G03Y72203I-211J1386D01*
G01X1592756Y72229D01*
Y74907D01*
G03X1592905Y76213I-1156J793D01*
G02X1593215Y76755I372J147D01*
G03X1593121Y79537I-215J1385D01*
G02X1592756Y79935I35J398D01*
G01Y89726D01*
X1589433Y93049D01*
X1589581Y93198D01*
X1589589Y93204D01*
G03X1589714Y93320I-889J1084D01*
G02X1590035Y93276I145J-138D01*
G03X1590401Y95040I1235J664D01*
G02X1589830Y95117I-248J314D01*
G03X1587732Y95302I-1130J-829D01*
G02X1587173Y95309I-276J290D01*
G01X1584734Y97748D01*
Y99236D01*
G02X1585215Y99627I400J-1D01*
G03X1586212Y99792I285J1373D01*
G02X1586749Y99669I204J-344D01*
G03X1587165Y101748I1251J831D01*
G02X1586622Y101841I-223J332D01*
G03X1585215Y102373I-1122J-841D01*
G02X1584734Y102764I-81J392D01*
G01Y164891D01*
X1586862Y167019D01*
X1593500D01*
G02X1593897Y166576I-1J-400D01*
G03X1596685I1394J-153D01*
G02X1597082Y167019I398J43D01*
G01X1599258D01*
X1599312Y166904D01*
G03X1601668I1178J555D01*
G01X1601722Y167019D01*
X1608618D01*
X1608668Y167069D01*
X1609080D01*
G02X1609435Y166485I0J-400D01*
G03X1611747I1156J-600D01*
G02X1612102Y167069I355J184D01*
G01X1612230D01*
G02X1612585Y166485I0J-400D01*
G03X1614897I1156J-600D01*
G02X1615252Y167069I355J184D01*
G01X1615380D01*
G02X1615735Y166485I0J-400D01*
G03X1618047I1156J-600D01*
G02X1618402Y167069I355J184D01*
G01X1618530D01*
G02X1618885Y166485I0J-400D01*
G03X1619605Y167112I1156J-600D01*
G01X1619486Y167070D01*
X1619255Y167300D01*
X1619653Y167698D01*
X1619758Y167678D01*
G03X1620449Y170180I247J1278D01*
G01X1620317Y170228D01*
Y172056D01*
G02X1621005Y172333I400J-1D01*
G03X1623009Y173983I937J904D01*
G02X1623337Y174612I328J229D01*
G01X1623840D01*
G02X1624104Y173912I0J-400D01*
G03X1625828I862J-976D01*
G02X1626092Y174612I264J300D01*
G01X1666360D01*
X1673833Y182085D01*
X1673974Y181958D01*
G03X1675954Y183938I938J1042D01*
G01X1675827Y184079D01*
X1678092Y186344D01*
G02X1678773Y186029I282J-283D01*
G03X1679252Y184752I1597J-129D01*
G02X1679261Y184475I-139J-143D01*
G03X1681795Y182531I1189J-1074D01*
G02X1682294Y182678I335J-218D01*
G03X1682483Y185672I656J1462D01*
G02X1681967Y186024I-117J383D01*
G03X1681776Y186668I-1597J-123D01*
G02X1682127Y187260I351J192D01*
G01X1686294D01*
G02X1686661Y186702I0J-400D01*
G03X1689239I1289J-552D01*
G02X1689606Y187260I367J158D01*
G01X1690860D01*
X1694272Y183848D01*
Y172402D01*
X1695221Y171453D01*
X1712079D01*
X1717221Y176595D01*
X1717542D01*
Y176373D01*
X1717537Y176351D01*
G03X1720694Y176156I1563J-351D01*
G02X1721092Y176595I398J39D01*
G01X1721196D01*
G02X1721594Y176158I0J-400D01*
G03X1724784I1595J-146D01*
G02X1725182Y176595I398J37D01*
G01X1725672D01*
X1725686Y176410D01*
G03X1727193Y175014I1507J115D01*
G01X1732193D01*
G03X1733695Y176356I0J1511D01*
G01X1733715Y176534D01*
X1733904D01*
Y176595D01*
X1738271D01*
X1738285Y176410D01*
G03X1739792Y175014I1507J115D01*
G01X1744792D01*
G03X1746294Y176356I0J1511D01*
G01X1746314Y176534D01*
X1746503D01*
Y176595D01*
X1747296D01*
G02X1747695Y176177I-1J-400D01*
G03X1750706Y175345I1600J-73D01*
G02X1751337Y175442I352J-190D01*
G03X1752390Y175014I1054J1083D01*
G01X1757390D01*
G03X1758892Y176356I0J1511D01*
G01X1758912Y176534D01*
X1759101D01*
Y176595D01*
X1763467D01*
X1763481Y176410D01*
G03X1764987Y175014I1507J115D01*
G01X1769988D01*
G03X1770133Y175021I0J1511D01*
G01X1770227Y175030D01*
X1775404Y169853D01*
X1776913D01*
X1776934Y169832D01*
X1784249D01*
G02X1784512Y169131I-1J-400D01*
G03X1786488I988J-1131D01*
G02X1786751Y169832I264J301D01*
G01X1805479D01*
G02X1805871Y169352I0J-400D01*
G03X1806662Y167630I1569J-322D01*
G02Y166930I-194J-350D01*
G03Y164130I778J-1400D01*
G02Y163430I-194J-350D01*
G03X1808218I778J-1400D01*
G02Y164130I194J350D01*
G03Y166930I-778J1400D01*
G02Y167630I194J350D01*
G03X1809009Y169352I-778J1400D01*
G02X1809401Y169832I392J80D01*
G01X1814224D01*
G02X1814624Y169445I0J-400D01*
G03X1817626I1501J47D01*
G02X1818026Y169832I400J-13D01*
G01X1819761D01*
X1819797Y169677D01*
G03X1822725I1464J335D01*
G01X1822761Y169832D01*
X1832622D01*
G03X1834636I1007J975D01*
G01X1835580D01*
G03X1837979Y169409I1352J654D01*
G01X1838120Y169547D01*
X1841257Y166410D01*
Y160985D01*
G02X1840650Y160643I-400J0D01*
G03X1838824Y158283I-777J-1285D01*
G02X1838855Y157744I-279J-286D01*
G03X1840654Y155651I1087J-886D01*
G02X1841257Y155307I203J-345D01*
G01Y153478D01*
G37*
G36*
G01X1469667Y129543D02*
G02X1469646Y130132I260J304D01*
G03X1469217Y132565I-1056J1068D01*
G01X1469100Y132619D01*
Y146491D01*
G02X1469555Y146887I400J0D01*
G03Y149665I192J1389D01*
G02X1469100Y150061I-55J396D01*
G01Y161646D01*
X1469229Y161694D01*
G03Y164506I-529J1406D01*
G01X1469100Y164554D01*
Y164791D01*
X1471399Y167090D01*
X1508893D01*
G02X1509280Y166590I0J-400D01*
G03X1511996I1358J-350D01*
G02X1512383Y167090I387J100D01*
G01X1526251D01*
G03X1528749I1249J636D01*
G01X1544906D01*
X1546900Y165096D01*
Y89793D01*
G02X1546237Y89492I-400J0D01*
G03Y87228I-987J-1132D01*
G02X1546900Y86927I263J-301D01*
G01Y85977D01*
G02X1546471Y85578I-400J0D01*
G03Y82782I-101J-1398D01*
G02X1546900Y82383I29J-399D01*
G01Y74352D01*
X1545246Y72698D01*
X1492714D01*
G02X1492336Y73228I0J400D01*
G03X1489306I-1515J522D01*
G02X1488928Y72698I-378J-130D01*
G01X1470900D01*
X1469100Y74498D01*
Y127112D01*
X1469232Y127160D01*
G03X1469667Y129543I-477J1318D01*
G37*
G36*
G01X1737400Y248008D02*
G02X1737840Y248406I400J0D01*
G03X1739200Y248939I160J1594D01*
G02X1739800I300J-265D01*
G03Y251061I1200J1061D01*
G02X1739200I-300J265D01*
G03X1739078Y251185I-1201J-1060D01*
G02X1739064Y251764I269J296D01*
G01X1739400Y252100D01*
X1789041D01*
G02X1789339Y251433I0J-400D01*
G03X1791447Y249585I1044J-935D01*
G02X1792075Y249558I303J-261D01*
G03X1793384Y248886I1309J939D01*
G01X1798384D01*
G03X1799692Y249557I-1J1612D01*
G02X1800321Y249584I325J-233D01*
G03X1802349Y249481I1063J914D01*
G02X1802995Y249341I275J-290D01*
G03X1803315Y250955I1393J563D01*
G02X1802664Y251071I-286J279D01*
G03X1802428Y251433I-1278J-575D01*
G02X1802726Y252100I298J267D01*
G01X1807939D01*
G02X1808237Y251433I0J-400D01*
G03X1810345Y249585I1044J-935D01*
G02X1810973Y249558I303J-261D01*
G03X1812281Y248886I1309J940D01*
G01X1817282D01*
G03X1818590Y249557I-1J1612D01*
G02X1819218Y249584I325J-234D01*
G03X1821325Y251433I1063J914D01*
G02X1821623Y252100I298J267D01*
G01X1822401D01*
G02X1822800Y251721I0J-400D01*
G03X1824369Y250300I1500J79D01*
G02X1824787Y249921I18J-400D01*
G03X1827350Y248938I1500J79D01*
G02X1827922Y248932I283J-282D01*
G03X1827998Y250942I1014J968D01*
G02X1827427Y250978I-268J297D01*
G03X1826218Y251500I-1140J-978D01*
G02X1825800Y251879I-18J400D01*
G03X1825799Y251888I-1491J-161D01*
G01Y252100D01*
X1830199D01*
X1830234Y251944D01*
G03X1833166I1466J328D01*
G01X1833201Y252100D01*
X1833300D01*
X1843216Y262016D01*
X1872323D01*
G03X1874356Y264872I0J2152D01*
G02X1874734Y265403I378J131D01*
G01X1884176D01*
X1884336Y265367D01*
X1885552Y264151D01*
Y248848D01*
X1883999Y247295D01*
X1862195D01*
X1849400Y234500D01*
X1845137D01*
G02X1844743Y234965I1J400D01*
G03X1844229Y237117I-2814J465D01*
G02X1844351Y237699I323J236D01*
G03X1842364Y239853I-751J1301D01*
G02X1841670Y239916I-329J227D01*
G03X1839659Y237941I-1370J-616D01*
G02X1839789Y237315I-170J-362D01*
G03X1839115Y234965I2140J-1885D01*
G02X1838721Y234500I-395J-65D01*
G01X1837702D01*
G02X1837331Y235048I1J400D01*
G03X1834541I-1395J556D01*
G02X1834170Y234500I-372J-148D01*
G01X1827612D01*
G02X1827291Y235138I0J400D01*
G03X1824773Y236765I-1206J895D01*
G02X1824098Y236727I-350J194D01*
G03X1821577Y235100I-1221J-875D01*
G02X1821231Y234500I-346J-200D01*
G01X1795491D01*
G02X1795094Y234942I1J400D01*
G03X1792106I-1494J158D01*
G02X1791709Y234500I-398J-42D01*
G01X1769934D01*
G03X1767466I-1234J-856D01*
G01X1759434D01*
G03X1757214I-1110J-1843D01*
G01X1743902D01*
X1743900Y234698D01*
G03X1740934Y235015I-1502J-17D01*
G02X1740397Y234732I-390J89D01*
G03X1738951Y234539I-549J-1398D01*
G01X1738898Y234500D01*
X1738400D01*
X1737400Y235500D01*
Y236179D01*
G03Y238421I-1000J1121D01*
G01Y248008D01*
G37*
G36*
G01X1972448Y-13662D02*
X1974577Y-15790D01*
Y-19685D01*
G02X1972441Y-21821I-2136J0D01*
G01X1966914D01*
X1966913Y-21822D01*
X1921773D01*
X1921772Y-21821D01*
X1920700D01*
Y-14030D01*
X1921068Y-13662D01*
X1972448D01*
G37*
%LPC*%
G75*
G36*
G01X58661Y496081D02*
G03X59102Y496212I127J379D01*
G02X59045Y494550I1100J-870D01*
G03X58614Y494710I-329J-226D01*
G02X58661Y496081I-1312J731D01*
G37*
G36*
G01X1372908Y614982D02*
G03X1372332Y614897I-248J-314D01*
G02X1372030Y616935I-1232J859D01*
G03X1372606Y617020I248J314D01*
G02X1375108Y616962I1232J-859D01*
G03X1375693Y616861I338J214D01*
G02X1375408Y614951I863J-1105D01*
G03X1374819Y615024I-327J-230D01*
G02X1372908Y614982I-981J1137D01*
G37*
G36*
G01X1377032Y605669D02*
G03Y605143I302J-263D01*
G02X1374768I-1132J-987D01*
G03Y605669I-302J263D01*
G02X1374798Y607677I1132J987D01*
G03X1374811Y608206I-293J272D01*
G02X1377063Y608152I1150J967D01*
G03X1377050Y607623I293J-272D01*
G02X1377032Y605669I-1150J-966D01*
G37*
G36*
G01X29158Y590493D02*
G03X28555Y590491I-301J-264D01*
G02X28549Y592333I-1060J918D01*
G03X29152Y592335I301J264D01*
G02X31092Y592509I1060J-918D01*
G03X31624Y592535I251J311D01*
G02X33538Y592588I985J-997D01*
G03X34088Y592606I265J299D01*
G02X34156Y590571I997J-985D01*
G03X33606Y590553I-265J-299D01*
G02X31729Y590446I-998J985D01*
G03X31197Y590420I-251J-311D01*
G02X29158Y590493I-985J997D01*
G37*
G36*
G01X2515Y591438D02*
G03X2495Y590851I262J-303D01*
G02X516Y590968I-1056J-1068D01*
G03X566Y591554I-245J316D01*
G02X506Y591623I1027J954D01*
G03X194I-156J-125D01*
G02X73Y593510I-1094J877D01*
G03X627I277J288D01*
G02X2515Y591438I973J-1010D01*
G37*
G36*
G01X1379544Y591226D02*
G02X1384556Y591074I2556J1574D01*
G02X1379544Y591226I-2556J-1574D01*
G37*
G36*
G01X1421670Y583521D02*
G02X1419170I-1250J2729D01*
G02X1416467Y583623I-1250J2729D01*
G02X1412514Y584939I-1294J2709D01*
G02Y587725I159J1393D01*
G02X1416626Y588959I2659J-1393D01*
G02X1419170Y588979I1293J-2709D01*
G02X1421670I1250J-2729D01*
G02Y583521I1250J-2729D01*
G37*
G36*
G01X1383791Y580643D02*
G03X1383671Y580041I191J-351D01*
G02X1381783Y580420I-1171J-941D01*
G03X1381903Y581022I-191J351D01*
G02X1383791Y580643I1171J941D01*
G37*
G36*
G01X1387033Y573799D02*
G03X1386472Y573745I-253J-309D01*
G02X1383971Y574036I-1156J960D01*
G03X1383379Y574182I-358J-178D01*
G02X1383845Y576069I-879J1218D01*
G03X1384437Y575923I358J178D01*
G02X1386269Y575866I879J-1218D01*
G03X1386830Y575920I253J309D01*
G02X1389073Y575997I1156J-960D01*
G03X1389642Y575987I289J276D01*
G02X1389662Y573965I981J-1001D01*
G03X1389093Y573945I-275J-291D01*
G02X1387033Y573799I-1107J1015D01*
G37*
G36*
G01X2602Y575579D02*
G03X2589Y575050I293J-272D01*
G02X337Y575104I-1150J-967D01*
G03X350Y575633I-293J272D01*
G02X368Y577587I1150J966D01*
G03Y578113I-302J263D01*
G02X2632I1132J987D01*
G03Y577587I302J-263D01*
G02X2602Y575579I-1132J-987D01*
G37*
G36*
G01X1377132Y574469D02*
G03Y573943I302J-263D01*
G02X1374868I-1132J-987D01*
G03Y574469I-302J263D01*
G02X1374859Y576432I1132J987D01*
G03X1374850Y576962I-304J260D01*
G02X1377102Y576997I1111J1011D01*
G03X1377111Y576467I304J-260D01*
G02X1377132Y574469I-1111J-1011D01*
G37*
G36*
G01X17285Y579272D02*
G03X17558Y578830I395J-61D01*
G02Y575970I-458J-1430D01*
G03X17285Y575528I122J-381D01*
G02X17284Y575068I-1485J-227D01*
G03X17566Y574623I395J-61D01*
G02X18271Y572196I-427J-1440D01*
G03Y571670I302J-263D01*
G02X16007I-1132J-987D01*
G03Y572196I-302J263D01*
G02X15655Y573415I1132J987D01*
G03X15373Y573860I-395J61D01*
G02X15342Y576730I427J1440D01*
G03X15615Y577172I-122J381D01*
G02Y577628I1485J228D01*
G03X15342Y578070I-395J61D01*
G02X15520Y580976I458J1430D01*
G03X15679Y581208I-38J196D01*
G02X15662Y581634I1477J272D01*
G03X15377Y582059I-398J41D01*
G02X15484Y584968I423J1441D01*
G03X15638Y585205I-42J196D01*
G02X15633Y585797I1470J308D01*
G03X15352Y586257I-393J76D01*
G02X15501Y589178I418J1443D01*
G03X15662Y589411I-36J197D01*
G02X17408Y588205I1477J272D01*
G03X17247Y587972I36J-197D01*
G02X17245Y587416I-1477J-273D01*
G03X17526Y586956I393J-76D01*
G02X17424Y584045I-418J-1443D01*
G03X17270Y583808I42J-196D01*
G02X17294Y583347I-1470J-308D01*
G03X17579Y582922I398J-41D01*
G02X17436Y580005I-423J-1441D01*
G03X17277Y579773I38J-196D01*
G02X17285Y579272I-1477J-274D01*
G37*
G36*
G01X4627Y568396D02*
G03X5173I273J292D01*
G02Y566204I1027J-1096D01*
G03X4627I-273J-292D01*
G02Y568396I-1027J1096D01*
G37*
G36*
G01X20421Y567710D02*
G03X20975I277J288D01*
G02X23037Y567583I973J-1010D01*
G03X23659I311J252D01*
G02Y565817I1089J-883D01*
G03X23037I-311J-252D01*
G02X20975Y565690I-1089J883D01*
G03X20421I-277J-288D01*
G02Y567710I-973J1010D01*
G37*
G36*
G01X1383118Y561641D02*
G03X1383081Y561073I262J-302D01*
G02X1381114Y561202I-1049J-930D01*
G03X1381151Y561770I-262J302D01*
G02X1383118Y561641I1049J930D01*
G37*
G36*
G01X34369Y558678D02*
G03X34923I277J288D01*
G02X36985Y558551I973J-1010D01*
G03X37607I311J252D01*
G02Y556785I1089J-883D01*
G03X36985I-311J-252D01*
G02X34923Y556658I-1089J883D01*
G03X34369I-277J-288D01*
G02Y558678I-973J1010D01*
G37*
G36*
G01X28825Y556680D02*
G03X28203I-311J-252D01*
G02Y558446I-1089J883D01*
G03X28825I311J252D01*
G02Y556680I1089J-883D01*
G37*
G36*
G01X2393Y555510D02*
G03X2416Y554924I283J-282D01*
G02X430Y554895I-977J-1141D01*
G03X436Y555482I-269J296D01*
G02X389Y555529I968J1015D01*
G03X-189I-289J-277D01*
G02Y557471I-1011J971D01*
G03X389I289J277D01*
G02X2393Y555510I1012J-971D01*
G37*
G36*
G01X715478Y540859D02*
G03X715034Y540526I-49J-397D01*
G02X712873Y541917I-1384J224D01*
G03Y542583I-222J333D01*
G02Y544917I777J1167D01*
G03Y545583I-222J333D01*
G02Y547917I777J1167D01*
G03Y548583I-222J333D01*
G02X713822Y551141I777J1167D01*
G03X714266Y551474I49J397D01*
G02X716427Y550083I1384J-224D01*
G03Y549417I222J-333D01*
G02Y547083I-777J-1167D01*
G03Y546417I222J-333D01*
G02Y544083I-777J-1167D01*
G03Y543417I222J-333D01*
G02X715478Y540859I-777J-1167D01*
G37*
G36*
G01X647073Y542165D02*
G03Y541535I246J-315D01*
G02X645227I-923J-1185D01*
G03Y542165I-246J315D01*
G02Y544535I923J1185D01*
G03Y545165I-246J315D01*
G02X647073I923J1185D01*
G03Y544535I246J-315D01*
G02Y542165I-923J-1185D01*
G37*
G36*
G01X1391434Y540655D02*
G03X1391428Y540051I259J-305D01*
G02X1389543Y540025I-928J-1051D01*
G03X1389521Y540629I-273J292D01*
G02X1391434Y540655I941J1171D01*
G37*
G36*
G01X2602Y539579D02*
G03X2589Y539050I293J-272D01*
G02X337Y539104I-1150J-967D01*
G03X350Y539633I-293J272D01*
G02X368Y541587I1150J966D01*
G03Y542113I-302J263D01*
G02X2632I1132J987D01*
G03Y541587I302J-263D01*
G02X2602Y539579I-1132J-987D01*
G37*
G36*
G01X1367792Y536427D02*
G03X1367238I-277J-288D01*
G02X1365244Y536476I-973J1010D01*
G03X1364669Y536483I-291J-274D01*
G02X1362701Y536461I-995J988D01*
G03X1362147I-277J-288D01*
G02X1360137Y536527I-973J1010D01*
G03X1359550Y536532I-296J-269D01*
G02X1357556Y536482I-1022J960D01*
G03X1357002I-277J-288D01*
G02X1355058Y536481I-973J1010D01*
G03X1354501Y536478I-277J-289D01*
G02X1354491Y538491I-981J1002D01*
G03X1355048Y538494I277J289D01*
G02X1355194Y538618I978J-1004D01*
G03X1355192Y538940I-120J160D01*
G02X1356991Y541083I827J1132D01*
G03X1357545I277J288D01*
G02X1359555Y541017I973J-1010D01*
G03X1360142Y541012I296J269D01*
G02X1362136Y541062I1022J-960D01*
G03X1362690I277J288D01*
G02X1364678Y541019I973J-1010D01*
G03X1365219Y540982I291J275D01*
G02X1367069Y540899I878J-1093D01*
G03X1367623I277J288D01*
G02X1369569I973J-1010D01*
G03X1370123I277J288D01*
G02X1372185Y539006I974J-1009D01*
G03X1372222Y538461I310J-253D01*
G02X1370292Y536427I-958J-1024D01*
G03X1369738I-277J-288D01*
G02X1367792I-973J1010D01*
G37*
G36*
G01X1377097Y534222D02*
G03X1376564Y534217I-264J-301D01*
G02X1374553Y536162I-942J1038D01*
G03X1374526Y536709I-305J259D01*
G02X1374446Y538641I974J1008D01*
G03X1374441Y539174I-301J264D01*
G02X1376452Y541127I1038J943D01*
G03X1377006I277J288D01*
G02X1378952I973J-1010D01*
G03X1379506I277J288D01*
G02X1381525Y539183I973J-1010D01*
G03Y538651I298J-266D01*
G02X1381526Y536785I-1046J-934D01*
G03X1381536Y536243I299J-266D01*
G02X1379548Y534266I-1015J-967D01*
G03X1378994I-277J-288D01*
G02X1377097Y534222I-972J1010D01*
G37*
G36*
G01X735027Y534190D02*
G03X734473I-277J-288D01*
G02X732490Y536173I-973J1010D01*
G03Y536727I-288J277D01*
G02X734473Y538710I1010J973D01*
G03X735027I277J288D01*
G02X737010Y536727I973J-1010D01*
G03Y536173I288J-277D01*
G02X735027Y534190I-1010J-973D01*
G37*
G36*
G01X27934Y533346D02*
G03X28466I266J298D01*
G02Y531254I934J-1046D01*
G03X27934I-266J-298D01*
G02Y533346I-934J1046D01*
G37*
G36*
G01X2636Y530282D02*
G03X2067Y530264I-276J-290D01*
G02X2004Y532236I-1027J954D01*
G03X2573Y532254I276J290D01*
G02X4611Y532271I1027J-954D01*
G03X5189I289J277D01*
G02Y530329I1011J-971D01*
G03X4611I-289J-277D01*
G02X2636Y530282I-1011J971D01*
G37*
G36*
G01X687517Y528591D02*
G02X685000Y527505I-1142J-813D01*
G02X683118Y532663I200J2995D01*
G02X685793Y533443I1382J238D01*
G02X687517Y528591I-593J-2943D01*
G37*
G36*
G01X702144Y523214D02*
G03X702156Y522612I270J-296D01*
G02X700311Y522574I-901J-1074D01*
G03X700299Y523176I-270J296D01*
G02X702144Y523214I901J1074D01*
G37*
G36*
G01X753730Y517369D02*
G03X753629Y516800I222J-333D01*
G02X751662Y517101I-1133J-826D01*
G03X751734Y517674I-239J321D01*
G02X751768Y519608I1166J947D01*
G03Y520134I-302J263D01*
G02X751505Y520563I1131J988D01*
G03X750997Y520790I-371J-149D01*
G02X751789Y522700I-479J1318D01*
G03X752309Y522502I362J169D01*
G02X754032Y520134I591J-1381D01*
G03Y519608I302J-263D01*
G02X753730Y517369I-1132J-987D01*
G37*
G36*
G01X63617Y519235D02*
G03X63596Y519857I-262J303D01*
G02X63343Y522008I907J1197D01*
G03X63317Y522545I-309J254D01*
G02X63282Y524631I1063J1061D01*
G03Y525177I-292J273D01*
G02X65087Y527527I1098J1025D01*
G03X65604Y527653I188J353D01*
G02X67972Y525813I1237J-852D01*
G03Y525287I302J-263D01*
G02X67864Y523201I-1132J-987D01*
G03X67853Y522919I136J-147D01*
G02X67882Y520913I-1103J-1019D01*
G03Y520387I302J-263D01*
G02Y518413I-1132J-987D01*
G03Y517887I302J-263D01*
G02X66485Y515422I-1132J-987D01*
G03X66032Y515148I-71J-394D01*
G02X63468Y516587I-1432J452D01*
G03Y517113I-302J263D01*
G02X63617Y519235I1132J987D01*
G37*
G36*
G01X1338529Y518605D02*
G02X1341188Y518347I1371J295D01*
G02X1338529Y518605I-1589J-2547D01*
G37*
G36*
G01X730615Y510466D02*
G03X730069Y510445I-262J-302D01*
G02X729985Y512634I-1069J1055D01*
G03X730531Y512655I262J302D01*
G02X730615Y510466I1069J-1055D01*
G37*
G36*
G01X721965Y510794D02*
G03X722143Y510299I373J-146D01*
G02X720014Y509530I-729J-1313D01*
G03X719836Y510025I-373J146D01*
G02X721965Y510794I729J1313D01*
G37*
G36*
G01X1334596Y506285D02*
G03X1334070Y505991I-135J-377D01*
G02X1331545Y507369I-1470J309D01*
G03X1331524Y507958I-281J285D01*
G02X1333976Y509381I976J1142D01*
G03X1334522Y509086I393J74D01*
G02X1334596Y506285I578J-1386D01*
G37*
G36*
G01X703472Y505634D02*
G03X702988Y505298I-88J-390D01*
G02X701828Y506966I-1488J202D01*
G03X702312Y507302I88J390D01*
G02X703472Y505634I1488J-202D01*
G37*
G36*
G01X712263Y504457D02*
G03X711711Y504440I-267J-298D01*
G02X709418Y504626I-1068J1056D01*
G03X708817Y504684I-326J-232D01*
G02X708954Y506564I-967J1015D01*
G03X709558Y506534I315J247D01*
G02X711708Y506555I1085J-1038D01*
G03X712260Y506540I284J282D01*
G02X714143Y506538I940J-1040D01*
G03X714724Y506585I268J296D01*
G02X714835Y504591I1176J-935D01*
G03X714252Y504573I-283J-283D01*
G02X712263Y504457I-1052J927D01*
G37*
G36*
G01X73515Y502952D02*
G03X73489Y503489I-309J254D01*
G02X75416Y505524I991J991D01*
G03X75975Y505547I268J297D01*
G02X78023Y505541I1021J-960D01*
G03X78608Y505540I293J272D01*
G02X80567Y503537I1021J-961D01*
G03X80516Y502998I268J-297D01*
G02X78474Y501098I-1116J-848D01*
G03X77941Y501094I-264J-301D01*
G02X76096Y501061I-941J1039D01*
G03X75564Y501046I-258J-306D01*
G02X73515Y502952I-964J1018D01*
G37*
G36*
G01X675615Y500166D02*
G03X675069Y500145I-262J-302D01*
G02X672968Y500109I-1069J1055D01*
G03X672442Y500130I-275J-290D01*
G02X672532Y502391I-942J1170D01*
G03X673058Y502370I275J290D01*
G02X674985Y502334I942J-1170D01*
G03X675531Y502355I262J302D01*
G02X675615Y500166I1069J-1055D01*
G37*
G36*
G01X648086Y500074D02*
G03X647702Y499680I16J-400D01*
G02X646139Y501201I-1502J20D01*
G03X646523Y501595I-16J400D01*
G02X648086Y500074I1502J-20D01*
G37*
G36*
G01X1269419Y500290D02*
G03X1269078Y499852I57J-396D01*
G02X1267374Y501181I-1494J-158D01*
G03X1267715Y501619I-57J396D01*
G02X1269419Y500290I1494J158D01*
G37*
G36*
G01X1336011Y498417D02*
G03X1335389I-311J-252D01*
G02Y500183I-1089J883D01*
G03X1336011I311J252D01*
G02Y498417I1089J-883D01*
G37*
G36*
G01X710329Y498366D02*
G03X709774Y498350I-269J-296D01*
G02X709710Y500512I-1074J1050D01*
G03X710265Y500528I269J296D01*
G02X710329Y498366I1074J-1050D01*
G37*
G36*
G01X1385071Y497791D02*
G03X1384469Y497731I-275J-291D01*
G02X1384322Y499638I-1228J864D01*
G03X1384925Y499671I287J278D01*
G02X1387049Y499777I1108J-860D01*
G03X1387629Y499778I290J276D01*
G02X1387579Y497767I1090J-1033D01*
G03X1387000Y497796I-303J-261D01*
G02X1385071Y497791I-967J1015D01*
G37*
G36*
G01X690059Y497029D02*
G03X689471Y496932I-251J-312D01*
G02X689143Y498907I-1269J804D01*
G03X689731Y499004I251J312D01*
G02X690059Y497029I1269J-804D01*
G37*
G36*
G01X1366733Y498513D02*
G03X1367320Y498523I289J277D01*
G02X1367304Y496541I1121J-1000D01*
G03X1366717Y496560I-302J-262D01*
G02X1364662Y496624I-998J985D01*
G03X1364049Y496613I-302J-262D01*
G02X1364056Y498490I-1169J943D01*
G03X1364669Y498474I313J249D01*
G02X1366733Y498513I1050J-929D01*
G37*
G36*
G01X-15685Y499063D02*
G03X-15671Y498494I288J-278D01*
G02X-17781Y498443I-1029J-1094D01*
G03X-17795Y499012I-288J278D01*
G02X-15685Y499063I1029J1094D01*
G37*
G36*
G01X977506Y498730D02*
G03X977514Y498168I289J-277D01*
G02X975465Y498082I-984J-998D01*
G03X975427Y498642I-303J261D01*
G02X975319Y498748I997J1123D01*
G03X974752Y498768I-293J-272D01*
G02X974771Y500799I-957J1025D01*
G03X975338Y500809I279J287D01*
G02X977506Y498730I1083J-1041D01*
G37*
G36*
G01X327889Y498735D02*
G03X327900Y498174I290J-275D01*
G02X325852Y498076I-978J-1004D01*
G03X325809Y498635I-306J258D01*
G02X325700Y498741I991J1129D01*
G03X325137Y498762I-292J-273D01*
G02X325157Y500805I-950J1031D01*
G03X325721Y500815I277J289D01*
G02X327889Y498735I1076J-1048D01*
G37*
G36*
G01X113190Y499013D02*
G03X113288Y498456I327J-230D01*
G02X111198Y498089I-861J-1231D01*
G03X111100Y498646I-327J230D01*
G02X113190Y499013I861J1231D01*
G37*
G36*
G01X1279133Y497801D02*
G03X1279720Y497660I355J184D01*
G02X1279262Y495746I875J-1221D01*
G03X1278675Y495887I-355J-184D01*
G02X1279133Y497801I-875J1221D01*
G37*
G36*
G01X928165Y497524D02*
G03X928151Y496941I267J-298D01*
G02X926179I-986J-997D01*
G03X926165Y497524I-281J285D01*
G02X928165I1000J1120D01*
G37*
G36*
G01X921700D02*
G03X921686Y496941I267J-298D01*
G02X919714I-986J-997D01*
G03X919700Y497524I-281J285D01*
G02X921700I1000J1120D01*
G37*
G36*
G01X276571Y496941D02*
G03X276557Y497524I-281J285D01*
G02X278557I1000J1120D01*
G03X278543Y496941I267J-298D01*
G02X276571I-986J-997D01*
G37*
G36*
G01X272092Y497524D02*
G03X272078Y496941I267J-298D01*
G02X270106I-986J-997D01*
G03X270092Y497524I-281J285D01*
G02X272092I1000J1120D01*
G37*
G36*
G01X883941Y497417D02*
G03X883925Y496856I277J-289D01*
G02X881875I-1025J-956D01*
G03X881859Y497417I-293J272D01*
G02X883941I1041J1083D01*
G37*
G36*
G01X234333D02*
G03X234317Y496856I277J-289D01*
G02X232267I-1025J-956D01*
G03X232251Y497417I-293J272D01*
G02X234333I1041J1083D01*
G37*
G36*
G01X1205441Y497404D02*
G03X1205425Y496843I277J-289D01*
G02X1203375I-1025J-956D01*
G03X1203359Y497404I-293J272D01*
G02X1205441I1041J1083D01*
G37*
G36*
G01X1145426D02*
G03X1145410Y496843I277J-289D01*
G02X1143360I-1025J-956D01*
G03X1143344Y497404I-293J272D01*
G02X1145426I1041J1083D01*
G37*
G36*
G01X1139033D02*
G03X1139017Y496843I277J-289D01*
G02X1136967I-1025J-956D01*
G03X1136951Y497404I-293J272D01*
G02X1139033I1041J1083D01*
G37*
G36*
G01X555833D02*
G03X555817Y496843I277J-289D01*
G02X553767I-1025J-956D01*
G03X553751Y497404I-293J272D01*
G02X555833I1041J1083D01*
G37*
G36*
G01X493752Y496843D02*
G03X493736Y497404I-293J272D01*
G02X495818I1041J1083D01*
G03X495802Y496843I277J-289D01*
G02X493752I-1025J-956D01*
G37*
G36*
G01X487359D02*
G03X487343Y497404I-293J272D01*
G02X489425I1041J1083D01*
G03X489409Y496843I277J-289D01*
G02X487359I-1025J-956D01*
G37*
G36*
G01X1199141Y497317D02*
G03X1199125Y496756I277J-289D01*
G02X1197075I-1025J-956D01*
G03X1197059Y497317I-293J272D01*
G02X1199141I1041J1083D01*
G37*
G36*
G01X1168512Y497368D02*
G03X1168495Y496788I267J-298D01*
G02X1166513Y496795I-995J-988D01*
G03X1166500Y497375I-282J284D01*
G02X1168512Y497368I1010J1112D01*
G37*
G36*
G01X1162381Y497335D02*
G03X1162345Y496756I257J-307D01*
G02X1160366Y496827I-1025J-956D01*
G03X1160372Y497408I-272J293D01*
G02X1162381Y497335I1045J1079D01*
G37*
G36*
G01X914794Y497379D02*
G03X914783Y496799I270J-295D01*
G02X912801Y496784I-983J-999D01*
G03X912782Y497364I-285J281D01*
G02X914794Y497379I998J1123D01*
G37*
G36*
G01X908055Y497339D02*
G03X908022Y496760I258J-305D01*
G02X906042Y496823I-1022J-960D01*
G03X906045Y497404I-274J292D01*
G02X908055Y497339I1041J1083D01*
G37*
G36*
G01X890161Y497583D02*
G03X890198Y497023I303J-261D01*
G02X888119Y496943I-998J-1123D01*
G03X888113Y497505I-288J278D01*
G02X890161Y497583I988J995D01*
G37*
G36*
G01X549533Y497317D02*
G03X549517Y496756I277J-289D01*
G02X547467I-1025J-956D01*
G03X547451Y497317I-293J272D01*
G02X549533I1041J1083D01*
G37*
G36*
G01X518904Y497368D02*
G03X518887Y496788I267J-298D01*
G02X516905Y496795I-995J-988D01*
G03X516892Y497375I-282J284D01*
G02X518904Y497368I1010J1112D01*
G37*
G36*
G01X512773Y497335D02*
G03X512737Y496756I257J-307D01*
G02X510758Y496827I-1025J-956D01*
G03X510764Y497408I-272J293D01*
G02X512773Y497335I1045J1079D01*
G37*
G36*
G01X265186Y497379D02*
G03X265175Y496799I270J-295D01*
G02X263193Y496784I-983J-999D01*
G03X263174Y497364I-285J281D01*
G02X265186Y497379I998J1123D01*
G37*
G36*
G01X258447Y497339D02*
G03X258414Y496760I258J-305D01*
G02X256434Y496823I-1022J-960D01*
G03X256437Y497404I-274J292D01*
G02X258447Y497339I1041J1083D01*
G37*
G36*
G01X240553Y497583D02*
G03X240590Y497023I303J-261D01*
G02X238511Y496943I-998J-1123D01*
G03X238505Y497505I-288J278D01*
G02X240553Y497583I988J995D01*
G37*
G36*
G01X1181441Y497304D02*
G03X1181425Y496743I277J-289D01*
G02X1179375I-1025J-956D01*
G03X1179359Y497304I-293J272D01*
G02X1181441I1041J1083D01*
G37*
G36*
G01X1175244D02*
G03X1175228Y496743I277J-289D01*
G02X1173178I-1025J-956D01*
G03X1173162Y497304I-293J272D01*
G02X1175244I1041J1083D01*
G37*
G36*
G01X531833D02*
G03X531817Y496743I277J-289D01*
G02X529767I-1025J-956D01*
G03X529751Y497304I-293J272D01*
G02X531833I1041J1083D01*
G37*
G36*
G01X525636D02*
G03X525620Y496743I277J-289D01*
G02X523570I-1025J-956D01*
G03X523554Y497304I-293J272D01*
G02X525636I1041J1083D01*
G37*
G36*
G01X948429Y496647D02*
G03X948443Y496064I281J-285D01*
G02X946443I-1000J-1120D01*
G03X946457Y496647I-267J298D01*
G02X948429I986J997D01*
G37*
G36*
G01X298821D02*
G03X298835Y496064I281J-285D01*
G02X296835I-1000J-1120D01*
G03X296849Y496647I-267J298D01*
G02X298821I986J997D01*
G37*
G36*
G01X955025Y496344D02*
G03X955041Y495783I293J-272D01*
G02X952959I-1041J-1083D01*
G03X952975Y496344I-277J289D01*
G02X955025I1025J956D01*
G37*
G36*
G01X305417D02*
G03X305433Y495783I293J-272D01*
G02X303351I-1041J-1083D01*
G03X303367Y496344I-277J289D01*
G02X305417I1025J956D01*
G37*
G36*
G01X1387075Y494670D02*
G03X1387658Y494664I294J271D01*
G02X1387584Y492665I1083J-1041D01*
G03X1387002Y492702I-308J-255D01*
G02X1385029Y492752I-961J1021D01*
G03X1384430Y492727I-288J-277D01*
G02X1384395Y494660I-1167J946D01*
G03X1384995Y494657I301J263D01*
G02X1387075Y494670I1046J-934D01*
G37*
G36*
G01X1209267Y495024D02*
G03X1209253Y494441I267J-298D01*
G02X1207281I-986J-997D01*
G03X1207267Y495024I-281J285D01*
G02X1209267I1000J1120D01*
G37*
G36*
G01X559659D02*
G03X559645Y494441I267J-298D01*
G02X557673I-986J-997D01*
G03X557659Y495024I-281J285D01*
G02X559659I1000J1120D01*
G37*
G36*
G01X894041Y494611D02*
G03X894025Y494050I277J-289D01*
G02X891975I-1025J-956D01*
G03X891959Y494611I-293J272D01*
G02X894041I1041J1083D01*
G37*
G36*
G01X242367Y494050D02*
G03X242351Y494611I-293J272D01*
G02X244433I1041J1083D01*
G03X244417Y494050I277J-289D01*
G02X242367I-1025J-956D01*
G37*
G36*
G01X1296357Y494363D02*
G03X1296909Y494322I297J268D01*
G02X1296737Y492145I969J-1172D01*
G03X1296185Y492191I-300J-265D01*
G02X1296357Y494363I-945J1168D01*
G37*
G36*
G01X1366738Y493709D02*
G03X1367321Y493723I285J281D01*
G02Y491723I1120J-1000D01*
G03X1366738Y491737I-298J-267D01*
G02X1364632Y491866I-997J986D01*
G03X1364005Y491874I-317J-245D01*
G02X1364068Y493690I-1164J949D01*
G03X1364693Y493655I326J231D01*
G02X1366738Y493709I1048J-932D01*
G37*
G36*
G01X694736Y493316D02*
G03Y492790I302J-263D01*
G02X692472I-1132J-987D01*
G03Y493316I-302J263D01*
G02X694736I1132J987D01*
G37*
G36*
G01X690957Y493268D02*
G03Y492742I302J-263D01*
G02X688693I-1132J-987D01*
G03Y493268I-302J263D01*
G02X690957I1132J987D01*
G37*
G36*
G01X918192Y492799D02*
G03X918178Y492216I267J-298D01*
G02X916206I-986J-997D01*
G03X916192Y492799I-281J285D01*
G02X918192I1000J1120D01*
G37*
G36*
G01X268584D02*
G03X268570Y492216I267J-298D01*
G02X266598I-986J-997D01*
G03X266584Y492799I-281J285D01*
G02X268584I1000J1120D01*
G37*
G36*
G01X1171656Y492724D02*
G03X1171642Y492141I267J-298D01*
G02X1169670I-986J-997D01*
G03X1169656Y492724I-281J285D01*
G02X1171656I1000J1120D01*
G37*
G36*
G01X924641Y492661D02*
G03X924625Y492100I277J-289D01*
G02X922575I-1025J-956D01*
G03X922559Y492661I-293J272D01*
G02X924641I1041J1083D01*
G37*
G36*
G01X522048Y492724D02*
G03X522034Y492141I267J-298D01*
G02X520062I-986J-997D01*
G03X520048Y492724I-281J285D01*
G02X522048I1000J1120D01*
G37*
G36*
G01X275033Y492661D02*
G03X275017Y492100I277J-289D01*
G02X272967I-1025J-956D01*
G03X272951Y492661I-293J272D01*
G02X275033I1041J1083D01*
G37*
G36*
G01X1165363Y492624D02*
G03X1165349Y492041I267J-298D01*
G02X1163377I-986J-997D01*
G03X1163363Y492624I-281J285D01*
G02X1165363I1000J1120D01*
G37*
G36*
G01X1142031Y492808D02*
G03X1142058Y492247I298J-267D01*
G02X1139977Y492207I-1020J-1103D01*
G03X1139981Y492768I-283J283D01*
G02X1142031Y492808I1006J976D01*
G37*
G36*
G01X911432Y492624D02*
G03X911418Y492041I267J-298D01*
G02X909446I-986J-997D01*
G03X909432Y492624I-281J285D01*
G02X911432I1000J1120D01*
G37*
G36*
G01X515755D02*
G03X515741Y492041I267J-298D01*
G02X513769I-986J-997D01*
G03X513755Y492624I-281J285D01*
G02X515755I1000J1120D01*
G37*
G36*
G01X492423Y492808D02*
G03X492450Y492247I298J-267D01*
G02X490369Y492207I-1020J-1103D01*
G03X490373Y492768I-283J283D01*
G02X492423Y492808I1006J976D01*
G37*
G36*
G01X261824Y492624D02*
G03X261810Y492041I267J-298D01*
G02X259838I-986J-997D01*
G03X259824Y492624I-281J285D01*
G02X261824I1000J1120D01*
G37*
G36*
G01X1178860Y492481D02*
G03X1178856Y491920I283J-283D01*
G02X1176806Y491880I-1006J-976D01*
G03X1176779Y492441I-298J267D01*
G02X1178860Y492481I1020J1103D01*
G37*
G36*
G01X529252D02*
G03X529248Y491920I283J-283D01*
G02X527198Y491880I-1006J-976D01*
G03X527171Y492441I-298J267D01*
G02X529252Y492481I1020J1103D01*
G37*
G36*
G01X1194104Y492426D02*
G03X1194088Y491865I277J-289D01*
G02X1192038I-1025J-956D01*
G03X1192022Y492426I-293J272D01*
G02X1192005Y494575I1041J1083D01*
G03Y495143I-282J284D01*
G02X1192063Y497329I1058J1066D01*
G03X1192077Y497912I-267J298D01*
G02X1194049I986J997D01*
G03X1194063Y497329I281J-285D01*
G02X1194121Y495143I-1000J-1120D01*
G03Y494575I282J-284D01*
G02X1194104Y492426I-1058J-1066D01*
G37*
G36*
G01X544496D02*
G03X544480Y491865I277J-289D01*
G02X542430I-1025J-956D01*
G03X542414Y492426I-293J272D01*
G02X542397Y494575I1041J1083D01*
G03Y495143I-282J284D01*
G02X542455Y497329I1058J1066D01*
G03X542469Y497912I-267J298D01*
G02X544441I986J997D01*
G03X544455Y497329I281J-285D01*
G02X544513Y495143I-1000J-1120D01*
G03Y494575I282J-284D01*
G02X544496Y492426I-1058J-1066D01*
G37*
G36*
G01X1157252Y492447D02*
G03X1157238Y491864I267J-298D01*
G02X1155266I-986J-997D01*
G03X1155252Y492447I-281J285D01*
G02X1155156Y494594I1000J1120D01*
G03Y495140I-292J273D01*
G02X1155252Y497287I1096J1027D01*
G03X1155266Y497870I-267J298D01*
G02X1157238I986J997D01*
G03X1157252Y497287I281J-285D01*
G02X1157348Y495140I-1000J-1120D01*
G03Y494594I292J-273D01*
G02X1157252Y492447I-1096J-1027D01*
G37*
G36*
G01X1152209Y492384D02*
G03X1152193Y491823I277J-289D01*
G02X1150143I-1025J-956D01*
G03X1150127Y492384I-293J272D01*
G02X1150110Y494533I1041J1083D01*
G03Y495101I-282J284D01*
G02X1150168Y497287I1058J1066D01*
G03X1150182Y497870I-267J298D01*
G02X1152154I986J997D01*
G03X1152168Y497287I281J-285D01*
G02X1152226Y495101I-1000J-1120D01*
G03Y494533I282J-284D01*
G02X1152209Y492384I-1058J-1066D01*
G37*
G36*
G01X507644Y492447D02*
G03X507630Y491864I267J-298D01*
G02X505658I-986J-997D01*
G03X505644Y492447I-281J285D01*
G02X505548Y494594I1000J1120D01*
G03Y495140I-292J273D01*
G02X505644Y497287I1096J1027D01*
G03X505658Y497870I-267J298D01*
G02X507630I986J997D01*
G03X507644Y497287I281J-285D01*
G02X507740Y495140I-1000J-1120D01*
G03Y494594I292J-273D01*
G02X507644Y492447I-1096J-1027D01*
G37*
G36*
G01X502601Y492384D02*
G03X502585Y491823I277J-289D01*
G02X500535I-1025J-956D01*
G03X500519Y492384I-293J272D01*
G02X500502Y494533I1041J1083D01*
G03Y495101I-282J284D01*
G02X500560Y497287I1058J1066D01*
G03X500574Y497870I-267J298D01*
G02X502546I986J997D01*
G03X502560Y497287I281J-285D01*
G02X502618Y495101I-1000J-1120D01*
G03Y494533I282J-284D01*
G02X502601Y492384I-1058J-1066D01*
G37*
G36*
G01X1185183Y492311D02*
G03X1185167Y491750I277J-289D01*
G02X1183117I-1025J-956D01*
G03X1183101Y492311I-293J272D01*
G02X1185183I1041J1083D01*
G37*
G36*
G01X1148356Y492538D02*
G03X1148372Y491977I293J-272D01*
G02X1146290I-1041J-1083D01*
G03X1146306Y492538I-277J289D01*
G02X1148356I1025J956D01*
G37*
G36*
G01X535575Y492311D02*
G03X535559Y491750I277J-289D01*
G02X533509I-1025J-956D01*
G03X533493Y492311I-293J272D01*
G02X535575I1041J1083D01*
G37*
G36*
G01X498748Y492538D02*
G03X498764Y491977I293J-272D01*
G02X496682I-1041J-1083D01*
G03X496698Y492538I-277J289D01*
G02X498748I1025J956D01*
G37*
G36*
G01X1202015Y492261D02*
G03X1201999Y491700I277J-289D01*
G02X1199949I-1025J-956D01*
G03X1199933Y492261I-293J272D01*
G02X1202015I1041J1083D01*
G37*
G36*
G01X552407D02*
G03X552391Y491700I277J-289D01*
G02X550341I-1025J-956D01*
G03X550325Y492261I-293J272D01*
G02X552407I1041J1083D01*
G37*
G36*
G01X951741Y492217D02*
G03X951725Y491656I277J-289D01*
G02X949675I-1025J-956D01*
G03X949659Y492217I-293J272D01*
G02X951741I1041J1083D01*
G37*
G36*
G01X887525Y492444D02*
G03X887541Y491883I293J-272D01*
G02X885459I-1041J-1083D01*
G03X885475Y492444I-277J289D01*
G02X887525I1025J956D01*
G37*
G36*
G01X302133Y492217D02*
G03X302117Y491656I277J-289D01*
G02X300067I-1025J-956D01*
G03X300051Y492217I-293J272D01*
G02X302133I1041J1083D01*
G37*
G36*
G01X235851Y491883D02*
G03X235867Y492444I-277J289D01*
G02X237917I1025J956D01*
G03X237933Y491883I293J-272D01*
G02X235851I-1041J-1083D01*
G37*
G36*
G01X939732Y492224D02*
G03X939718Y491641I267J-298D01*
G02X937746I-986J-997D01*
G03X937732Y492224I-281J285D01*
G02X937636Y494371I1000J1120D01*
G03Y494917I-292J273D01*
G02X937732Y497064I1096J1027D01*
G03X937746Y497647I-267J298D01*
G02X939718I986J997D01*
G03X939732Y497064I281J-285D01*
G02X939828Y494917I-1000J-1120D01*
G03Y494371I292J-273D01*
G02X939732Y492224I-1096J-1027D01*
G37*
G36*
G01X934623Y497652D02*
G03X934641Y497070I283J-283D01*
G02X934743Y494917I-994J-1126D01*
G03Y494371I292J-273D01*
G02X934641Y492218I-1096J-1027D01*
G03X934623Y491636I265J-299D01*
G02X932652Y491646I-991J-992D01*
G03X932640Y492229I-280J286D01*
G02X932551Y494371I1007J1115D01*
G03Y494917I-292J273D01*
G02X932640Y497059I1096J1027D01*
G03X932652Y497642I-268J297D01*
G02X934623Y497652I980J1002D01*
G37*
G36*
G01X930852Y492161D02*
G03X930836Y491600I277J-289D01*
G02X928786I-1025J-956D01*
G03X928770Y492161I-293J272D01*
G02X930852I1041J1083D01*
G37*
G36*
G01X288138Y491641D02*
G03X288124Y492224I-281J285D01*
G02X288028Y494371I1000J1120D01*
G03Y494917I-292J273D01*
G02X288124Y497064I1096J1027D01*
G03X288138Y497647I-267J298D01*
G02X290110I986J997D01*
G03X290124Y497064I281J-285D01*
G02X290220Y494917I-1000J-1120D01*
G03Y494371I292J-273D01*
G02X290124Y492224I-1096J-1027D01*
G03X290110Y491641I267J-298D01*
G02X288138I-986J-997D01*
G37*
G36*
G01X285033Y492218D02*
G03X285015Y491636I265J-299D01*
G02X283044Y491646I-991J-992D01*
G03X283032Y492229I-280J286D01*
G02X282943Y494371I1007J1115D01*
G03Y494917I-292J273D01*
G02X283032Y497059I1096J1027D01*
G03X283044Y497642I-268J297D01*
G02X285015Y497652I980J1002D01*
G03X285033Y497070I283J-283D01*
G02X285135Y494917I-994J-1126D01*
G03Y494371I292J-273D01*
G02X285033Y492218I-1096J-1027D01*
G37*
G36*
G01X281244Y492161D02*
G03X281228Y491600I277J-289D01*
G02X279178I-1025J-956D01*
G03X279162Y492161I-293J272D01*
G02X281244I1041J1083D01*
G37*
G36*
G01X1189019Y492126D02*
G03X1189003Y491565I277J-289D01*
G02X1186953I-1025J-956D01*
G03X1186937Y492126I-293J272D01*
G02X1186920Y494275I1041J1083D01*
G03Y494843I-282J284D01*
G02X1186978Y497029I1058J1066D01*
G03X1186992Y497612I-267J298D01*
G02X1188964I986J997D01*
G03X1188978Y497029I281J-285D01*
G02X1189036Y494843I-1000J-1120D01*
G03Y494275I282J-284D01*
G02X1189019Y492126I-1058J-1066D01*
G37*
G36*
G01X539411D02*
G03X539395Y491565I277J-289D01*
G02X537345I-1025J-956D01*
G03X537329Y492126I-293J272D01*
G02X537312Y494275I1041J1083D01*
G03Y494843I-282J284D01*
G02X537370Y497029I1058J1066D01*
G03X537384Y497612I-267J298D01*
G02X539356I986J997D01*
G03X539370Y497029I281J-285D01*
G02X539428Y494843I-1000J-1120D01*
G03Y494275I282J-284D01*
G02X539411Y492126I-1058J-1066D01*
G37*
G36*
G01X1258024Y491691D02*
G03X1257734Y491166I87J-390D01*
G02X1256064Y492140I-1414J-506D01*
G03X1256379Y492651I-68J394D01*
G02X1258024Y491691I1341J409D01*
G37*
G36*
G01X902921Y492094D02*
G03X902907Y491511I267J-298D01*
G02X900935I-986J-997D01*
G03X900921Y492094I-281J285D01*
G02X900825Y494241I1000J1120D01*
G03Y494787I-292J273D01*
G02X900921Y496934I1096J1027D01*
G03X900935Y497517I-267J298D01*
G02X902907I986J997D01*
G03X902921Y496934I281J-285D01*
G02X903017Y494787I-1000J-1120D01*
G03Y494241I292J-273D01*
G02X902921Y492094I-1096J-1027D01*
G37*
G36*
G01X897817Y492072D02*
G03X897791Y491490I261J-303D01*
G02X895816Y491528I-1007J-976D01*
G03X895813Y492110I-276J290D01*
G02X895778Y494275I1023J1099D01*
G03Y494843I-282J284D01*
G02X895776Y496973I1058J1066D01*
G03X895781Y497536I-282J284D01*
G02X897827Y497576I1004J978D01*
G03X897853Y497014I297J-268D01*
G02X897894Y494843I-1017J-1105D01*
G03Y494275I282J-284D01*
G02X897817Y492072I-1058J-1066D01*
G37*
G36*
G01X253313Y492094D02*
G03X253299Y491511I267J-298D01*
G02X251327I-986J-997D01*
G03X251313Y492094I-281J285D01*
G02X251217Y494241I1000J1120D01*
G03Y494787I-292J273D01*
G02X251313Y496934I1096J1027D01*
G03X251327Y497517I-267J298D01*
G02X253299I986J997D01*
G03X253313Y496934I281J-285D01*
G02X253409Y494787I-1000J-1120D01*
G03Y494241I292J-273D01*
G02X253313Y492094I-1096J-1027D01*
G37*
G36*
G01X248209Y492072D02*
G03X248183Y491490I261J-303D01*
G02X246208Y491528I-1007J-976D01*
G03X246205Y492110I-276J290D01*
G02X246170Y494275I1023J1099D01*
G03Y494843I-282J284D01*
G02X246168Y496973I1058J1066D01*
G03X246173Y497536I-282J284D01*
G02X248219Y497576I1004J978D01*
G03X248245Y497014I297J-268D01*
G02X248286Y494843I-1017J-1105D01*
G03Y494275I282J-284D01*
G02X248209Y492072I-1058J-1066D01*
G37*
G36*
G01X944974Y491957D02*
G03X944937Y491384I260J-304D01*
G02X942933Y491462I-1040J-940D01*
G03X942940Y492036I-275J290D01*
G02X944974Y491957I1060J1064D01*
G37*
G36*
G01X295366D02*
G03X295329Y491384I260J-304D01*
G02X293325Y491462I-1040J-940D01*
G03X293332Y492036I-275J290D01*
G02X295366Y491957I1060J1064D01*
G37*
G36*
G01X675905Y488413D02*
G03X675343Y488419I-284J-282D01*
G02X675423Y490498I-1043J1081D01*
G03X675983Y490461I299J266D01*
G02X677989Y490283I917J-1061D01*
G03X678611I311J252D01*
G02Y488517I1089J-883D01*
G03X677989I-311J-252D01*
G02X675905Y488413I-1089J883D01*
G37*
G36*
G01X1249993Y490037D02*
G03X1249842Y489533I213J-338D01*
G02X1247674Y490184I-1368J-620D01*
G03X1247825Y490688I-213J338D01*
G02X1249993Y490037I1368J620D01*
G37*
G36*
G01X1384569Y488374D02*
G03X1385157Y488363I299J265D01*
G02X1385068Y486385I1084J-1040D01*
G03X1384481Y486426I-312J-250D01*
G02X1382475Y486509I-963J1019D01*
G03X1381875Y486504I-298J-267D01*
G02X1381906Y488437I-1134J985D01*
G03X1382505Y488413I310J253D01*
G02X1384569Y488374I1014J-968D01*
G37*
G36*
G01X1270829Y486076D02*
G03X1270262Y485945I-222J-333D01*
G02X1269767Y487855I-1212J705D01*
G03X1270327Y488015I205J343D01*
G02X1270829Y486076I1335J-689D01*
G37*
G36*
G01X721918Y486830D02*
G03X721707Y486326I164J-365D01*
G02X719683Y487170I-1407J-526D01*
G03X719894Y487674I-164J365D01*
G02X721903Y489576I1407J526D01*
G03X722427Y489775I161J366D01*
G02X723190Y487772I1365J-627D01*
G03X722666Y487573I-161J-366D01*
G02X721918Y486830I-1365J627D01*
G37*
G36*
G01X676738Y484538D02*
G03X676166Y484532I-283J-282D01*
G02X676142Y486632I-1086J1038D01*
G03X676714Y486638I283J282D01*
G02X678742Y486770I1086J-1038D01*
G03X679268Y486791I251J311D01*
G02X679358Y484530I1032J-1091D01*
G03X678832Y484509I-251J-311D01*
G02X676738Y484538I-1032J1091D01*
G37*
G36*
G01X610496Y485157D02*
G03X611028Y485145I273J293D01*
G02X610974Y482903I972J-1145D01*
G03X610442Y482915I-273J-293D01*
G02X610496Y485157I-972J1145D01*
G37*
G36*
G01X1256886Y484677D02*
G03X1256664Y484137I142J-374D01*
G02X1254822Y484840I-1276J-580D01*
G03X1255016Y485390I-161J366D01*
G02X1256886Y484677I1334J690D01*
G37*
G36*
G01X709160Y482443D02*
G03X708607Y482412I-260J-304D01*
G02X708488Y484579I-1096J1027D01*
G03X709041Y484610I260J304D01*
G02X709160Y482443I1096J-1027D01*
G37*
G36*
G01X1382632Y481490D02*
G03X1382079I-277J-289D01*
G02X1382138Y483601I-1038J1085D01*
G03X1382690Y483570I292J273D01*
G02X1384528Y483555I910J-1066D01*
G03X1385097Y483596I264J300D01*
G02X1385189Y481551I1144J-973D01*
G03X1384618Y481540I-280J-286D01*
G02X1382632Y481490I-1018J964D01*
G37*
G36*
G01X1291632Y481713D02*
G03Y481187I302J-263D01*
G02X1289368I-1132J-987D01*
G03Y481713I-302J263D01*
G02X1291632I1132J987D01*
G37*
G36*
G01X1270997Y480678D02*
G03X1271240Y480465I199J-18D01*
G02X1270069Y478999I331J-1465D01*
G01Y479000D01*
G03X1269654Y479399I-400J-1D01*
G02X1269715Y482197I-55J1401D01*
G03X1270147Y482576I32J399D01*
G02X1271253Y481050I1500J-76D01*
G03X1271001Y480850I-52J-193D01*
G02X1270997Y480678I-1401J-53D01*
G37*
G36*
G01X1320664Y478550D02*
G03X1321208Y478564I264J300D01*
G02X1321204Y476424I1052J-1072D01*
G03X1320660Y476441I-281J-285D01*
G02X1320664Y478550I-922J1056D01*
G37*
G36*
G01X13539Y474346D02*
G03X13007Y474329I-256J-307D01*
G02X12933Y476571I-1035J1088D01*
G03X13465Y476588I256J307D01*
G02X13539Y474346I1035J-1088D01*
G37*
G36*
G01X1256580Y475699D02*
G03X1257145Y475665I299J265D01*
G02X1256963Y473607I995J-1125D01*
G03X1256401Y473672I-314J-249D01*
G02X1256580Y475699I-871J1098D01*
G37*
G36*
G01X1321355Y471476D02*
G03X1320779Y471433I-267J-298D01*
G02X1320582Y473416I-1080J894D01*
G03X1321155Y473488I252J311D01*
G02X1321355Y471476I1205J-896D01*
G37*
G36*
G01X-13433Y472543D02*
G03X-13555Y471963I202J-345D01*
G02X-15455Y472315I-1135J-823D01*
G03X-15362Y472900I-219J335D01*
G02X-13124Y474898I1171J941D01*
G03X-12556I284J282D01*
G02Y472782I1066J-1058D01*
G03X-13124I-284J-282D01*
G02X-13433Y472543I-1066J1058D01*
G37*
G36*
G01X1327785Y470347D02*
G03X1328334Y470375I260J304D01*
G02X1328382Y468250I1085J-1039D01*
G03X1327833Y468254I-277J-289D01*
G02X1327785Y470347I-956J1025D01*
G37*
G36*
G01X3788Y468295D02*
G03X3213Y468421I-345J-202D01*
G02X3684Y470340I-863J1229D01*
G03X4252Y470186I355J184D01*
G02X3788Y468295I748J-1186D01*
G37*
G36*
G01X1257966Y468047D02*
G03X1257526Y467687I-42J-398D01*
G02X1256204Y469220I-1396J133D01*
G03X1256625Y469603I21J399D01*
G02X1257966Y468047I1501J-63D01*
G37*
G36*
G01X582851Y467547D02*
G03X582433Y467160I-18J-400D01*
G02X581093Y468603I-1401J42D01*
G03X581511Y468990I18J400D01*
G02X582851Y467547I1401J-42D01*
G37*
G36*
G01X619041Y464629D02*
G03X618801Y465180I-362J170D01*
G02X618314Y467777I459J1430D01*
G03X618342Y468374I-251J311D01*
G02X620336Y468283I1048J1076D01*
G03X620308Y467686I251J-311D01*
G02X620619Y465971I-1048J-1076D01*
G03X620859Y465420I362J-170D01*
G02X619041Y464629I-459J-1430D01*
G37*
G36*
G01X1343063Y462534D02*
G03X1342510Y462527I-273J-292D01*
G02X1342427Y464604I-982J1001D01*
G03X1342979Y464641I257J307D01*
G02X1345197Y464645I1111J-1011D01*
G03X1345769Y464627I295J270D01*
G02X1345757Y462614I970J-1012D01*
G03X1345185Y462602I-280J-285D01*
G02X1343063Y462534I-1095J1028D01*
G37*
G36*
G01X575657Y460293D02*
G03X575269Y459895I12J-400D01*
G02X573824Y461304I-1402J8D01*
G03X574212Y461702I-12J400D01*
G02X575657Y460293I1402J-8D01*
G37*
G36*
G01X1378802Y457185D02*
G03X1378191Y457175I-301J-263D01*
G02X1378202Y459061I-1163J950D01*
G03X1378813Y459044I313J250D01*
G02X1378802Y457185I1044J-936D01*
G37*
G36*
G01X1685535Y458399D02*
G03Y457854I293J-272D01*
G02X1683335I-1100J-1022D01*
G03Y458399I-293J272D01*
G02X1685535I1100J1022D01*
G37*
G36*
G01X1676975Y457708D02*
G03X1676913Y457143I249J-313D01*
G02X1674810Y457376I-1169J-943D01*
G03X1674872Y457941I-249J313D01*
G02X1676975Y457708I1169J943D01*
G37*
G36*
G01X1840514Y453316D02*
G03X1839895Y453286I-297J-268D01*
G02X1839767Y455103I-1127J834D01*
G03X1840384Y455160I285J281D01*
G02X1842815Y455244I1246J-839D01*
G03X1843445I315J246D01*
G02X1845677Y455398I1185J-923D01*
G03X1846228Y455393I278J287D01*
G02X1846267Y453309I957J-1024D01*
G03X1845716Y453283I-262J-302D01*
G02X1843445Y453398I-1086J1038D01*
G03X1842815I-315J-246D01*
G02X1840514Y453316I-1185J923D01*
G37*
G36*
G01X34016Y453011D02*
G03X33427Y453045I-310J-253D01*
G02X33534Y454939I-977J1005D01*
G03X34123Y454905I310J253D01*
G02X34016Y453011I977J-1005D01*
G37*
G36*
G01X1412503Y453247D02*
G03X1411898Y453052I-228J-329D01*
G02X1408964Y453561I-1423J510D01*
G01Y457561D01*
G02X1411565Y458608I1511J0D01*
G03X1412124Y458592I288J278D01*
G02X1413829Y456379I950J-1031D01*
G03X1413878Y455677I214J-338D01*
G02X1412503Y453247I-577J-1278D01*
G37*
G36*
G01X1404424Y452530D02*
G03X1403865Y452514I-271J-294D01*
G02X1401264Y453561I-1090J1047D01*
G01Y457561D01*
G02X1404191Y458091I1511J0D01*
G03X1404797Y457904I375J139D01*
G02X1404891Y455556I811J-1143D01*
G03X1404286Y455213I-205J-344D01*
G01Y454894D01*
G03X1404597Y454728I200J0D01*
G02X1404424Y452530I778J-1167D01*
G37*
G36*
G01X1396886Y455896D02*
Y455067D01*
G03X1397506Y454733I400J0D01*
G02X1397201Y452659I769J-1172D01*
G03X1396577Y452645I-306J-257D01*
G02X1393864Y453561I-1202J916D01*
G01Y457562D01*
G02X1396465Y458608I1511J-1D01*
G03X1397024Y458592I288J278D01*
G02X1397439Y456265I951J-1031D01*
G03X1396886Y455896I-153J-370D01*
G37*
G36*
G01X1682201Y450789D02*
G03X1682187Y450234I281J-285D01*
G02X1680168Y450283I-1033J-948D01*
G03X1680182Y450838I-281J285D01*
G02X1680196Y452749I1033J948D01*
G03X1680191Y453304I-290J275D01*
G02X1682211Y453323I1001J982D01*
G03X1682216Y452768I290J-275D01*
G02X1682201Y450789I-1001J-982D01*
G37*
G36*
G01X1677412Y448780D02*
G03X1677408Y448243I295J-271D01*
G02X1675179Y448258I-1121J-999D01*
G03X1675183Y448795I-295J271D01*
G02X1677412Y448780I1121J999D01*
G37*
G36*
G01X-15859Y446824D02*
G03X-15841Y447426I-254J309D01*
G02X-13489Y449585I1088J1175D01*
G03X-12870Y449571I315J246D01*
G02X-10591Y447330I1218J-1041D01*
G03Y446730I265J-300D01*
G02X-12945Y444584I-1061J-1200D01*
G03X-13582Y444595I-323J-236D01*
G02X-15859Y446824I-1257J994D01*
G37*
G36*
G01X1719804Y443854D02*
G03X1719976Y443297I348J-198D01*
G02X1718052Y442757I-659J-1350D01*
G03X1717909Y443323I-337J216D01*
G02X1717595Y443559I677J1228D01*
G03X1717029I-283J-282D01*
G02Y445541I-992J991D01*
G03X1717595I283J282D01*
G02X1719804Y443854I992J-991D01*
G37*
G36*
G01X1413434Y442480D02*
G03X1413457Y441892I282J-283D01*
G02X1411425Y441813I-973J-1144D01*
G03X1411402Y442401I-282J283D01*
G02X1413434Y442480I973J1144D01*
G37*
G36*
G01X750525Y439327D02*
G03X749900Y438975I-226J-330D01*
G02X747354Y439707I-1400J-75D01*
G03X747221Y440287I-327J230D01*
G02X748465Y443011I729J1313D01*
G03X748991Y443294I137J376D01*
G02X750525Y439327I3650J-869D01*
G37*
G36*
G01X1409123Y439924D02*
G03Y439309I257J-307D01*
G02X1407327I-898J-1076D01*
G03Y439924I-257J307D01*
G02X1409123I898J1076D01*
G37*
G36*
G01X777237Y435326D02*
G03X776669Y435167I-211J-339D01*
G02X776159Y436989I-1252J632D01*
G03X776727Y437148I211J339D01*
G02X777237Y435326I1252J-632D01*
G37*
G36*
G01X86933Y434771D02*
G03X86513Y434391I-21J-399D01*
G02X84993Y436071I-1600J80D01*
G03X85413Y436451I21J399D01*
G02X86933Y434771I1600J-80D01*
G37*
G36*
G01X747092Y431907D02*
G03X747088Y431287I251J-312D01*
G02X745189Y431300I-957J-1157D01*
G03X745193Y431920I-251J312D01*
G02X747092Y431907I957J1157D01*
G37*
G36*
G01X1410949Y428744D02*
G03X1410390Y428728I-271J-294D01*
G02X1407788Y429775I-1090J1047D01*
G01Y434776D01*
G02X1410390Y435822I1512J-1D01*
G03X1410949Y435806I288J278D01*
G02X1411364Y433479I951J-1031D01*
G03X1410812Y433110I-152J-369D01*
G01Y431440D01*
G03X1411364Y431071I400J0D01*
G02X1410949Y428744I536J-1296D01*
G37*
G36*
G01X62516Y427333D02*
Y425934D01*
G03X63075Y425567I400J0D01*
G02X62659Y423268I555J-1288D01*
G03X62094Y423257I-277J-288D01*
G02X59494Y424305I-1089J1048D01*
G01Y429306D01*
G02X62214Y430212I1511J-1D01*
G03X62770Y430130I320J241D01*
G02X63068Y427703I830J-1130D01*
G03X62516Y427333I-152J-370D01*
G37*
G36*
G01X37670Y423903D02*
G03X37302Y423503I32J-399D01*
G02X35707Y424889I-1402J-3D01*
G03X36051Y425309I-55J396D01*
G02X37670Y423903I1499J91D01*
G37*
G36*
G01X79664Y426541D02*
G03X79943Y427021I-109J385D01*
G02X81936Y425859I1556J379D01*
G03X81657Y425379I109J-385D01*
G02X80020Y423400I-1557J-379D01*
G03X79600Y423020I-21J-399D01*
G02X78038Y421498I-1600J80D01*
G03X77649Y421066I9J-400D01*
G02X76014Y422537I-1597J-131D01*
G03X76403Y422969I-9J400D01*
G02X78080Y424700I1597J131D01*
G03X78500Y425080I21J399D01*
G02X79664Y426541I1600J-80D01*
G37*
G36*
G01X1408670Y416490D02*
X1408660Y416406D01*
G02X1406068Y415528I-1502J169D01*
G03X1405509Y415544I-288J-278D01*
G02X1405094Y417871I-951J1031D01*
G03X1405646Y418240I152J369D01*
G01Y419910D01*
G03X1405094Y420279I-400J0D01*
G02X1405509Y422606I-536J1296D01*
G03X1406068Y422622I271J294D01*
G02X1408670Y421585I1090J-1047D01*
G01Y416490D01*
G37*
G36*
G01X1414187Y415755D02*
G03X1413637Y415626I-210J-340D01*
G02X1412950Y417677I-1190J742D01*
G03X1413493Y418037I143J373D01*
G01X1413568Y420270D01*
G03X1413030Y420658I-400J13D01*
G02X1413507Y422994I-485J1316D01*
G03X1414067Y423005I274J291D01*
G02X1416647Y422124I1079J-1059D01*
G01X1416668Y421948D01*
X1416504Y417042D01*
X1416505D01*
X1416502Y416988D01*
X1416477Y416817D01*
G02X1414187Y415755I-1495J223D01*
G37*
G36*
G01X47064Y415253D02*
G03X47079Y414659I275J-290D01*
G02X45121I-979J-1139D01*
G03X45136Y415253I-260J304D01*
G02X47064I964J1018D01*
G37*
G36*
G01X1403912Y409757D02*
Y411742D01*
G03X1403291Y412075I-400J-1D01*
G02X1403584Y414159I-771J1171D01*
G03X1404209Y414181I304J260D01*
G02X1406934Y413291I1214J-900D01*
G01Y408196D01*
X1406925Y408112D01*
G02X1404351Y407216I-1502J169D01*
G03X1403769Y407201I-284J-282D01*
G02X1403337Y409397I-1044J935D01*
G03X1403912Y409757I175J360D01*
G37*
G36*
G01X77640Y409384D02*
G03X78099Y409764I59J395D01*
G02X79571Y411297I1601J-64D01*
G03X79931Y411776I-32J399D01*
G02X81629Y410503I1569J324D01*
G03X81269Y410024I32J-399D01*
G02X79460Y408116I-1569J-324D01*
G03X79001Y407736I-59J-395D01*
G02X77640Y409384I-1601J64D01*
G37*
G36*
G01X52969Y404812D02*
G03X52380Y404909I-338J-214D01*
G02X52752Y406631I-880J1091D01*
G03X53084Y406593I179J90D01*
G02X53088Y406598I1182J-941D01*
G01X55227Y409137D01*
G02X55949Y409611I1156J-974D01*
G03X56198Y410162I-114J383D01*
G02X57941Y409428I1273J587D01*
G03X57721Y408866I134J-377D01*
G02X57894Y408173I-1338J-702D01*
G01Y408078D01*
X57885Y407994D01*
G02X57539Y407189I-1503J169D01*
G01X56228Y405632D01*
X56227D01*
X55422Y404678D01*
X55421Y404676D01*
G02X52969Y404812I-1177J948D01*
G37*
G36*
G01X66839Y403667D02*
G03X67332Y403390I385J108D01*
G02X66385Y401582I378J-1350D01*
G03X65877Y401829I-378J-131D01*
G02X64311Y402193I-493J1429D01*
G01X61973Y404550D01*
X61972Y404551D01*
G02X62537Y407067I1052J1085D01*
G03X62763Y407630I-129J379D01*
G02X64573Y406993I1244J646D01*
G03X64450Y406345I161J-366D01*
G01X65153Y405638D01*
X66457Y404323D01*
G02X66839Y403667I-1073J-1064D01*
G37*
G36*
G01X77580Y398573D02*
G03X78100I260J304D01*
G02X79889Y398771I1040J-1218D01*
G03X80440Y398960I187J354D01*
G02X81151Y396884I1460J-660D01*
G03X80600Y396695I-187J-354D01*
G02X78100Y396137I-1460J660D01*
G03X77580I-260J-304D01*
G02Y398573I-1040J1218D01*
G37*
G36*
G01X66806Y392960D02*
G02X66435Y390673I594J-1270D01*
G03X65860Y390647I-275J-291D01*
G02X63214Y391645I-1135J998D01*
G01Y396645D01*
G02X65481Y397954I1511J0D01*
G03X66025Y398096I200J346D01*
G02X66768Y396056I1205J-716D01*
G03X66236Y395679I-132J-378D01*
G01Y393322D01*
G03X66806Y392960I400J0D01*
G37*
G36*
G01X1662244Y389244D02*
G03X1662179Y388723I267J-298D01*
G02X1659933Y389003I-1245J-840D01*
G03X1659998Y389524I-267J298D01*
G02X1660139Y391382I1245J840D01*
G03Y391925I-294J271D01*
G02X1662347I1104J1018D01*
G03Y391382I294J-271D01*
G02X1662244Y389244I-1104J-1018D01*
G37*
G36*
G01X680410Y387607D02*
G03X680439Y386998I273J-292D01*
G02X678498Y386906I-916J-1190D01*
G03X678469Y387515I-273J292D01*
G02X680410Y387607I916J1190D01*
G37*
G36*
G01X61723Y381799D02*
G03X61642Y381177I206J-343D01*
G02X59846Y381450I-1078J-1046D01*
G03X59953Y382067I-191J351D01*
G02X61723Y381799I1047J933D01*
G37*
G36*
G01X1665990Y378242D02*
G03X1666006Y377716I310J-254D01*
G02X1663744Y377647I-1101J-1021D01*
G03X1663728Y378173I-310J254D01*
G02X1665990Y378242I1101J1021D01*
G37*
G36*
G01X49372Y358259D02*
G03X48838Y358324I-303J-261D01*
G02X49108Y360531I-868J1226D01*
G03X49642Y360466I303J261D01*
G02X49372Y358259I868J-1226D01*
G37*
G36*
G01X73727Y320826D02*
G03X73126Y320844I-308J-255D01*
G02X71014Y320913I-1026J956D01*
G03X70437Y320957I-309J-253D01*
G02X68544Y320975I-937J1043D01*
G03X67983Y320959I-272J-293D01*
G02Y323041I-1083J1041D01*
G03X68544Y323025I289J277D01*
G02X70586Y322887I956J-1025D01*
G03X71163Y322843I309J253D01*
G02X73139Y322741I937J-1043D01*
G03X73741Y322751I297J268D01*
G02X76317Y322238I1146J-971D01*
G03X76898Y322014I381J122D01*
G02X76285Y320315I702J-1213D01*
G03X75694Y320513I-375J-139D01*
G02X73727Y320826I-807J1267D01*
G37*
G36*
G01X82999Y315101D02*
G03X82422Y315094I-285J-280D01*
G02X82449Y317114I-1098J1025D01*
G03X83026Y317092I299J265D01*
G02X82999Y315101I974J-1009D01*
G37*
G36*
G01X65096Y315473D02*
G03Y314927I292J-273D01*
G02X62904I-1096J-1027D01*
G03Y315473I-292J273D01*
G02X65096I1096J1027D01*
G37*
G36*
G01X4991Y303270D02*
G03X5621I315J246D01*
G02Y301424I1185J-923D01*
G03X4991I-315J-246D01*
G02Y303270I-1185J923D01*
G37*
G36*
G01X57545Y298269D02*
G03X57566Y298815I-281J284D01*
G02X57690Y300912I1134J985D01*
G03X57669Y301521I-269J296D01*
G02X59610Y301588I931J1179D01*
G03X59631Y300979I269J-296D01*
G02X59755Y298731I-931J-1179D01*
G03X59734Y298185I281J-284D01*
G02X57545Y298269I-1134J-985D01*
G37*
G36*
G01X49683Y291311D02*
G03Y290689I252J-311D01*
G02X47917I-883J-1089D01*
G03Y291311I-252J311D01*
G02X49683I883J1089D01*
G37*
G36*
G01X49810Y284127D02*
G03Y283573I288J-277D01*
G02X47790I-1010J-973D01*
G03Y284127I-288J277D01*
G02X49810I1010J973D01*
G37*
G36*
G01X69327Y282696D02*
G03X69873I273J292D01*
G02Y280504I1027J-1096D01*
G03X69327I-273J-292D01*
G02Y282696I-1027J1096D01*
G37*
G36*
G01X61013Y276868D02*
G03X60487I-263J-302D01*
G02Y279132I-987J1132D01*
G03X61013I263J302D01*
G02Y276868I987J-1132D01*
G37*
G36*
G01X1658523Y276344D02*
G03X1658539Y275783I293J-272D01*
G02X1656457I-1041J-1083D01*
G03X1656473Y276344I-277J289D01*
G02Y278256I1025J956D01*
G03X1656457Y278817I-293J272D01*
G02X1658539I1041J1083D01*
G03X1658523Y278256I277J-289D01*
G02Y276344I-1025J-956D01*
G37*
G36*
G01X1658585Y266214D02*
G03X1658616Y265675I310J-253D01*
G02X1656461Y265616I-1049J-1075D01*
G03X1656462Y266156I-295J271D01*
G02X1656473Y268056I1036J944D01*
G03X1656457Y268617I-293J272D01*
G02X1658539I1041J1083D01*
G03X1658523Y268056I277J-289D01*
G02X1658585Y266214I-1025J-957D01*
G37*
G36*
G01X1658748Y258865D02*
G03X1658830Y258331I333J-222D01*
G02X1656740Y257950I-881J-1091D01*
G03X1656627Y258478I-345J202D01*
G02X1658748Y258865I873J1222D01*
G37*
G36*
G01X1669624Y255597D02*
G03X1669481Y256198I-319J242D01*
G02X1668945Y256637I658J1350D01*
G03X1668414Y256733I-318J-242D01*
G02X1666532Y258743I-747J1187D01*
G03X1666377Y259340I-324J234D01*
G02X1668103Y259788I591J1271D01*
G03X1668258Y259191I324J-234D01*
G02X1668730Y258834I-591J-1271D01*
G03X1669266Y258769I304J260D01*
G02X1671338Y256641I874J-1222D01*
G03X1671481Y256040I319J-242D01*
G02X1669624Y255597I-659J-1349D01*
G37*
G36*
G01X1726471Y249314D02*
G03X1725917I-277J-288D01*
G02X1723874Y249418I-973J1010D01*
G03X1723291Y249449I-306J-258D01*
G02X1723445Y251443I-1040J1083D01*
G03X1724025Y251383I318J242D01*
G02X1725917Y251334I919J-1059D01*
G03X1726471I277J288D01*
G02X1728417I973J-1010D01*
G03X1728971I277J288D01*
G02Y249314I973J-1010D01*
G03X1728417I-277J-288D01*
G02X1726471I-973J1010D01*
G37*
G36*
G01X1690282Y249679D02*
G03X1689813Y249382I-80J-392D01*
G02X1687218Y249048I-1362J334D01*
G03X1686708Y249225I-352J-190D01*
G02X1685177Y249429I-595J1379D01*
G03X1684652Y249406I-249J-313D01*
G02X1684551Y251668I-1037J1087D01*
G03X1685076Y251691I249J313D01*
G02X1687474Y251240I1037J-1087D01*
G03X1687972Y251034I362J170D01*
G02X1688734Y251089I478J-1318D01*
G03X1689203Y251386I80J392D01*
G02X1690282Y249679I1362J-334D01*
G37*
G36*
G01X1510804Y246222D02*
G03X1510800Y245658I282J-284D01*
G02X1508810Y245669I-1000J-982D01*
G03X1508814Y246233I-282J284D01*
G02X1510804Y246222I1000J982D01*
G37*
G36*
G01X1662685Y245453D02*
G03X1663057Y245081I399J27D01*
G02X1661457Y243481I-101J-1499D01*
G03X1661085Y243853I-399J-27D01*
G02X1662685Y245453I101J1499D01*
G37*
G36*
G01X70004Y244530D02*
G03X70625Y244515I317J244D01*
G02X70568Y242120I1449J-1233D01*
G03X69947Y242135I-317J-244D01*
G02X67127Y242049I-1449J1233D01*
G03X66551I-288J-277D01*
G02X63771Y242090I-1371J1319D01*
G03X63184Y242095I-296J-269D01*
G02X63209Y244678I-1384J1305D01*
G03X63796Y244673I296J269D01*
G02X66551Y244687I1384J-1305D01*
G03X67127I288J277D01*
G02X70004Y244530I1371J-1319D01*
G37*
G36*
G01X1626025Y242615D02*
G03X1626599Y242478I350J194D01*
G02X1625390Y240152I1543J-2279D01*
G03X1624948Y240543I-400J-7D01*
G02X1626025Y242615I-150J1394D01*
G37*
G36*
G01X1642231Y235551D02*
G03X1642727Y235263I388J97D01*
G02X1641746Y233572I379J-1350D01*
G03X1641250Y233860I-388J-97D01*
G02X1642231Y235551I-379J1350D01*
G37*
G36*
G01X1682720Y234701D02*
G03X1683281Y234682I290J275D01*
G02X1683212Y232543I1019J-1103D01*
G03X1682651Y232562I-290J-275D01*
G02X1682720Y234701I-1019J1103D01*
G37*
G36*
G01X1499773Y233137D02*
G03X1500019Y232603I369J-154D01*
G02X1498202Y231818I-460J-1430D01*
G03X1497982Y232363I-361J171D01*
G02X1499773Y233137I496J1312D01*
G37*
G36*
G01X51939Y237500D02*
G03Y238100I-265J300D01*
G02X53993Y240557I1061J1200D01*
G03X54513Y240577I248J314D01*
G02X56640Y240618I1087J-1177D01*
G03X57160I260J304D01*
G02X59261Y238200I1040J-1218D01*
G03Y237600I265J-300D01*
G02Y235200I-1061J-1200D01*
G03Y234600I265J-300D01*
G02Y232200I-1061J-1200D01*
G03Y231600I265J-300D01*
G02Y229200I-1061J-1200D01*
G03Y228600I265J-300D01*
G02X57160Y226182I-1061J-1200D01*
G03X56640I-260J-304D01*
G02X54607Y226143I-1040J1218D01*
G03X54087Y226123I-248J-314D01*
G02X51939Y228500I-1088J1176D01*
G03Y229100I-265J300D01*
G02Y231500I1061J1200D01*
G03Y232100I-265J300D01*
G02Y234500I1061J1200D01*
G03Y235100I-265J300D01*
G02Y237500I1061J1200D01*
G37*
G36*
G01X-10353Y231081D02*
G03X-10281Y230458I283J-283D01*
G02X-13953Y229950I-1530J-2466D01*
G03X-14215Y230618I-295J270D01*
G02X-15160Y233402I131J1597D01*
G03X-15169Y234002I-269J296D01*
G02X-13068Y236421I1040J1219D01*
G03X-12540Y236420I265J300D01*
G02X-10423Y234015I1056J-1205D01*
G03Y233415I265J-300D01*
G02X-10353Y231081I-1061J-1200D01*
G37*
G36*
G01X1627010Y226336D02*
G03X1627549Y226367I253J310D01*
G02X1627608Y224212I1075J-1049D01*
G03X1627068Y224213I-271J-295D01*
G02X1627010Y226336I-944J1037D01*
G37*
G36*
G01X1401311Y222717D02*
G03X1400689I-311J-252D01*
G02Y224483I-1089J883D01*
G03X1401311I311J252D01*
G02Y222717I1089J-883D01*
G37*
G36*
G01X1622290Y224916D02*
G03Y224386I300J-265D01*
G02X1620038I-1126J-994D01*
G03Y224916I-300J265D01*
G02X1622290I1126J994D01*
G37*
G36*
G01X19300Y219939D02*
G03X18700I-300J-265D01*
G02X16439Y222200I-1200J1061D01*
G03Y222800I-265J300D01*
G02X17167Y225567I1061J1200D01*
G03X17399Y226205I-83J391D01*
G02X21578Y225792I2287J1787D01*
G03X21571Y225191I260J-304D01*
G02X21700Y225061I-1071J-1191D01*
G03X22300I300J265D01*
G02X24561Y222800I1200J-1061D01*
G03Y222200I265J-300D01*
G02X22300Y219939I-1061J-1200D01*
G03X21700I-300J-265D01*
G02X19300I-1200J1061D01*
G37*
G36*
G01X1492365Y219956D02*
G03X1492298Y219394I247J-314D01*
G02X1490272Y219582I-1102J-867D01*
G03X1490309Y220146I-264J301D01*
G02X1492365Y219956I1128J991D01*
G37*
G36*
G01X1768Y225347D02*
G03X1854Y225972I-201J346D01*
G02X6019Y225971I2083J2020D01*
G03X6080Y225363I287J-278D01*
G02X6304Y222908I-907J-1320D01*
G03X6325Y222322I282J-283D01*
G02X6573Y220169I-1048J-1212D01*
G03X6618Y219647I324J-235D01*
G02X4305Y219567I-1118J-1147D01*
G03X4280Y219856I-150J133D01*
G02X4161Y219961I999J1252D01*
G03X3873Y219951I-139J-144D01*
G02X1553Y222158I-1195J1067D01*
G03X1532Y222746I-281J284D01*
G02X1525Y222752I1039J1219D01*
G03X1005Y222756I-262J-302D01*
G02X1023Y225193I-1031J1226D01*
G03X1543Y225189I262J302D01*
G02X1768Y225347I1030J-1227D01*
G37*
G36*
G01X1628596Y216742D02*
G03X1628021Y216738I-286J-280D01*
G02X1628059Y218771I-1086J1037D01*
G03X1628633Y218745I300J265D01*
G02X1628596Y216742I962J-1020D01*
G37*
G36*
G01X1321474Y217713D02*
G03X1322045Y217665I309J254D01*
G02X1321821Y215640I985J-1134D01*
G03X1321252Y215719I-323J-237D01*
G02X1321474Y217713I-862J1105D01*
G37*
G36*
G01X1592278Y213823D02*
G03X1591747Y213696I-197J-348D01*
G02X1589432Y215586I-1253J828D01*
G03X1589455Y216127I-283J283D01*
G02X1590941Y218372I1070J906D01*
G03X1591421Y218583I118J382D01*
G02X1594029Y216794I1449J-683D01*
G03X1594046Y216226I290J-276D01*
G02X1592278Y213823I-1026J-1097D01*
G37*
G36*
G01X1647421Y213096D02*
G03X1646839Y213071I-279J-286D01*
G02X1646802Y215071I-1139J979D01*
G03X1647385Y215067I293J272D01*
G02X1647421Y213096I1015J-967D01*
G37*
G36*
G01X1873391Y212681D02*
G03X1872830Y212602I-241J-319D01*
G02X1872553Y214561I-1122J840D01*
G03X1873114Y214640I241J319D01*
G02X1873391Y212681I1122J-840D01*
G37*
G36*
G01X1612802Y215167D02*
G03Y214590I277J-289D01*
G02X1610720I-1041J-1083D01*
G03Y215167I-277J288D01*
G02X1612802I1041J1083D01*
G37*
G36*
G01X1863324Y210751D02*
G03X1862750Y210652I-240J-319D01*
G02X1860002Y211341I-1253J829D01*
G03X1859604Y211704I-398J-37D01*
G01X1859602D01*
G02X1861099Y213346I2J1502D01*
G03X1861497Y212983I398J37D01*
G01X1861499D01*
G02X1862462Y212632I-2J-1502D01*
G03X1863041Y212701I257J306D01*
G02X1863324Y210751I1129J-832D01*
G37*
G36*
G01X65883Y211720D02*
G03Y211180I295J-270D01*
G02X63517I-1183J-1080D01*
G03Y211720I-295J270D01*
G02X65883I1183J1080D01*
G37*
G36*
G01X1826685Y210650D02*
X1822024D01*
G03X1821652Y210102I0J-400D01*
G02X1820044Y210954I-1303J-516D01*
G03X1820318Y211516I-87J390D01*
G02X1821685Y213672I1367J645D01*
G01X1826686D01*
G02X1828196Y212171I-1J-1511D01*
G01Y212076D01*
X1828187Y211992D01*
G02X1826685Y210650I-1502J169D01*
G37*
G36*
G01X1323990Y208218D02*
G03X1323448I-271J-294D01*
G02Y210284I-948J1033D01*
G03X1323990I271J294D01*
G02Y208218I948J-1033D01*
G37*
G36*
G01X1330822Y207932D02*
G03X1330281Y207927I-268J-297D01*
G02X1330197Y210048I-957J1024D01*
G03X1330735Y210086I248J313D01*
G02X1332969Y210023I1089J-1035D01*
G03X1333579I305J259D01*
G02Y208079I1145J-972D01*
G03X1332969I-305J-259D01*
G02X1330822Y207932I-1145J972D01*
G37*
G36*
G01X1673388Y208579D02*
G03X1672950Y208225I-41J-398D01*
G02X1671698Y209774I-1394J154D01*
G03X1672136Y210128I41J398D01*
G02X1673388Y208579I1394J-154D01*
G37*
G36*
G01X1856810Y207408D02*
G03X1857399Y207388I304J260D01*
G02X1857330Y205357I1071J-1053D01*
G03X1856741Y205377I-304J-260D01*
G02X1856810Y207408I-1071J1053D01*
G37*
G36*
G01X1517619Y204557D02*
G03X1517615Y204002I286J-280D01*
G02X1515595Y204017I-1017J-965D01*
G03X1515599Y204572I-286J280D01*
G02X1517619Y204557I1017J965D01*
G37*
G36*
G01X37173Y207328D02*
G03X37176Y206690I243J-318D01*
G02X33299Y206337I-1743J-2320D01*
G03X33044Y207006I-294J271D01*
G02X32000Y207539I156J1594D01*
G03X31400I-300J-265D01*
G02X29139Y209800I-1200J1061D01*
G03Y210400I-265J300D01*
G02X31400Y212661I1061J1200D01*
G03X32000I300J265D01*
G02X34400I1200J-1061D01*
G03X35000I300J265D01*
G02X37261Y210400I1200J-1061D01*
G03Y209800I265J-300D01*
G02X37173Y207328I-1061J-1200D01*
G37*
G36*
G01X21569Y207254D02*
G03X21531Y206609I216J-336D01*
G02X17578Y206366I-1846J-2239D01*
G03X17370Y207032I-290J275D01*
G02X16639Y209800I330J1568D01*
G03Y210400I-265J300D01*
G02X18900Y212661I1061J1200D01*
G03X19500I300J265D01*
G02X21900I1200J-1061D01*
G03X22500I300J265D01*
G02X24761Y210400I1200J-1061D01*
G03Y209800I265J-300D01*
G02X22500Y207539I-1061J-1200D01*
G03X21900I-300J-265D01*
G02X21569Y207254I-1201J1060D01*
G37*
G36*
G01X2340Y206793D02*
G03X2368Y207104I-110J167D01*
G02X2281Y207194I1107J1158D01*
G03X1992Y207204I-149J-133D01*
G02X-193Y209546I-1117J1148D01*
G03Y210142I-267J298D01*
G02X1949Y212525I1068J1194D01*
G03X2468Y212510I268J296D01*
G02X4500Y212493I1006J-1247D01*
G03X5020Y212499I256J307D01*
G02X7148Y210104I1054J-1206D01*
G03Y209510I268J-297D01*
G02X6461Y206767I-1074J-1189D01*
G03X6240Y206135I97J-388D01*
G02X2340Y206793I-2303J-1765D01*
G37*
G36*
G01X-6028Y201618D02*
G03X-5934Y202265I-181J357D01*
G02X-1974Y202233I1997J2105D01*
G03X-1902Y201591I271J-295D01*
G02X-3735Y198979I-798J-1389D01*
G03X-4255Y198977I-259J-305D01*
G02X-6340Y198973I-1045J1214D01*
G03X-6860I-260J-304D01*
G02Y201409I-1040J1218D01*
G03X-6340I260J304D01*
G02X-6028Y201618I1041J-1217D01*
G37*
G36*
G01X1546924Y199009D02*
G03X1546944Y198437I289J-276D01*
G02X1544986Y198368I-944J-1037D01*
G03X1544966Y198940I-289J276D01*
G02X1546924Y199009I944J1037D01*
G37*
G36*
G01X1606297Y198182D02*
G03X1606897Y198183I300J266D01*
G02X1606808Y196176I1202J-1059D01*
G03X1606212Y196230I-322J-237D01*
G02X1606297Y198182I-962J1020D01*
G37*
G36*
G01X-12582Y201244D02*
G03X-12649Y201592I-125J156D01*
G02X-10427Y201819I839J2778D01*
G03X-10506Y201172I191J-352D01*
G02X-10525Y198789I-1080J-1183D01*
G03Y198189I265J-300D01*
G02X-12626Y195771I-1061J-1200D01*
G03X-13146I-260J-304D01*
G02X-15247Y198189I-1040J1218D01*
G03Y198789I-265J300D01*
G02X-13146Y201207I1061J1200D01*
G03X-12626I260J304D01*
G02X-12582Y201244I1053J-1207D01*
G37*
G36*
G01X1675818Y195715D02*
G03X1675217Y195701I-294J-271D01*
G02X1675172Y197682I-1151J965D01*
G03X1675773Y197696I294J271D01*
G02X1675818Y195715I1151J-965D01*
G37*
G36*
G01X1708794Y193293D02*
G02X1712894Y191735I3218J2294D01*
G02X1708794Y193293I-882J3852D01*
G37*
G36*
G01X1685249Y190074D02*
G03X1684682Y190002I-248J-314D01*
G02X1684418Y192084I-1198J906D01*
G03X1684985Y192156I248J314D01*
G02X1685249Y190074I1198J-906D01*
G37*
G36*
G01X1701557Y188169D02*
G03X1701547Y188800I-251J312D01*
G02X1703393Y188831I903J1200D01*
G03X1703403Y188200I251J-312D01*
G02X1701557Y188169I-903J-1200D01*
G37*
G36*
G01X98966Y184654D02*
G03X98434I-266J-298D01*
G02X96626Y186796I-933J1046D01*
G03X96647Y187404I-249J313D01*
G02X98942Y189631I1083J1180D01*
G03X99523Y189606I302J262D01*
G02X100761Y187223I977J-1006D01*
G03X100687Y186861I38J-196D01*
G02X100873Y186710I-788J-1160D01*
G03X101427I277J288D01*
G02X103334Y186746I973J-1010D01*
G03X103866I266J298D01*
G02Y184654I934J-1046D01*
G03X103334I-266J-298D01*
G02X101427Y184690I-934J1046D01*
G03X100873I-277J-288D01*
G02X98966Y184654I-973J1010D01*
G37*
G36*
G01X1621217Y184110D02*
G03X1620607Y184084I-294J-271D01*
G02X1620531Y185894I-1107J860D01*
G03X1621141Y185920I294J271D01*
G02X1621217Y184110I1107J-860D01*
G37*
G36*
G01X1609625Y183827D02*
G03X1609071Y183803I-265J-300D01*
G02X1608985Y185821I-1015J968D01*
G03X1609539Y185845I265J300D01*
G02X1611497Y185914I1014J-968D01*
G03X1612052Y185930I269J296D01*
G02X1614042Y185943I1001J-981D01*
G03X1614597Y185934I282J283D01*
G02X1614564Y183914I956J-1026D01*
G03X1614009Y183923I-282J-283D01*
G02X1612110Y183912I-955J1026D01*
G03X1611555Y183896I-269J-296D01*
G02X1609625Y183827I-1001J981D01*
G37*
G36*
G01X1636197Y184326D02*
G03X1636141Y183739I241J-319D01*
G02X1634254Y183918I-1041J-939D01*
G03X1634310Y184505I-241J319D01*
G02X1636197Y184326I1041J939D01*
G37*
G36*
G01X1626926Y184554D02*
G03X1627326Y184161I400J7D01*
G02X1625924Y182736I0J-1402D01*
G03X1625524Y183129I-400J-7D01*
G02X1626926Y184554I0J1402D01*
G37*
G36*
G01X1656005Y183496D02*
G03X1656044Y182887I277J-288D01*
G02X1654235Y182770I-835J-1126D01*
G03X1654196Y183379I-277J288D01*
G02X1656005Y183496I835J1126D01*
G37*
G36*
G01X1835113Y178705D02*
G03X1834511Y178660I-281J-284D01*
G02X1834375Y180495I-1123J839D01*
G03X1834977Y180540I281J284D01*
G02X1835113Y178705I1123J-839D01*
G37*
G36*
G01X1494307Y176588D02*
G03X1493800Y176362I-136J-376D01*
G02X1491426Y177789I-1300J526D01*
G03X1491404Y178328I-306J257D01*
G02X1493956Y179600I1065J1059D01*
G03X1494447Y179268I396J56D01*
G02X1494307Y176588I336J-1361D01*
G37*
G36*
G01X1615361Y178138D02*
G03X1615868Y177853I388J97D01*
G02X1614925Y176177I418J-1338D01*
G03X1614418Y176462I-388J-97D01*
G02X1615361Y178138I-418J1338D01*
G37*
G36*
G01X1884594Y177825D02*
G03X1884609Y177477I106J-170D01*
G02X1882939Y177266I-679J-1340D01*
G03X1882912Y177889I-264J301D01*
G02X1884992Y180014I888J1211D01*
G03X1885538Y179930I317J244D01*
G02X1885208Y177786I862J-1230D01*
G03X1884662Y177870I-317J-244D01*
G02X1884594Y177825I-863J1230D01*
G37*
G36*
G01X1254141Y174935D02*
G03X1253859I-141J-142D01*
G02Y177065I-1059J1065D01*
G03X1254141I141J142D01*
G02Y174935I1059J-1065D01*
G37*
G36*
G01X1856413Y174768D02*
G03X1855887I-263J-302D01*
G02Y177032I-987J1132D01*
G03X1856413I263J302D01*
G02Y174768I987J-1132D01*
G37*
G36*
G01X1876568Y175809D02*
G03X1876939Y175417I400J7D01*
G02X1875330Y173892I-107J-1498D01*
G03X1874959Y174284I-400J-7D01*
G02X1876568Y175809I107J1498D01*
G37*
G36*
G01X1472982Y172651D02*
G03X1472443Y172631I-259J-305D01*
G02X1472425Y174787I-1055J1069D01*
G03X1472964Y174776I276J290D01*
G02X1472982Y172651I924J-1055D01*
G37*
G36*
G01X1614926Y174330D02*
G03X1615426Y174119I364J166D01*
G02X1614624Y172220I474J-1319D01*
G03X1614124Y172431I-364J-166D01*
G02X1613209Y172419I-475J1319D01*
G03X1612732Y172230I-126J-380D01*
G02X1610389Y172044I-1232J670D01*
G03X1609884Y172153I-317J-244D01*
G02X1610333Y174245I-662J1236D01*
G03X1610838Y174136I317J244D01*
G02X1611941Y174231I662J-1236D01*
G03X1612418Y174420I126J380D01*
G02X1614926Y174330I1232J-670D01*
G37*
G36*
G01X1596631Y171213D02*
G03X1596053I-289J-277D01*
G02Y173155I-1011J971D01*
G03X1596631I289J277D01*
G02Y171213I1011J-971D01*
G37*
G36*
G01X1305383Y168925D02*
G03X1304823Y168924I-279J-286D01*
G02X1304818Y170925I-985J998D01*
G03X1305378Y170926I279J286D01*
G02X1305383Y168925I985J-998D01*
G37*
G36*
G01X1887496Y171573D02*
G03Y171027I292J-273D01*
G02X1885304I-1096J-1027D01*
G03Y171573I-292J273D01*
G02X1887496I1096J1027D01*
G37*
G36*
G01X123944Y163030D02*
G03X123628Y162579I80J-392D01*
G02X121724Y163910I-1584J-239D01*
G03X122040Y164361I-80J392D01*
G02X123944Y163030I1584J239D01*
G37*
G36*
G01X1563010Y162532D02*
G03X1563039Y161911I266J-299D01*
G02X1561202Y161865I-889J-1211D01*
G03X1561201Y162487I-252J311D01*
G02X1563010Y162532I878J1093D01*
G37*
G36*
G01X1870051Y154828D02*
G03X1870597Y154777I300J264D01*
G02X1870340Y152665I924J-1184D01*
G03X1869798Y152747I-315J-247D01*
G02X1870051Y154828I-798J1153D01*
G37*
G36*
G01X52728Y153836D02*
G03X52970Y153321I375J-138D01*
G02X51141Y152346I-470J-1321D01*
G03X50754Y152844I-387J98D01*
G01X47309D01*
G02X46273Y153255I0J1511D01*
G03X45688Y153216I-274J-291D01*
G02X45504Y155172I-1088J884D01*
G03X46085Y155243I257J306D01*
G02X47309Y155868I1224J-886D01*
G01X51310D01*
G02X52820Y154366I-1J-1512D01*
G01Y154271D01*
X52811Y154187D01*
G02X52728Y153836I-1502J170D01*
G37*
G36*
G01X68100Y149962D02*
X63097D01*
G02X61925Y150520I1J1511D01*
G03X61323Y150541I-310J-252D01*
G02X61341Y152439I-1023J959D01*
G03X61944Y152449I297J268D01*
G02X63097Y152984I1154J-976D01*
G01X68099D01*
G02X69253Y152448I0J-1511D01*
G03X69834Y152416I306J258D01*
G02X69781Y150437I966J-1016D01*
G03X69199I-291J-274D01*
G02X68100Y149962I-1100J1036D01*
G37*
G36*
G01X1887324Y152830D02*
G03X1887272Y152305I273J-292D01*
G02X1885025Y152529I-1222J-874D01*
G03X1885077Y153054I-273J292D01*
G02X1885165Y154913I1222J874D01*
G03X1885102Y155496I-302J262D01*
G02X1887134Y155715I898J1204D01*
G03X1887197Y155132I302J-262D01*
G02X1887324Y152830I-898J-1204D01*
G37*
G36*
G01X1265136Y151576D02*
G03X1265691Y151567I282J284D01*
G02X1265656Y149548I955J-1026D01*
G03X1265101Y149557I-282J-284D01*
G02X1263135Y149613I-955J1027D01*
G03X1262557I-289J-277D01*
G02Y151555I-1011J971D01*
G03X1263135I289J277D01*
G02X1265136Y151576I1011J-971D01*
G37*
G36*
G01X1575096Y151073D02*
G03Y150527I292J-273D01*
G02X1572904I-1096J-1027D01*
G03Y151073I-292J273D01*
G02X1575096I1096J1027D01*
G37*
G36*
G01X1295225Y148328D02*
G03X1294824Y147980I-4J-400D01*
G02X1291833Y148182I-1489J197D01*
G03X1291497Y148578I-400J1D01*
G02X1291670Y151562I237J1483D01*
G03X1292050Y151918I-18J400D01*
G02X1292056Y151966I1493J-162D01*
G03X1291848Y152194I-198J28D01*
G02X1293119Y154358I-76J1500D01*
G03X1293834Y154353I359J177D01*
G02X1295387Y152184I1338J-683D01*
G03X1295045Y151781I58J-396D01*
G02Y151728I-1502J-26D01*
G03X1295402Y151323I400J-7D01*
G02X1295225Y148328I-163J-1493D01*
G37*
G36*
G01X1279005Y147368D02*
G03X1278984Y146779I260J-304D01*
G02X1277038Y146800I-984J-999D01*
G03X1277030Y147389I-274J291D01*
G02X1279005Y147368I1000J1121D01*
G37*
G36*
G01X1873380Y146296D02*
G03X1873409Y145732I297J-267D01*
G02X1871484Y145809I-1009J-1113D01*
G03Y146126I-122J159D01*
G02X1871370Y146223I850J1115D01*
G03X1871048Y146158I-138J-144D01*
G02X1870598Y147929I-1380J592D01*
G03X1871178Y148020I248J314D01*
G02X1873380Y146296I1163J-783D01*
G37*
G36*
G01X1297421Y143496D02*
G03X1296839Y143471I-279J-286D01*
G02X1296802Y145471I-1139J979D01*
G03X1297385Y145467I293J272D01*
G02X1297421Y143496I1015J-967D01*
G37*
G36*
G01X1910547Y143703D02*
G03X1911150Y143631I332J223D01*
G02X1911010Y141718I950J-1031D01*
G03X1910403Y141736I-311J-251D01*
G02X1910547Y143703I-1187J1076D01*
G37*
G36*
G01X1240948Y143581D02*
G03X1240950Y142954I249J-313D01*
G02X1239084Y142946I-928J-1181D01*
G03X1239082Y143573I-249J313D01*
G02X1240948Y143581I928J1181D01*
G37*
G36*
G01X1267817Y140600D02*
G03X1267304Y140292I-120J-382D01*
G02X1266345Y141978I-1476J276D01*
G03X1266872Y142261I138J376D01*
G02X1267817Y140600I1364J-323D01*
G37*
G36*
G01X1905267Y141604D02*
G03X1905220Y141049I263J-302D01*
G02X1903106Y141112I-1084J-889D01*
G03X1903093Y141669I-293J272D01*
G02X1905267Y141604I1122J1143D01*
G37*
G36*
G01X1856050Y137539D02*
G03X1855450I-300J-265D01*
G02Y139661I-1200J1061D01*
G03X1856050I300J265D01*
G02Y137539I1200J-1061D01*
G37*
G36*
G01X1879910Y138935D02*
G03X1879937Y138396I308J-255D01*
G02X1877819Y138229I-987J-996D01*
G03X1877761Y138765I-323J236D01*
G02X1879910Y138935I992J1128D01*
G37*
G36*
G01X1324841Y132400D02*
G03X1324211I-315J-246D01*
G02Y134246I-1185J923D01*
G03X1324841I315J246D01*
G02Y132400I1185J-923D01*
G37*
G36*
G01X1287527Y130990D02*
G03X1286973I-277J-288D01*
G02X1284990Y132973I-973J1010D01*
G03Y133527I-288J277D01*
G02Y135473I1010J973D01*
G03Y136027I-288J277D01*
G02Y137973I1010J973D01*
G03Y138527I-288J277D01*
G02X1286973Y140510I1010J973D01*
G03X1287527I277J288D01*
G02X1289510Y138527I973J-1010D01*
G03Y137973I288J-277D01*
G02Y136027I-1010J-973D01*
G03Y135473I288J-277D01*
G02Y133527I-1010J-973D01*
G03Y132973I288J-277D01*
G02X1287527Y130990I-1010J-973D01*
G37*
G36*
G01X1861933Y132617D02*
G03X1861943Y131996I257J-306D01*
G02X1860051Y131967I-928J-1181D01*
G03X1860041Y132588I-257J306D01*
G02X1859873Y134796I928J1181D01*
G03Y135342I-292J273D01*
G02X1862065I1096J1027D01*
G03Y134796I292J-273D01*
G02X1861933Y132617I-1096J-1027D01*
G37*
G36*
G01X1580430Y130126D02*
G03X1580434Y129600I303J-261D01*
G02X1578170Y129582I-1124J-996D01*
G03X1578166Y130108I-303J261D01*
G02X1580430Y130126I1124J996D01*
G37*
G36*
G01X625831Y129840D02*
G03X626364Y129595I380J125D01*
G02X625569Y127860I536J-1295D01*
G03X625036Y128105I-380J-125D01*
G02X625831Y129840I-536J1295D01*
G37*
G36*
G01X1253068Y126988D02*
G03X1252490Y126954I-273J-293D01*
G02X1252424Y128969I-1146J971D01*
G03X1253003Y128973I288J278D01*
G02X1253068Y126988I1021J-960D01*
G37*
G36*
G01X683927Y126075D02*
G03X683373I-277J-288D01*
G02X681056Y126686I-973J1010D01*
G03X680501Y126933I-383J-114D01*
G02X681244Y128599I-601J1267D01*
G03X681799Y128352I383J114D01*
G02X683373Y128095I601J-1267D01*
G03X683927I277J288D01*
G02Y126075I973J-1010D01*
G37*
G36*
G01X645317Y124397D02*
G03X645034Y123914I105J-386D01*
G02X642303Y123865I-1360J-341D01*
G03X641920Y124348I-391J83D01*
G02X643117Y126527I30J1402D01*
G03X643783I333J222D01*
G02X645317Y124397I1167J-777D01*
G37*
G36*
G01X1248363Y123745D02*
G03X1248983Y123780I296J270D01*
G02X1249046Y121939I1217J-880D01*
G03X1248425Y121931I-307J-256D01*
G02X1248363Y123745I-1099J870D01*
G37*
G36*
G01X1270473Y121404D02*
G03X1269927I-273J-292D01*
G02X1267780Y121500I-1027J1096D01*
G03X1267197Y121514I-298J-267D01*
G02Y123486I-997J986D01*
G03X1267780Y123500I285J281D01*
G02X1269927Y123596I1120J-1000D01*
G03X1270473I273J292D01*
G02Y121404I1027J-1096D01*
G37*
G36*
G01X1287039Y117747D02*
G03Y117117I246J-315D01*
G02X1285193I-923J-1185D01*
G03Y117747I-246J315D01*
G02X1287039I923J1185D01*
G37*
G36*
G01X660254Y114819D02*
G03X659685Y114699I-228J-329D01*
G02X659289Y116584I-1195J733D01*
G03X659858Y116704I228J329D01*
G02X660254Y114819I1195J-733D01*
G37*
G36*
G01X1907493Y116959D02*
G03X1907504Y116391I287J-279D01*
G02X1905388Y116350I-1037J-1086D01*
G03X1905377Y116918I-287J279D01*
G02X1907493Y116959I1037J1086D01*
G37*
G36*
G01X1278135Y116500D02*
G03X1278122Y115901I259J-305D01*
G02X1276186Y115992I-1022J-1101D01*
G03X1276228Y116589I-244J317D01*
G02X1278135Y116500I1001J981D01*
G37*
G36*
G01X1915277Y115092D02*
G03X1915367Y114526I321J-239D01*
G02X1913343Y114258I-867J-1226D01*
G03X1913283Y114828I-307J256D01*
G02X1915277Y115092I869J1100D01*
G37*
G36*
G01X1303600Y113273D02*
G03Y112727I292J-273D01*
G02X1301408I-1096J-1027D01*
G03Y113273I-292J273D01*
G02X1301439Y115359I1096J1027D01*
G03Y115641I-142J141D01*
G02X1301450Y117770I1065J1059D01*
G03X1301452Y118052I-141J142D01*
G02X1303580Y118032I1074J1050D01*
G03X1303578Y117750I141J-142D01*
G02X1303569Y115641I-1074J-1050D01*
G03Y115359I142J-141D01*
G02X1303600Y113273I-1065J-1059D01*
G37*
G36*
G01X951622Y111340D02*
G03X951635Y110779I291J-274D01*
G02X949553Y110787I-1045J-1079D01*
G03X949571Y111348I-276J290D01*
G02X951622Y111340I1029J952D01*
G37*
G36*
G01X302014D02*
G03X302027Y110779I291J-274D01*
G02X299945Y110787I-1045J-1079D01*
G03X299963Y111348I-276J290D01*
G02X302014Y111340I1029J952D01*
G37*
G36*
G01X614990Y109822D02*
G03X615527Y109612I369J153D01*
G02X614849Y107736I588J-1273D01*
G03X614302Y107918I-361J-172D01*
G02X614990Y109822I-700J1329D01*
G37*
G36*
G01X1209253Y109017D02*
G03X1209267Y108434I281J-285D01*
G02X1207267I-1000J-1120D01*
G03X1207281Y109017I-267J298D01*
G02X1209253I986J997D01*
G37*
G36*
G01X1202560D02*
G03X1202574Y108434I281J-285D01*
G02X1200574I-1000J-1120D01*
G03X1200588Y109017I-267J298D01*
G02X1202560I986J997D01*
G37*
G36*
G01X1178842Y108978D02*
G03X1178869Y108417I298J-267D01*
G02X1176788Y108377I-1020J-1103D01*
G03X1176792Y108938I-283J283D01*
G02X1178842Y108978I1006J976D01*
G37*
G36*
G01X559645Y109017D02*
G03X559659Y108434I281J-285D01*
G02X557659I-1000J-1120D01*
G03X557673Y109017I-267J298D01*
G02X559645I986J997D01*
G37*
G36*
G01X552952D02*
G03X552966Y108434I281J-285D01*
G02X550966I-1000J-1120D01*
G03X550980Y109017I-267J298D01*
G02X552952I986J997D01*
G37*
G36*
G01X529234Y108978D02*
G03X529261Y108417I298J-267D01*
G02X527180Y108377I-1020J-1103D01*
G03X527184Y108938I-283J283D01*
G02X529234Y108978I1006J976D01*
G37*
G36*
G01X924511Y108948D02*
G03X924538Y108387I298J-267D01*
G02X922457Y108347I-1020J-1103D01*
G03X922461Y108908I-283J283D01*
G02X924511Y108948I1006J976D01*
G37*
G36*
G01X918111Y108987D02*
G03X918125Y108404I281J-285D01*
G02X916125I-1000J-1120D01*
G03X916139Y108987I-267J298D01*
G02X918111I986J997D01*
G37*
G36*
G01X911418D02*
G03X911432Y108404I281J-285D01*
G02X909432I-1000J-1120D01*
G03X909446Y108987I-267J298D01*
G02X911418I986J997D01*
G37*
G36*
G01X887700Y108948D02*
G03X887727Y108387I298J-267D01*
G02X885646Y108347I-1020J-1103D01*
G03X885650Y108908I-283J283D01*
G02X887700Y108948I1006J976D01*
G37*
G36*
G01X274903D02*
G03X274930Y108387I298J-267D01*
G02X272849Y108347I-1020J-1103D01*
G03X272853Y108908I-283J283D01*
G02X274903Y108948I1006J976D01*
G37*
G36*
G01X268503Y108987D02*
G03X268517Y108404I281J-285D01*
G02X266517I-1000J-1120D01*
G03X266531Y108987I-267J298D01*
G02X268503I986J997D01*
G37*
G36*
G01X261810D02*
G03X261824Y108404I281J-285D01*
G02X259824I-1000J-1120D01*
G03X259838Y108987I-267J298D01*
G02X261810I986J997D01*
G37*
G36*
G01X238092Y108948D02*
G03X238119Y108387I298J-267D01*
G02X236038Y108347I-1020J-1103D01*
G03X236042Y108908I-283J283D01*
G02X238092Y108948I1006J976D01*
G37*
G36*
G01X1185167Y108608D02*
G03X1185183Y108047I293J-272D01*
G02X1183101I-1041J-1083D01*
G03X1183117Y108608I-277J289D01*
G02X1185167I1025J956D01*
G37*
G36*
G01X1171746D02*
G03X1171762Y108047I293J-272D01*
G02X1169680I-1041J-1083D01*
G03X1169696Y108608I-277J289D01*
G02X1171746I1025J956D01*
G37*
G36*
G01X1165453D02*
G03X1165469Y108047I293J-272D01*
G02X1163387I-1041J-1083D01*
G03X1163403Y108608I-277J289D01*
G02X1165453I1025J956D01*
G37*
G36*
G01X1148356D02*
G03X1148372Y108047I293J-272D01*
G02X1146290I-1041J-1083D01*
G03X1146306Y108608I-277J289D01*
G02X1148356I1025J956D01*
G37*
G36*
G01X1142063D02*
G03X1142079Y108047I293J-272D01*
G02X1139997I-1041J-1083D01*
G03X1140013Y108608I-277J289D01*
G02X1142063I1025J956D01*
G37*
G36*
G01X535559D02*
G03X535575Y108047I293J-272D01*
G02X533493I-1041J-1083D01*
G03X533509Y108608I-277J289D01*
G02X535559I1025J956D01*
G37*
G36*
G01X522138D02*
G03X522154Y108047I293J-272D01*
G02X520072I-1041J-1083D01*
G03X520088Y108608I-277J289D01*
G02X522138I1025J956D01*
G37*
G36*
G01X515845D02*
G03X515861Y108047I293J-272D01*
G02X513779I-1041J-1083D01*
G03X513795Y108608I-277J289D01*
G02X515845I1025J956D01*
G37*
G36*
G01X498748D02*
G03X498764Y108047I293J-272D01*
G02X496682I-1041J-1083D01*
G03X496698Y108608I-277J289D01*
G02X498748I1025J956D01*
G37*
G36*
G01X492455D02*
G03X492471Y108047I293J-272D01*
G02X490389I-1041J-1083D01*
G03X490405Y108608I-277J289D01*
G02X492455I1025J956D01*
G37*
G36*
G01X930836Y108578D02*
G03X930852Y108017I293J-272D01*
G02X928770I-1041J-1083D01*
G03X928786Y108578I-277J289D01*
G02X930836I1025J956D01*
G37*
G36*
G01X894025D02*
G03X894041Y108017I293J-272D01*
G02X891959I-1041J-1083D01*
G03X891975Y108578I-277J289D01*
G02X894025I1025J956D01*
G37*
G36*
G01X281228D02*
G03X281244Y108017I293J-272D01*
G02X279162I-1041J-1083D01*
G03X279178Y108578I-277J289D01*
G02X281228I1025J956D01*
G37*
G36*
G01X244417D02*
G03X244433Y108017I293J-272D01*
G02X242351I-1041J-1083D01*
G03X242367Y108578I-277J289D01*
G02X244417I1025J956D01*
G37*
G36*
G01X1189030Y106782D02*
G03X1189014Y106221I277J-289D01*
G02X1186964I-1025J-956D01*
G03X1186948Y106782I-293J272D01*
G02X1186901Y108900I1041J1083D01*
G03X1186895Y109457I-290J275D01*
G02X1186922Y111597I1068J1057D01*
G03X1186938Y112158I-277J289D01*
G02X1188988I1025J956D01*
G03X1189004Y111597I293J-272D01*
G02X1189051Y109479I-1041J-1083D01*
G03X1189057Y108922I290J-275D01*
G02X1189030Y106782I-1068J-1057D01*
G37*
G36*
G01X1152219D02*
G03X1152203Y106221I277J-289D01*
G02X1150153I-1025J-956D01*
G03X1150137Y106782I-293J272D01*
G02X1150090Y108900I1041J1083D01*
G03X1150084Y109457I-290J275D01*
G02X1150111Y111597I1068J1057D01*
G03X1150127Y112158I-277J289D01*
G02X1152177I1025J956D01*
G03X1152193Y111597I293J-272D01*
G02X1152240Y109479I-1041J-1083D01*
G03X1152246Y108922I290J-275D01*
G02X1152219Y106782I-1068J-1057D01*
G37*
G36*
G01X934699D02*
G03X934683Y106221I277J-289D01*
G02X932633I-1025J-956D01*
G03X932617Y106782I-293J272D01*
G02X932570Y108900I1041J1083D01*
G03X932564Y109457I-290J275D01*
G02X932591Y111597I1068J1057D01*
G03X932607Y112158I-277J289D01*
G02X934657I1025J956D01*
G03X934673Y111597I293J-272D01*
G02X934720Y109479I-1041J-1083D01*
G03X934726Y108922I290J-275D01*
G02X934699Y106782I-1068J-1057D01*
G37*
G36*
G01X897888D02*
G03X897872Y106221I277J-289D01*
G02X895822I-1025J-956D01*
G03X895806Y106782I-293J272D01*
G02X895759Y108900I1041J1083D01*
G03X895753Y109457I-290J275D01*
G02X895780Y111597I1068J1057D01*
G03X895796Y112158I-277J289D01*
G02X897846I1025J956D01*
G03X897862Y111597I293J-272D01*
G02X897909Y109479I-1041J-1083D01*
G03X897915Y108922I290J-275D01*
G02X897888Y106782I-1068J-1057D01*
G37*
G36*
G01X539422D02*
G03X539406Y106221I277J-289D01*
G02X537356I-1025J-956D01*
G03X537340Y106782I-293J272D01*
G02X537293Y108900I1041J1083D01*
G03X537287Y109457I-290J275D01*
G02X537314Y111597I1068J1057D01*
G03X537330Y112158I-277J289D01*
G02X539380I1025J956D01*
G03X539396Y111597I293J-272D01*
G02X539443Y109479I-1041J-1083D01*
G03X539449Y108922I290J-275D01*
G02X539422Y106782I-1068J-1057D01*
G37*
G36*
G01X502611D02*
G03X502595Y106221I277J-289D01*
G02X500545I-1025J-956D01*
G03X500529Y106782I-293J272D01*
G02X500482Y108900I1041J1083D01*
G03X500476Y109457I-290J275D01*
G02X500503Y111597I1068J1057D01*
G03X500519Y112158I-277J289D01*
G02X502569I1025J956D01*
G03X502585Y111597I293J-272D01*
G02X502632Y109479I-1041J-1083D01*
G03X502638Y108922I290J-275D01*
G02X502611Y106782I-1068J-1057D01*
G37*
G36*
G01X285091D02*
G03X285075Y106221I277J-289D01*
G02X283025I-1025J-956D01*
G03X283009Y106782I-293J272D01*
G02X282962Y108900I1041J1083D01*
G03X282956Y109457I-290J275D01*
G02X282983Y111597I1068J1057D01*
G03X282999Y112158I-277J289D01*
G02X285049I1025J956D01*
G03X285065Y111597I293J-272D01*
G02X285112Y109479I-1041J-1083D01*
G03X285118Y108922I290J-275D01*
G02X285091Y106782I-1068J-1057D01*
G37*
G36*
G01X248280D02*
G03X248264Y106221I277J-289D01*
G02X246214I-1025J-956D01*
G03X246198Y106782I-293J272D01*
G02X246151Y108900I1041J1083D01*
G03X246145Y109457I-290J275D01*
G02X246172Y111597I1068J1057D01*
G03X246188Y112158I-277J289D01*
G02X248238I1025J956D01*
G03X248254Y111597I293J-272D01*
G02X248301Y109479I-1041J-1083D01*
G03X248307Y108922I290J-275D01*
G02X248280Y106782I-1068J-1057D01*
G37*
G36*
G01X1194108Y106576D02*
G03X1194095Y106014I278J-288D01*
G02X1192047Y106004I-1019J-963D01*
G03X1192029Y106565I-293J271D01*
G02X1191980Y108696I1034J1090D01*
G03X1191986Y109245I-288J278D01*
G02X1192049Y111347I1103J1019D01*
G03X1192064Y111909I-277J289D01*
G02X1194114I1025J956D01*
G03X1194129Y111347I292J-273D01*
G02X1194172Y109223I-1040J-1083D01*
G03X1194166Y108674I288J-278D01*
G02X1194108Y106576I-1103J-1019D01*
G37*
G36*
G01X1157297D02*
G03X1157284Y106014I278J-288D01*
G02X1155236Y106004I-1019J-963D01*
G03X1155218Y106565I-293J271D01*
G02X1155169Y108696I1034J1090D01*
G03X1155175Y109245I-288J278D01*
G02X1155238Y111347I1103J1019D01*
G03X1155253Y111909I-277J289D01*
G02X1157303I1025J956D01*
G03X1157318Y111347I292J-273D01*
G02X1157361Y109223I-1040J-1083D01*
G03X1157355Y108674I288J-278D01*
G02X1157297Y106576I-1103J-1019D01*
G37*
G36*
G01X939777D02*
G03X939764Y106014I278J-288D01*
G02X937716Y106004I-1019J-963D01*
G03X937698Y106565I-293J271D01*
G02X937649Y108696I1034J1090D01*
G03X937655Y109245I-288J278D01*
G02X937718Y111347I1103J1019D01*
G03X937733Y111909I-277J289D01*
G02X939783I1025J956D01*
G03X939798Y111347I292J-273D01*
G02X939841Y109223I-1040J-1083D01*
G03X939835Y108674I288J-278D01*
G02X939777Y106576I-1103J-1019D01*
G37*
G36*
G01X902966D02*
G03X902953Y106014I278J-288D01*
G02X900905Y106004I-1019J-963D01*
G03X900887Y106565I-293J271D01*
G02X900838Y108696I1034J1090D01*
G03X900844Y109245I-288J278D01*
G02X900907Y111347I1103J1019D01*
G03X900922Y111909I-277J289D01*
G02X902972I1025J956D01*
G03X902987Y111347I292J-273D01*
G02X903030Y109223I-1040J-1083D01*
G03X903024Y108674I288J-278D01*
G02X902966Y106576I-1103J-1019D01*
G37*
G36*
G01X544500D02*
G03X544487Y106014I278J-288D01*
G02X542439Y106004I-1019J-963D01*
G03X542421Y106565I-293J271D01*
G02X542372Y108696I1034J1090D01*
G03X542378Y109245I-288J278D01*
G02X542441Y111347I1103J1019D01*
G03X542456Y111909I-277J289D01*
G02X544506I1025J956D01*
G03X544521Y111347I292J-273D01*
G02X544564Y109223I-1040J-1083D01*
G03X544558Y108674I288J-278D01*
G02X544500Y106576I-1103J-1019D01*
G37*
G36*
G01X507689D02*
G03X507676Y106014I278J-288D01*
G02X505628Y106004I-1019J-963D01*
G03X505610Y106565I-293J271D01*
G02X505561Y108696I1034J1090D01*
G03X505567Y109245I-288J278D01*
G02X505630Y111347I1103J1019D01*
G03X505645Y111909I-277J289D01*
G02X507695I1025J956D01*
G03X507710Y111347I292J-273D01*
G02X507753Y109223I-1040J-1083D01*
G03X507747Y108674I288J-278D01*
G02X507689Y106576I-1103J-1019D01*
G37*
G36*
G01X290169D02*
G03X290156Y106014I278J-288D01*
G02X288108Y106004I-1019J-963D01*
G03X288090Y106565I-293J271D01*
G02X288041Y108696I1034J1090D01*
G03X288047Y109245I-288J278D01*
G02X288110Y111347I1103J1019D01*
G03X288125Y111909I-277J289D01*
G02X290175I1025J956D01*
G03X290190Y111347I292J-273D01*
G02X290233Y109223I-1040J-1083D01*
G03X290227Y108674I288J-278D01*
G02X290169Y106576I-1103J-1019D01*
G37*
G36*
G01X253358D02*
G03X253345Y106014I278J-288D01*
G02X251297Y106004I-1019J-963D01*
G03X251279Y106565I-293J271D01*
G02X251230Y108696I1034J1090D01*
G03X251236Y109245I-288J278D01*
G02X251299Y111347I1103J1019D01*
G03X251314Y111909I-277J289D01*
G02X253364I1025J956D01*
G03X253379Y111347I292J-273D01*
G02X253422Y109223I-1040J-1083D01*
G03X253416Y108674I288J-278D01*
G02X253358Y106576I-1103J-1019D01*
G37*
G36*
G01X954799Y106575D02*
G03X954787Y105996I270J-295D01*
G02X952803Y105985I-987J-996D01*
G03X952785Y106564I-285J281D01*
G02X954799Y106575I1001J1120D01*
G37*
G36*
G01X305191D02*
G03X305179Y105996I270J-295D01*
G02X303195Y105985I-987J-996D01*
G03X303177Y106564I-285J281D01*
G02X305191Y106575I1001J1120D01*
G37*
G36*
G01X948267Y106735D02*
G03X948281Y106170I290J-275D01*
G02X946211Y106176I-1038J-1086D01*
G03X946228Y106740I-275J291D01*
G02X948267Y106735I1022J960D01*
G37*
G36*
G01X298659D02*
G03X298673Y106170I290J-275D01*
G02X296603Y106176I-1038J-1086D01*
G03X296620Y106740I-275J291D01*
G02X298659Y106735I1022J960D01*
G37*
G36*
G01X1908258Y106254D02*
G03X1908667Y105913I396J59D01*
G02X1907328Y104307I48J-1401D01*
G03X1906919Y104648I-396J-59D01*
G02X1908258Y106254I-48J1401D01*
G37*
G36*
G01X1876102Y103939D02*
G03X1875735Y103468I26J-399D01*
G02X1872860Y102647I-1477J-272D01*
G03X1872347Y102875I-372J-146D01*
G02X1873130Y104771I-492J1313D01*
G03X1873654Y104571I364J167D01*
G02X1874157Y104695I606J-1375D01*
G03X1874524Y105166I-26J399D01*
G02X1876102Y103939I1477J272D01*
G37*
G36*
G01X977419Y104723D02*
G03X977512Y104164I325J-233D01*
G02X975516Y102270I-812J-1143D01*
G03X974939Y102377I-338J-214D01*
G02X974274Y104891I-839J1123D01*
G03X974718Y105354I50J397D01*
G02X977419Y104723I1482J246D01*
G37*
G36*
G01X327811D02*
G03X327904Y104164I325J-233D01*
G02X325908Y102270I-812J-1143D01*
G03X325331Y102377I-338J-214D01*
G02X324666Y104891I-839J1123D01*
G03X325110Y105354I50J397D01*
G02X327811Y104723I1482J246D01*
G37*
G36*
G01X768144Y101875D02*
G03X767583Y101859I-272J-293D01*
G02Y103941I-1083J1041D01*
G03X768144Y103925I289J277D01*
G02Y101875I956J-1025D01*
G37*
G36*
G01X1270315Y101177D02*
G03X1269685I-315J-246D01*
G02X1267445Y103169I-1185J923D01*
G03X1267466Y103715I-281J284D01*
G02X1269741Y105677I1134J985D01*
G03X1270349I304J260D01*
G02X1272590Y103678I1141J-977D01*
G03X1272592Y103131I293J-272D01*
G02X1270315Y101177I-1092J-1031D01*
G37*
G36*
G01X743589Y101538D02*
G03X743054Y101351I-174J-360D01*
G02X742426Y103315I-1354J649D01*
G03X742970Y103473I193J350D01*
G02X744736Y104095I1230J-673D01*
G03X745269Y104340I153J370D01*
G02X746064Y102605I1331J-440D01*
G03X745531Y102360I-153J-370D01*
G02X743589Y101538I-1331J440D01*
G37*
G36*
G01X1323598Y101146D02*
G03X1324138Y101133I277J289D01*
G02X1324023Y98980I987J-1132D01*
G03X1323485Y99025I-294J-272D01*
G02X1323598Y101146I-857J1109D01*
G37*
G36*
G01X1375685Y100772D02*
G03Y100460I125J-156D01*
G02X1373798Y100339I-877J-1094D01*
G03Y100893I-288J277D01*
G02Y102839I1010J973D01*
G03Y103393I-288J277D01*
G02Y105339I1010J973D01*
G03Y105893I-288J277D01*
G02X1375781Y107876I1010J973D01*
G03X1376335I277J288D01*
G02X1378318Y105893I973J-1010D01*
G03Y105339I288J-277D01*
G02Y103393I-1010J-973D01*
G03Y102839I288J-277D01*
G02X1376335Y100856I-1010J-973D01*
G03X1375781I-277J-288D01*
G02X1375685Y100772I-970J1012D01*
G37*
G36*
G01X757896Y100973D02*
G03Y100427I292J-273D01*
G02X755704I-1096J-1027D01*
G03Y100973I-292J273D01*
G02X757896I1096J1027D01*
G37*
G36*
G01X1559131Y99752D02*
G03X1559108Y99174I265J-300D01*
G02X1557118Y99201I-1008J-974D01*
G03X1557111Y99779I-280J286D01*
G02X1559131Y99752I1025J1098D01*
G37*
G36*
G01X1555704Y99831D02*
G03X1555727Y99252I287J-279D01*
G02X1553745Y99124I-927J-1052D01*
G03X1553693Y99701I-301J264D01*
G02X1555704Y99831I934J1176D01*
G37*
G36*
G01X1573583Y97382D02*
G03X1573573Y96771I253J-310D01*
G02X1571637Y96803I-987J-1132D01*
G03X1571647Y97414I-253J310D01*
G02X1573583Y97382I987J1132D01*
G37*
G36*
G01X1919293Y95062D02*
G03X1919273Y94531I288J-277D01*
G02X1917030Y94617I-1160J-955D01*
G03X1917050Y95148I-288J277D01*
G02X1917117Y97133I1160J954D01*
G03X1917073Y97722I-291J274D01*
G02X1919095Y97872I929J1180D01*
G03X1919139Y97283I291J-274D01*
G02X1919293Y95062I-929J-1180D01*
G37*
G36*
G01X1921Y93995D02*
G03X2176Y94476I-131J378D01*
G02X4503Y95850I1354J364D01*
G03X5057I277J288D01*
G02X7003I973J-1010D01*
G03X7557I277J288D01*
G02X9503I973J-1010D01*
G03X10057I277J288D01*
G02X12003I973J-1010D01*
G03X12557I277J288D01*
G02X14503I973J-1010D01*
G03X15057I277J288D01*
G02X17003I973J-1010D01*
G03X17557I277J288D01*
G02X19503I973J-1010D01*
G03X20057I277J288D01*
G02X22003I973J-1010D01*
G03X22557I277J288D01*
G02X24895Y94518I973J-1010D01*
G03X25194Y94036I389J-92D01*
G02X23907Y91660I-314J-1366D01*
G03X23353I-277J-288D01*
G02X21407I-973J1010D01*
G03X20853I-277J-288D01*
G02X18907I-973J1010D01*
G03X18353I-277J-288D01*
G02X16407I-973J1010D01*
G03X15853I-277J-288D01*
G02X13907I-973J1010D01*
G03X13353I-277J-288D01*
G02X11407I-973J1010D01*
G03X10853I-277J-288D01*
G02X8907I-973J1010D01*
G03X8353I-277J-288D01*
G02X6407I-973J1010D01*
G03X5853I-277J-288D01*
G02X3907I-973J1010D01*
G03X3353I-277J-288D01*
G02X1921Y93995I-972J1010D01*
G37*
G36*
G01X691464Y93829D02*
G03X692074Y93682I363J168D01*
G02X691636Y91871I926J-1182D01*
G03X691026Y92018I-363J-168D01*
G02X688742Y92559I-926J1182D01*
G03X688163Y92724I-362J-171D01*
G02X688638Y94558I-763J1176D01*
G03X689224Y94420I353J187D01*
G02X691464Y93829I876J-1220D01*
G37*
G36*
G01X34168Y91396D02*
G03X33821Y91859I-395J66D01*
G02X35482Y93104I179J1491D01*
G03X35829Y92641I395J-66D01*
G02X34168Y91396I-179J-1491D01*
G37*
G36*
G01X733655Y89330D02*
G03X734242Y89312I302J263D01*
G02X734185Y87407I999J-983D01*
G03X733598Y87425I-302J-263D01*
G02X731603Y87422I-999J983D01*
G03X731034I-284J-282D01*
G02Y89394I-996J986D01*
G03X731603I285J282D01*
G02X733655Y89330I996J-986D01*
G37*
G36*
G01X694085Y83696D02*
G03X693552Y83430I-147J-372D01*
G02X692715Y85104I-1352J370D01*
G03X693248Y85370I147J372D01*
G02X694085Y83696I1352J-370D01*
G37*
G36*
G01X1908997Y83884D02*
G03X1909009Y83351I304J-260D01*
G02X1906918Y83302I-1024J-958D01*
G03X1906906Y83835I-304J260D01*
G02X1906885Y85729I1023J958D01*
G03X1906880Y86268I-298J267D01*
G02X1908951Y86287I1027J955D01*
G03X1908956Y85748I298J-267D01*
G02X1908997Y83884I-1027J-955D01*
G37*
G36*
G01X1903859Y80735D02*
G03X1904459Y80728I303J261D01*
G02X1904438Y78875I1042J-938D01*
G03X1903838Y78882I-303J-261D01*
G02X1903859Y80735I-1042J938D01*
G37*
G36*
G01X675599Y76999D02*
G03X675021I-289J-277D01*
G02X672971Y78911I-1011J971D01*
G03X672946Y79472I-297J268D01*
G02X672883Y81465I954J1028D01*
G03X672867Y82031I-290J275D01*
G02X674841Y84021I962J1020D01*
G03X675419I289J277D01*
G02X677447Y82085I1011J-971D01*
G03X677463Y81519I290J-275D01*
G02X677539Y79559I-963J-1019D01*
G03X677564Y78998I297J-268D01*
G02X675599Y76999I-954J-1028D01*
G37*
G36*
G01X1581380Y74745D02*
G03X1580834I-273J-292D01*
G02Y76937I-1027J1096D01*
G03X1581380I273J292D01*
G02Y74745I1027J-1096D01*
G37*
G36*
G01X1571553Y76478D02*
G03X1572093Y76463I278J288D01*
G02X1572034Y74246I983J-1135D01*
G03X1571494Y74261I-278J-288D01*
G02X1571553Y76478I-983J1135D01*
G37*
G36*
G01X732623Y74336D02*
G03X732045Y74316I-279J-286D01*
G02X731971Y76391I-1122J999D01*
G03X732549Y76411I279J286D01*
G02X732623Y74336I1122J-999D01*
G37*
G36*
G01X1390765Y73812D02*
G03X1390207Y73739I-242J-318D01*
G02X1389168Y76000I-1107J861D01*
G03X1389587Y76376I20J400D01*
G02X1389623Y76695I2997J-177D01*
G03X1389193Y77160I-395J67D01*
G02X1389567Y79866I-125J1396D01*
G03X1389822Y79975I71J187D01*
G02X1393790Y81547I2762J-1177D01*
G02X1396200Y81552I1211J-2747D01*
G02X1400106Y77500I1200J-2752D01*
G02X1396200Y73448I-2706J-1300D01*
G02X1393792Y73452I-1199J2752D01*
G02X1390765Y73812I-1208J2748D01*
G37*
G36*
G01X1563773Y75324D02*
G03X1563830Y74780I319J-242D01*
G02X1561652Y74549I-981J-1138D01*
G03X1561595Y75093I-319J242D01*
G02X1563773Y75324I981J1138D01*
G37*
G36*
G01X651513Y71168D02*
G03X650987I-263J-302D01*
G02X649077Y73485I-987J1132D01*
G03Y74115I-246J315D01*
G02X650987Y76432I923J1185D01*
G03X651513I263J302D01*
G02X653423Y74115I987J-1132D01*
G03Y73485I246J-315D01*
G02X651513Y71168I-923J-1185D01*
G37*
G36*
G01X724800Y66531D02*
G03X724911Y65938I314J-248D01*
G02X723100Y65599I-711J-1208D01*
G03X722989Y66192I-314J248D01*
G02X722337Y67729I711J1208D01*
G03X722062Y68206I-389J94D01*
G02X723823Y69221I398J1344D01*
G03X724098Y68744I389J-94D01*
G02X724800Y66531I-398J-1344D01*
G37*
G36*
G01X1396239Y62392D02*
G02X1393639I-1300J2706D01*
G02X1389625Y66381I-1300J2706D01*
G02X1393551Y70660I2524J1625D01*
G02X1396300Y70788I1499J-2601D01*
G02X1400156Y66569I1250J-2729D01*
G02X1396239Y62392I-2617J-1471D01*
G37*
G36*
G01X657580Y43507D02*
G03X657054I-263J-302D01*
G02X655144Y45824I-987J1132D01*
G03Y46454I-246J315D01*
G02X657054Y48771I923J1185D01*
G03X657580I263J302D01*
G02X659490Y46454I987J-1132D01*
G03Y45824I246J-315D01*
G02X657580Y43507I-923J-1185D01*
G37*
G36*
G01X1363657Y44922D02*
G03X1363609Y44366I261J-303D01*
G02X1361465Y44549I-1161J-953D01*
G03X1361513Y45105I-261J303D01*
G02X1363657Y44922I1161J953D01*
G37*
G36*
G01X732808Y42554D02*
G03X732818Y41965I275J-290D01*
G02X730922Y41933I-931J-1049D01*
G03X730912Y42522I-275J290D01*
G02X732808Y42554I931J1049D01*
G37*
G36*
G01X1350782Y39408D02*
G03X1350159Y39379I-300J-265D01*
G02X1350071Y41258I-1214J885D01*
G03X1350694Y41287I300J265D01*
G02X1350782Y39408I1214J-885D01*
G37*
G36*
G01X686498Y45656D02*
G02X686275Y40237I-1398J-2657D01*
G02X683582Y40410I-1371J-294D01*
G02X683558Y45576I1518J2590D01*
G03X683719Y46081I-205J344D01*
G02X686311Y46152I1281J569D01*
G03X686498Y45656I374J-142D01*
G37*
G36*
G01X1368673Y36704D02*
G03X1368127I-273J-292D01*
G02Y38896I-1027J1096D01*
G03X1368673I273J292D01*
G02X1370826Y38794I1027J-1096D01*
G03X1371408Y38776I299J265D01*
G02X1371398Y36805I992J-991D01*
G03X1370815Y36793I-286J-280D01*
G02X1368673Y36704I-1115J1007D01*
G37*
G36*
G01X1380603Y27537D02*
G03X1381116Y27305I374J143D01*
G02X1380239Y25361I526J-1407D01*
G03X1379726Y25593I-374J-143D01*
G02X1380603Y27537I-526J1407D01*
G37*
G36*
G01X1358027Y16334D02*
G03X1357725Y15854I88J-390D01*
G02X1355934Y16983I-1464J-337D01*
G03X1356236Y17463I-88J390D01*
G02X1356241Y18157I1464J336D01*
G03X1355947Y18640I-389J94D01*
G02X1355997Y21571I353J1460D01*
G03X1356313Y22013I-81J392D01*
G02X1356304Y22298I1490J190D01*
G03X1356004Y22712I-399J27D01*
G02X1356147Y25651I373J1455D01*
G03X1356314Y25879I-31J198D01*
G02X1356308Y26274I1486J220D01*
G03X1355972Y26715I-397J46D01*
G02X1356043Y29694I227J1485D01*
G03X1356400Y30114I-42J398D01*
G02X1356399Y30147I1501J62D01*
G03X1356054Y30529I-400J-14D01*
G02X1355129Y33004I207J1488D01*
G03Y33530I-302J263D01*
G02X1355871Y35967I1132J987D01*
G03X1356107Y36564I-104J386D01*
G02X1358273Y38310I1193J736D01*
G03X1358827I277J288D01*
G02X1360854Y36375I973J-1010D01*
G03X1360861Y35839I300J-264D01*
G02X1360893Y33830I-1100J-1022D01*
G03Y33304I302J-263D01*
G02X1359784Y30815I-1132J-987D01*
G03X1359392Y30370I5J-400D01*
G02X1358057Y28706I-1492J-170D01*
G03X1357700Y28286I42J-398D01*
G02X1357692Y28026I-1500J-84D01*
G03X1358028Y27585I397J-46D01*
G02X1358029Y24616I-228J-1485D01*
G03X1357862Y24388I31J-198D01*
G02X1357875Y24069I-1486J-220D01*
G03X1358175Y23655I399J-27D01*
G02X1358106Y20729I-372J-1455D01*
G03X1357790Y20287I81J-392D01*
G02X1357759Y19743I-1490J-188D01*
G03X1358053Y19260I389J-94D01*
G02X1358027Y16334I-353J-1460D01*
G37*
G36*
G01X1375619Y17927D02*
G02X1375654Y12428I1223J-2742D01*
G02X1372919Y12576I-1223J2742D01*
G02X1369148Y16600I-1019J2824D01*
G02X1369174Y19057I2752J1200D01*
G02X1369198Y21398I2776J1142D01*
G02X1370450Y25222I2743J1219D01*
G03X1370533Y25479I-99J174D01*
G02X1370768Y27087I1367J621D01*
G03Y27613I-302J263D01*
G02Y29587I1132J987D01*
G03Y30113I-302J263D01*
G02X1373032I1132J987D01*
G03Y29587I302J-263D01*
G02Y27613I-1132J-987D01*
G03Y27087I302J-263D01*
G02X1373282Y25511I-1132J-987D01*
G03X1373370Y25257I184J-79D01*
G02X1374693Y21419I-1429J-2640D01*
G02X1374676Y18943I-2743J-1219D01*
G02X1374883Y18138I-2776J-1143D01*
G02X1375619Y17927I-453J-2968D01*
G37*
G36*
G01X1368378Y4805D02*
G03X1367800I-289J-277D01*
G02Y6747I-1011J971D01*
G03X1368378I289J277D01*
G02Y4805I1011J-971D01*
G37*
G36*
G01X1381506Y-3690D02*
G03X1381956Y-4056I399J31D01*
G02X1380653Y-5660I195J-1489D01*
G03X1380203Y-5294I-399J-31D01*
G02X1381506Y-3690I-195J1489D01*
G37*
G36*
G01X1347152Y-19392D02*
G03X1346567Y-19406I-286J-280D01*
G02X1346520Y-17495I-1049J930D01*
G03X1347105Y-17481I286J280D01*
G02X1347144Y-17438I1058J-920D01*
G03Y-16884I-288J277D01*
G02X1349164I1010J973D01*
G03Y-17438I288J-277D01*
G02X1349248Y-17534I-1012J-970D01*
G03X1349560I156J125D01*
G02X1351627Y-17401I1094J-877D01*
G03X1352181I277J288D01*
G02Y-19421I973J-1010D01*
G03X1351627I-277J-288D01*
G02X1349681I-973J1010D01*
G03X1349127I-277J-288D01*
G02X1347152Y-19392I-973J1010D01*
G37*
G36*
G01X1375155Y-17824D02*
G02X1373099Y-17881I-1054J924D01*
G03X1372569Y-17844I-286J-280D01*
G02X1370533Y-15654I-916J1190D01*
G03X1370522Y-15110I-299J266D01*
G02X1370449Y-13110I1083J1041D01*
G03X1370447Y-12598I-308J255D01*
G02X1370460Y-10653I1151J965D01*
G03X1370467Y-10139I-303J261D01*
G02X1370846Y-7911I1165J948D01*
G03X1370837Y-7224I-209J341D01*
G02X1370457Y-4937I752J1300D01*
G03Y-4411I-302J263D01*
G02X1370487Y-2403I1132J987D01*
G03X1370500Y-1874I-293J272D01*
G02X1372752Y-1928I1150J967D01*
G03X1372739Y-2457I293J-272D01*
G02X1372721Y-4411I-1150J-966D01*
G03Y-4937I302J-263D01*
G02X1372375Y-7204I-1132J-987D01*
G03X1372384Y-7891I209J-341D01*
G02X1372770Y-10171I-752J-1300D01*
G03X1372763Y-10685I303J-261D01*
G02X1372754Y-12592I-1165J-948D01*
G03X1372756Y-13104I308J-255D01*
G02X1372725Y-15069I-1151J-965D01*
G03X1372736Y-15613I299J-266D01*
G02X1372788Y-15670I-1083J-1041D01*
G03X1373314Y-15739I302J262D01*
G02X1375083Y-15900I786J-1161D01*
G03X1375664Y-15878I280J285D01*
G02X1375736Y-17802I1055J-924D01*
G03X1375155Y-17824I-280J-285D01*
G37*
G36*
G01X1357442Y-16338D02*
G02X1355673Y-15031I-1492J-169D01*
G03X1355997Y-14593I-74J393D01*
G02X1356001Y-14217I1492J172D01*
G03X1355656Y-13765I-396J55D01*
G02X1355795Y-10774I191J1490D01*
G03X1355988Y-10568I-7J200D01*
G02X1355990Y-10428I1501J49D01*
G03X1355654Y-10007I-399J26D01*
G02X1355706Y-7033I235J1483D01*
G03X1356042Y-6528I-49J397D01*
G02X1356010Y-5860I1447J404D01*
G03X1355695Y-5397I-393J71D01*
G02X1355676Y-2455I294J1473D01*
G03X1355991Y-2034I-84J391D01*
G02X1355988Y-1885I1498J105D01*
G03X1355664Y-1481I-400J11D01*
G02X1354818Y980I286J1474D01*
G03Y1506I-302J263D01*
G02X1355957Y3995I1132J987D01*
G03X1356323Y4560I2J400D01*
G02X1358872Y4551I1277J580D01*
G03X1359280Y3985I363J-168D01*
G02X1360582Y1506I170J-1492D01*
G03Y980I302J-263D01*
G02X1359403Y-1508I-1132J-987D01*
G03X1358991Y-1911I-12J-400D01*
G02X1357802Y-3393I-1502J-13D01*
G03X1357487Y-3814I84J-391D01*
G02X1357468Y-4188I-1498J-111D01*
G03X1357783Y-4651I393J-71D01*
G02X1357672Y-7615I-294J-1473D01*
G03X1357336Y-8120I49J-397D01*
G02X1357388Y-8620I-1447J-403D01*
G03X1357724Y-9041I399J-26D01*
G02X1357541Y-12025I-236J-1483D01*
G03X1357348Y-12231I7J-200D01*
G02X1357335Y-12482I-1501J-48D01*
G03X1357680Y-12934I396J-55D01*
G02X1357766Y-15900I-191J-1490D01*
G03X1357442Y-16338I74J-393D01*
G37*
G36*
G01X1381208Y983D02*
G02X1379849Y831I-531J-1405D01*
G03X1379770Y1539I-220J334D01*
G02X1379186Y3952I530J1405D01*
G03X1379169Y4507I-296J269D01*
G02X1381333Y4573I1050J1074D01*
G03X1381350Y4018I296J-269D01*
G02X1381129Y1691I-1050J-1074D01*
G03X1381208Y983I220J-334D01*
G37*
G36*
G01X1376618Y5814D02*
G02X1375228Y5634I-524J-1408D01*
G03X1375148Y6331I-230J327D01*
G02X1376517Y6508I528J1299D01*
G03X1376618Y5814I241J-319D01*
G37*
G36*
G01X717821Y39557D02*
G02X715736Y37718I-921J-1057D01*
G03X715097Y37752I-332J-223D01*
G02X712873Y37851I-1074J901D01*
G03X712224Y37862I-328J-228D01*
G02X710054Y39634I-1123J839D01*
G03Y40166I-298J266D01*
G02X712250Y41902I1046J933D01*
G03X712899Y41891I328J228D01*
G02X713154Y42154I1126J-836D01*
G03X713149Y42786I-247J314D01*
G02X713067Y44947I851J1114D01*
G03X712995Y45595I-266J298D01*
G02X714647Y47831I679J1227D01*
G03X715203I278J288D01*
G02X716403Y48205I973J-1009D01*
G03X716866Y48644I65J395D01*
G02X721049Y51722I2984J326D01*
G02X724896Y47471I1263J-2723D01*
G02X722547Y46006I-1293J-543D01*
G02X722215Y45999I-229J2993D01*
G02X720085Y45977I-1074J901D01*
G02X719635Y45976I-232J2993D01*
G02X717699Y45847I-1035J945D01*
G03X717161Y45825I-257J-307D01*
G02X717105Y45772I-991J991D01*
G03X717222Y45101I265J-299D01*
G02X717628Y42749I-522J-1301D01*
G03X717637Y42141I264J-300D01*
G02X717786Y40126I-895J-1079D01*
G03X717821Y39557I298J-267D01*
G37*
G36*
G01X1407451Y44314D02*
G02X1405746Y44387I-905J-1198D01*
G03X1405786Y45035I-213J338D01*
G02X1407466Y44963I888J1085D01*
G03X1407451Y44314I226J-330D01*
G37*
G36*
G01X1412322Y44402D02*
G02X1410529Y44222I-776J-1286D01*
G03X1410479Y44849I-271J294D01*
G02X1412246Y45027I775J1169D01*
G03X1412322Y44402I283J-283D01*
G37*
G36*
G01X1380607Y44908D02*
G02X1377608Y45072I-1497J125D01*
G03X1377162Y45479I-400J10D01*
G02X1378491Y46932I-173J1492D01*
G03X1378937Y46525I400J-10D01*
G02X1379835Y46349I174J-1492D01*
G03X1380425Y46651I193J350D01*
G02X1381186Y45232I1392J-167D01*
G03X1380607Y44908I-180J-357D01*
G37*
G36*
G01X664412Y46340D02*
G02X662559Y46356I-936J-1044D01*
G03X662564Y46956I-262J302D01*
G02X664667Y48777I936J1044D01*
G03X665333I333J222D01*
G02Y47223I1167J-777D01*
G03X664667I-333J-222D01*
G02X664417Y46940I-1166J778D01*
G03X664412Y46340I262J-302D01*
G37*
G36*
G01X1371355Y50196D02*
G02X1370408Y48784I555J-1396D01*
G03X1369875Y49157I-400J-4D01*
G02X1370808Y50548I-467J1322D01*
G03X1371355Y50196I399J20D01*
G37*
G36*
G01X1398290Y52158D02*
G02X1396499Y51982I-790J-1158D01*
G03X1396312Y52649I-286J280D01*
G02X1395800Y52830I740J2909D01*
G02X1393300I-1250J2729D01*
G02X1389228Y56583I-1250J2729D01*
G03X1388916Y57115I-376J137D01*
G02X1389356Y59884I222J1384D01*
G02X1393300Y61288I2694J-1325D01*
G02X1395800I1250J-2729D01*
G02X1399650Y57059I1250J-2729D01*
G02X1398343Y52850I-2600J-1500D01*
G03X1398290Y52158I172J-361D01*
G37*
G36*
G01X1408317Y52082D02*
G02X1406373Y54026I-1167J777D01*
G03Y54692I-222J333D01*
G02Y57026I777J1167D01*
G03Y57692I-222J333D01*
G02X1408317Y59636I777J1167D01*
G03X1408983I333J222D01*
G02X1410927Y57692I1167J-777D01*
G03Y57026I222J-333D01*
G02Y54692I-777J-1167D01*
G03Y54026I222J-333D01*
G02X1408983Y52082I-777J-1167D01*
G03X1408317I-333J-222D01*
G37*
G36*
G01X714619Y54213D02*
G02X712577Y54229I-1029J-953D01*
G03X712581Y54777I-289J276D01*
G02X712619Y56722I1029J953D01*
G03X712622Y57286I-282J284D01*
G02X712689Y59319I998J985D01*
G03X712703Y59905I-265J299D01*
G02X712580Y61779I977J1005D01*
G03X712440Y62388I-314J248D01*
G02X712012Y62707I609J1263D01*
G03X711433Y62720I-296J-269D01*
G02X711478Y64653I-993J990D01*
G03X712057Y64640I296J269D01*
G02X714150Y62781I993J-990D01*
G03X714290Y62172I314J-248D01*
G02X715056Y61180I-610J-1262D01*
G03X715526Y60865I392J77D01*
G02X716814Y58521I274J-1375D01*
G03Y57969I289J-276D01*
G02X715449Y55643I-1014J-969D01*
G03X714963Y55361I-100J-387D01*
G02X714623Y54761I-1352J370D01*
G03X714619Y54213I289J-276D01*
G37*
G36*
G01X1382757Y58993D02*
G02X1381727Y57963I414J-1444D01*
G03X1381244Y58461I-384J110D01*
G02X1382259Y59476I-344J1359D01*
G03X1382757Y58993I388J-99D01*
G37*
G36*
G01X1410417Y64582D02*
G02X1408473Y66526I-1167J777D01*
G03Y67192I-222J333D01*
G02X1408380Y69459I777J1167D01*
G03X1408358Y70102I-248J313D01*
G02X1410317Y72036I792J1157D01*
G03X1410983I333J222D01*
G02X1413020Y70159I1167J-778D01*
G03X1413042Y69516I248J-313D01*
G02X1413027Y67192I-792J-1157D01*
G03Y66526I222J-333D01*
G02X1411083Y64582I-777J-1167D01*
G03X1410417I-333J-222D01*
G37*
G36*
G01X664867Y64823D02*
G02Y66377I-1167J777D01*
G03X665533I333J222D01*
G02Y64823I1167J-777D01*
G03X664867I-333J-222D01*
G37*
G36*
G01X656587Y64968D02*
G02X654677Y67285I-987J1132D01*
G03Y67915I-246J315D01*
G02X655252Y70561I923J1185D01*
G03X655442Y71234I-92J389D01*
G02X655577Y73485I1058J1066D01*
G03Y74115I-246J315D01*
G02X657487Y76432I923J1185D01*
G03X658013I263J302D01*
G02X659923Y74115I987J-1132D01*
G03Y73485I246J-315D01*
G02X659348Y70839I-923J-1185D01*
G03X659158Y70166I92J-389D01*
G02X659023Y67915I-1058J-1066D01*
G03Y67285I246J-315D01*
G02X657113Y64968I-923J-1185D01*
G03X656587I-263J-302D01*
G37*
G36*
G01X704753Y68146D02*
G02X703871Y65776I127J-1396D01*
G03X703316Y65796I-288J-277D01*
G02X701407Y65830I-936J1044D01*
G03X700853I-277J-288D01*
G02X698905Y65832I-973J1010D01*
G03X698364Y65845I-278J-288D01*
G02X696449Y65909I-923J1055D01*
G03X695907Y65931I-283J-283D01*
G02X695991Y67991I-907J1069D01*
G03X696533Y67969I283J283D01*
G02X698415Y67908I907J-1069D01*
G03X698956Y67895I278J288D01*
G02X699312Y68122I923J-1055D01*
G03X699480Y68712I-163J365D01*
G02X699597Y70436I1160J787D01*
G03X699534Y71027I-298J267D01*
G02X699335Y71204I828J1131D01*
G03X698755Y71209I-292J-273D01*
G02X696632Y71334I-1008J975D01*
G03X696003Y71342I-318J-243D01*
G02X696025Y73070I-1093J878D01*
G03X696654Y73062I318J243D01*
G02X698772Y73140I1093J-878D01*
G03X699352Y73135I292J273D01*
G02X701403Y71224I1008J-975D01*
G03X701466Y70633I298J-267D01*
G02X701654Y70468I-827J-1132D01*
G03X702204Y70442I289J277D01*
G02X704362Y68730I916J-1062D01*
G03X704753Y68146I354J-186D01*
G37*
G36*
G01X666267Y67823D02*
G02Y69377I-1167J777D01*
G03X666933I333J222D01*
G02Y67823I1167J-777D01*
G03X666267I-333J-222D01*
G37*
G36*
G01X1884509Y77337D02*
G02X1881914Y75824I-1309J-737D01*
G03X1881274Y75884I-342J-207D01*
G02X1879009Y77509I-1044J936D01*
G03X1878847Y78059I-348J196D01*
G02X1880473Y80310I654J1241D01*
G03X1881027I277J288D01*
G02X1882973I973J-1010D01*
G03X1883527I277J288D01*
G02X1884778Y77926I973J-1010D01*
G03X1884509Y77337I79J-392D01*
G37*
G36*
G01X6314Y78585D02*
G02X4763Y78637I-815J-1141D01*
G03X4786Y79303I-210J341D01*
G02X6337Y79251I815J1141D01*
G03X6314Y78585I210J-341D01*
G37*
G36*
G01X12726Y79724D02*
G02X10804Y79558I-862J-1230D01*
G03X10767Y80158I-282J284D01*
G02X10652Y80257I856J1111D01*
G03X10098I-277J-288D01*
G02X8520Y82532I-972J1010D01*
G03X8543Y83242I-172J361D01*
G02X8187Y83524I681J1226D01*
G03X7583Y83509I-296J-269D01*
G02X7538Y85343I-1083J891D01*
G03X8142Y85358I296J269D01*
G02X10198Y85477I1083J-891D01*
G03X10752I277J288D01*
G02X12330Y83202I972J-1010D01*
G03X12307Y82492I172J-361D01*
G02X12660Y80321I-682J-1225D01*
G03X12726Y79724I295J-269D01*
G37*
G36*
G01X734458Y83544D02*
G02X734501Y81795I1242J-844D01*
G03X733861Y81792I-319J-241D01*
G02X733818Y83515I-1127J834D01*
G03X734458Y83544I309J254D01*
G37*
G36*
G01X754099Y83008D02*
G02X751591Y84535I-1419J492D01*
G03X751574Y85103I-290J276D01*
G02X753689Y85165I1026J1097D01*
G03X753706Y84597I290J-276D01*
G02X753780Y84523I-1024J-1098D01*
G03X754123Y84622I146J136D01*
G02X754704Y83207I1377J-261D01*
G03X754099Y83008I-227J-330D01*
G37*
G36*
G01X1862259Y83697D02*
G02Y85321I-1264J812D01*
G03X1862931I336J216D01*
G02X1863397Y85782I1264J-812D01*
G03X1863400Y86458I-212J339D01*
G02X1865006Y86451I809J1266D01*
G03X1865003Y85775I212J-339D01*
G02X1862931Y83697I-808J-1266D01*
G03X1862259I-336J-216D01*
G37*
G36*
G01X714182Y87090D02*
G02X712274Y86956I-882J-1090D01*
G03X712233Y87539I-293J272D01*
G02X714330Y89329I882J1090D01*
G03X715030Y89341I347J199D01*
G02X715053Y87983I1238J-658D01*
G03X714353Y87971I-347J-199D01*
G02X714141Y87673I-1239J657D01*
G03X714182Y87090I293J-272D01*
G37*
G36*
G01X1366495Y87347D02*
G02X1366438Y85635I1205J-897D01*
G03X1365791Y85669I-336J-217D01*
G02X1365847Y87356I-1091J881D01*
G03X1366495Y87347I327J230D01*
G37*
G36*
G01X707312Y87073D02*
G02X704606Y86976I-1340J-413D01*
G03X704134Y87458I-389J91D01*
G02X705211Y88514I-289J1372D01*
G03X705683Y88032I389J-91D01*
G02X705688Y88033I277J-1374D01*
G03X705989Y88542I-81J392D01*
G02X707613Y87582I1340J413D01*
G03X707312Y87073I81J-392D01*
G37*
G36*
G01X7750Y87098D02*
G02X7648Y88832I-1150J802D01*
G03X8275Y88869I299J265D01*
G02X10398Y89077I1150J-802D01*
G03X10952I277J288D01*
G02Y87057I973J-1010D01*
G03X10398I-277J-288D01*
G02X8377Y87135I-973J1010D01*
G03X7750Y87098I-299J-265D01*
G37*
G36*
G01X699100Y90315D02*
G02X698399Y89052I700J-1215D01*
G03X697800Y89385I-400J-14D01*
G02X698501Y90648I-700J1215D01*
G03X699100Y90315I400J14D01*
G37*
G36*
G01X45388Y101035D02*
G03X44836Y101404I-400J0D01*
G02X45231Y103748I-536J1296D01*
G03X45790Y103776I265J299D01*
G02X46832Y104260I1110J-1026D01*
G03X47211Y104713I-18J400D01*
G02X49277Y106128I1389J187D01*
G03X49870Y106478I193J350D01*
G01Y107971D01*
G03X49299Y108332I-400J-1D01*
G02X47310Y109786I-599J1268D01*
G03X46911Y110239I-396J53D01*
G02X45866Y110648I-11J1511D01*
G03X45283Y110610I-274J-292D01*
G02X44814Y112761I-1083J890D01*
G03X45388Y113120I174J360D01*
G01Y115180D01*
G03X44814Y115539I-400J-1D01*
G02X45210Y117772I-614J1261D01*
G03X45792Y117778I288J278D01*
G02X46990Y118259I1108J-1028D01*
G03X47411Y118712I25J399D01*
G02X49467Y120133I1389J188D01*
G03X50058Y120485I191J352D01*
G01Y121865D01*
G03X49489Y122228I-400J0D01*
G02X47525Y123774I-589J1272D01*
G03X47084Y124250I-392J79D01*
G02X45871Y124643I-184J1500D01*
G03X45310Y124628I-273J-293D01*
G02X44836Y126896I-1010J972D01*
G03X45388Y127265I152J369D01*
G01Y129080D01*
G03X44814Y129439I-400J-1D01*
G02X45173Y131709I-614J1260D01*
G03X45754Y131736I278J288D01*
G02X47057Y132253I1145J-986D01*
G03X47499Y132640I42J398D01*
G02X49489Y133872I1401J-40D01*
G03X50057Y134235I168J363D01*
G01Y136016D01*
G03X49467Y136367I-400J-1D01*
G02X47411Y137788I-667J1233D01*
G03X46990Y138241I-396J54D01*
G02X45902Y138615I-90J1509D01*
G03X45319Y138555I-264J-301D01*
G02X44814Y140661I-1119J845D01*
G03X45388Y141020I174J360D01*
G01Y143135D01*
G03X44836Y143504I-400J0D01*
G02X45270Y145812I-536J1296D01*
G03X45830Y145818I277J289D01*
G02X48412Y144760I1070J-1068D01*
G01Y139665D01*
X48402Y139581D01*
G02X48386Y139475I-1502J172D01*
G03X48784Y139002I393J-73D01*
G02X49768Y138614I16J-1402D01*
G03X50364Y138662I277J289D01*
G02X53080Y137760I1205J-912D01*
G01Y132665D01*
X53071Y132581D01*
G02X50511Y131671I-1502J169D01*
G03X49935Y131655I-280J-286D01*
G02X48831Y131200I-1035J945D01*
G03X48411Y130790I-20J-400D01*
G02X48412Y130760I-1510J-65D01*
G01Y125665D01*
X48402Y125581D01*
G02X48368Y125391I-1502J171D01*
G03X48789Y124898I389J-94D01*
G02X49786Y124586I110J-1398D01*
G03X50359Y124656I253J310D01*
G02X53080Y123760I1210J-906D01*
G01Y118665D01*
X53071Y118581D01*
G02X50364Y117838I-1502J169D01*
G03X49768Y117886I-319J-241D01*
G02X48784Y117498I-968J1014D01*
G03X48386Y117025I-5J-400D01*
G02X48412Y116760I-1486J-280D01*
G01Y111665D01*
X48402Y111581D01*
G02X48386Y111473I-1502J167D01*
G03X48762Y111001I393J-73D01*
G02X49628Y110651I-62J-1401D01*
G03X50205Y110699I266J299D01*
G02X52892Y109760I1176J-949D01*
G01Y104665D01*
X52883Y104581D01*
G02X50172Y103843I-1502J169D01*
G03X49574Y103891I-320J-240D01*
G02X48738Y103505I-973J1009D01*
G03X48385Y103032I40J-398D01*
G02X48412Y102760I-1485J-285D01*
G01Y97665D01*
X48402Y97581D01*
G02X48369Y97395I-1502J171D01*
G03X48745Y96901I389J-94D01*
G02X49592Y96581I-45J-1401D01*
G03X50168Y96651I255J309D01*
G02X52892Y95760I1213J-901D01*
G01Y90665D01*
X52883Y90581D01*
G02X50280Y89714I-1502J169D01*
G03X49703Y89720I-291J-274D01*
G02X49299Y91968I-1003J980D01*
G03X49870Y92329I171J362D01*
G01Y93871D01*
G03X49299Y94232I-400J-1D01*
G02X47323Y95764I-599J1268D01*
G03X46924Y96239I-393J75D01*
G02X45718Y96807I-25J1511D01*
G03X45116Y96834I-313J-249D01*
G02X44791Y99020I-1016J966D01*
G03X45388Y99367I197J348D01*
G01Y101035D01*
G37*
G36*
G01X1862145Y90487D02*
G02X1862121Y91926I-1330J698D01*
G03X1862823Y91938I348J198D01*
G02X1862847Y90499I1330J-698D01*
G03X1862145Y90487I-348J-198D01*
G37*
G36*
G01X1377318Y92950D02*
G02X1377200Y91168I1146J-971D01*
G03X1376558Y91211I-337J-216D01*
G02X1376676Y92993I-1146J971D01*
G03X1377318Y92950I337J216D01*
G37*
G36*
G01X679467Y91853D02*
G02X677290Y93603I-1167J778D01*
G03Y94157I-288J277D01*
G02X677173Y94296I1012J971D01*
G03X676839Y94279I-161J-118D01*
G02X676619Y95982I-1209J710D01*
G03X677211Y96013I282J284D01*
G02X679467Y95907I1089J-883D01*
G03X680133I333J222D01*
G02X682310Y94157I1167J-778D01*
G03Y93603I288J-277D01*
G02X682467Y93407I-1011J-971D01*
G03X683133I333J222D01*
G02Y91853I1167J-777D01*
G03X682467I-333J-222D01*
G02X680133I-1167J777D01*
G03X679467I-333J-222D01*
G37*
G36*
G01X733247Y93211D02*
G02X731940Y94192I-1337J-421D01*
G03X732325Y94726I8J400D01*
G02X733652Y93731I1415J504D01*
G03X733247Y93211I-23J-400D01*
G37*
G36*
G01X1363012Y95261D02*
G02X1360588Y96453I-1378J258D01*
G03Y96985I-298J266D01*
G02X1362680I1046J934D01*
G03Y96453I298J-266D01*
G02X1362959Y95976I-1047J-932D01*
G03X1363342Y96091I189J64D01*
G02X1363693Y95465I1358J350D01*
G03X1363012Y95261I-288J-278D01*
G37*
G36*
G01X64176Y137752D02*
G02X64231Y138155I1511J-1D01*
G03X63855Y138662I-385J107D01*
G02X62833Y139141I34J1402D01*
G03X62176Y139060I-301J-263D01*
G02X59320Y139750I-1345J690D01*
G01Y144750D01*
G02X62075Y145609I1511J0D01*
G03X62731Y145606I329J227D01*
G02X62995Y143711I1147J-806D01*
G03X62342Y143401I-253J-310D01*
G01Y141454D01*
G03X62997Y141146I400J1D01*
G02X65254Y139750I891J-1082D01*
G03X65653Y139261I390J-89D01*
G02X66891Y138664I34J-1511D01*
G03X67525Y138660I319J242D01*
G02X67828Y136652I1107J-860D01*
G03X67198Y136324I-230J-328D01*
G01Y134103D01*
G03X67819Y133770I400J0D01*
G02X67470Y131759I773J-1170D01*
G03X66844Y131777I-320J-240D01*
G02X65557Y131244I-1157J973D01*
G03X65126Y130792I-35J-398D01*
G02X62963Y129433I-1389J-190D01*
G03X62342Y129100I-221J-334D01*
G01Y125665D01*
X62333Y125581D01*
G02X62277Y125309I-1502J168D01*
G03X62629Y124793I382J-117D01*
G02X63486Y124414I-106J-1398D01*
G03X64105Y124501I275J291D01*
G02X66672Y124554I1300J-771D01*
G03X67357Y124579I335J218D01*
G02X67598Y122903I1227J-679D01*
G03X66916Y122619I-282J-284D01*
G01Y119887D01*
G03X67613Y119619I400J0D01*
G02X67428Y118000I1041J-939D01*
G03X66728Y117999I-350J-194D01*
G02X65351Y117219I-1323J731D01*
G03X64947Y116729I-15J-400D01*
G02X62827Y115228I-1365J-320D01*
G03X62212Y114891I-215J-337D01*
G01Y111665D01*
X62202Y111581D01*
G02X62150Y111324I-1502J170D01*
G03X62509Y110812I384J-113D01*
G02X63424Y110393I-87J-1399D01*
G03X64060Y110480I286J280D01*
G02X66073Y111095I1324J-730D01*
G03X66643Y111351I183J356D01*
G02X67452Y109710I1357J-351D01*
G03X66896Y109341I-156J-368D01*
G01Y104665D01*
X66886Y104581D01*
G02X66796Y104212I-1502J171D01*
G03X67044Y103690I374J-142D01*
G02X65264Y102784I-444J-1330D01*
G03X64987Y103291I-381J121D01*
G02X64079Y103987I397J1459D01*
G03X63461Y104077I-345J-202D01*
G02X62602Y103702I-958J1023D01*
G03X62248Y103187I29J-399D01*
G02X62312Y102760I-1447J-435D01*
G01Y99010D01*
G03X62967Y98702I400J1D01*
G02X62686Y96851I891J-1082D01*
G03X62027Y96866I-335J-219D01*
G02X59290Y97750I-1226J884D01*
G01Y102751D01*
G02X60764Y104261I1511J-1D01*
G03X61142Y104758I-10J400D01*
G02X63257Y106281I1360J342D01*
G03X63872Y106618I215J337D01*
G01Y107949D01*
G03X63239Y108274I-400J0D01*
G02X61060Y109744I-817J1139D01*
G03X60677Y110239I-389J95D01*
G02X59188Y111750I22J1511D01*
G01Y116750D01*
G02X62002Y117518I1512J0D01*
G03X62621Y117430I345J203D01*
G02X63569Y117811I961J-1021D01*
G03X63950Y118319I-4J400D01*
G02X63894Y118730I1455J408D01*
G01Y121876D01*
G03X63278Y122213I-400J0D01*
G02X61165Y123741I-754J1182D01*
G03X60789Y124239I-388J98D01*
G02X59320Y125750I43J1511D01*
G01Y130750D01*
G02X62082Y131599I1511J0D01*
G03X62706Y131553I330J225D01*
G02X63792Y132003I1030J-951D01*
G03X64201Y132475I16J400D01*
G02X64176Y132747I1486J274D01*
G01Y137752D01*
G37*
G36*
G01X1945567Y98870D02*
G02X1945553Y97453I1203J-720D01*
G03X1944863Y97460I-347J-199D01*
G02X1942476Y98931I-1202J721D01*
G03X1942249Y99530I-338J215D01*
G02X1943821Y100126I388J1347D01*
G03X1944048Y99527I338J-215D01*
G02X1944877Y98877I-387J-1348D01*
G03X1945567Y98870I347J199D01*
G37*
G36*
G01X1883951Y99405D02*
G02X1883056Y100778I-1401J65D01*
G03X1883600Y101147I144J373D01*
G02X1885894Y102410I1502J-13D01*
G03X1886488Y102634I211J340D01*
G02X1887007Y103362I1342J-407D01*
G03X1886924Y104055I-235J323D01*
G02X1888342Y104202I573J1389D01*
G03X1888403Y103506I225J-331D01*
G02X1887140Y101006I-573J-1279D01*
G03X1886556Y100758I-197J-348D01*
G02X1884508Y99754I-1454J376D01*
G03X1883951Y99405I-158J-367D01*
G37*
G36*
G01X-7480Y103132D02*
G03X-6213Y103535I-2J2199D01*
G02X-2154Y102201I1488J-2314D01*
G03X-1414Y102183I374J143D01*
G02X2988I2201J-962D01*
G03X3728Y102201I366J161D01*
G02X7771Y103545I2571J-980D01*
G03X9025Y103132I1283J1786D01*
G01X9056D01*
G03X10323Y103535I-2J2199D01*
G02X14382Y102201I1488J-2314D01*
G03X15122Y102183I374J143D01*
G02X19524I2201J-962D01*
G03X20264Y102201I366J161D01*
G02X24307Y103545I2571J-980D01*
G03X25561Y103132I1283J1786D01*
G01X25591D01*
G03X26858Y103535I-2J2199D01*
G02X30917Y102201I1488J-2314D01*
G03X31657Y102183I374J143D01*
G02Y100259I2201J-962D01*
G03X30917Y100241I-366J-161D01*
G02X26874Y98897I-2571J980D01*
G03X25620Y99310I-1283J-1786D01*
G01X25590D01*
G03X24323Y98907I2J-2199D01*
G02X20264Y100241I-1488J2314D01*
G03X19524Y100259I-374J-143D01*
G02X15122I-2201J962D01*
G03X14382Y100241I-366J-161D01*
G02X10339Y98897I-2571J980D01*
G03X9085Y99310I-1283J-1786D01*
G01X9054D01*
G03X7787Y98907I2J-2199D01*
G02X3728Y100241I-1488J2314D01*
G03X2988Y100259I-374J-143D01*
G02X-1414I-2201J962D01*
G03X-2154Y100241I-366J-161D01*
G02X-6197Y98897I-2571J980D01*
G03X-7451Y99310I-1283J-1786D01*
G01X-7481D01*
G03X-8748Y98907I2J-2199D01*
G02X-12807Y100241I-1488J2314D01*
G03X-13547Y100259I-374J-143D01*
G02Y102183I-2201J962D01*
G03X-12807Y102201I366J161D01*
G02X-8764Y103545I2571J-980D01*
G03X-7510Y103132I1283J1786D01*
G01X-7480D01*
G37*
G36*
G01X1346235Y101140D02*
G02X1344156Y101022I-978J-1140D01*
G03X1343997Y101671I-293J272D01*
G02X1344107Y107366I1003J2829D01*
G02X1346766Y106927I1393J163D01*
G02X1346319Y101803I-1766J-2427D01*
G03X1346235Y101140I176J-359D01*
G37*
G36*
G01X1396336Y101886D02*
G02X1394316I-1010J-973D01*
G03Y102440I-288J277D01*
G02X1394374Y104443I1010J973D01*
G03X1394379Y105026I-271J294D01*
G02X1394090Y106661I968J1014D01*
G03X1393857Y107217I-359J176D01*
G02X1393169Y107717I441J1331D01*
G03X1392517Y107705I-322J-237D01*
G02X1392488Y109327I-1158J791D01*
G03X1393140Y109339I322J237D01*
G02X1393502Y109702I1157J-792D01*
G03X1393504Y110359I-227J329D01*
G02X1395174Y112610I806J1147D01*
G03X1395814Y112854I246J315D01*
G02X1396329Y111498I1379J-252D01*
G03X1395689Y111254I-246J-315D01*
G02X1395106Y110352I-1379J252D01*
G03X1395104Y109695I227J-329D01*
G02X1395555Y107927I-806J-1147D01*
G03X1395788Y107371I359J-176D01*
G02X1396376Y106992I-442J-1331D01*
G03X1396954Y106983I293J272D01*
G02X1398919Y104983I997J-986D01*
G03X1398928Y104395I276J-290D01*
G02X1396934Y102433I-934J-1045D01*
G03X1396342Y102447I-302J-262D01*
G02X1396336Y102440I-1068J909D01*
G03Y101886I288J-277D01*
G37*
G36*
G01X74915Y103760D02*
G02Y106240I-2115J1240D01*
G03X75606I346J202D01*
G02X79837Y106239I2115J-1240D01*
G03X80527I345J202D01*
G02X84758Y106240I2116J-1239D01*
G03X85449I345J202D01*
G02X89679I2115J-1240D01*
G03X90370I346J202D01*
G02X94600I2115J-1240D01*
G03X95291I345J202D01*
G02X99522Y106239I2115J-1240D01*
G03X100212I345J202D01*
G02X104443Y106240I2116J-1239D01*
G03X105134I345J202D01*
G02Y103760I2115J-1240D01*
G03X104443I-345J-202D01*
G02X100212Y103761I-2115J1240D01*
G03X99522I-345J-202D01*
G02X95291Y103760I-2116J1239D01*
G03X94600I-345J-202D01*
G02X90370I-2115J1240D01*
G03X89679I-345J-202D01*
G02X85449I-2115J1240D01*
G03X84758I-345J-202D01*
G02X80527Y103761I-2115J1240D01*
G03X79837I-345J-202D01*
G02X75606Y103760I-2116J1239D01*
G03X74915I-345J-202D01*
G37*
G36*
G01X1324967Y103473D02*
G02X1323023Y105417I-1167J777D01*
G03Y106083I-222J333D01*
G02X1324967Y108027I777J1167D01*
G03X1325633I333J222D01*
G02X1327577Y106083I1167J-777D01*
G03Y105417I222J-333D01*
G02X1325633Y103473I-777J-1167D01*
G03X1324967I-333J-222D01*
G37*
G36*
G01X1255492Y105937D02*
G02X1252899Y105146I-1192J-737D01*
G03X1252390Y105515I-400J-16D01*
G02X1253482Y106954I-410J1445D01*
G03X1253975Y106564I400J-1D01*
G02X1254208Y106599I324J-1364D01*
G03X1254336Y106940I-13J200D01*
G02X1255742Y106537I1065J1060D01*
G03X1255492Y105937I90J-390D01*
G37*
G36*
G01X121205Y107701D02*
G02X119466Y107899I-1008J-1114D01*
G03X119551Y108534I-195J349D01*
G02X121264Y108339I982J1001D01*
G03X121205Y107701I209J-341D01*
G37*
G36*
G01X-12598Y111006D02*
G03X-11331Y111409I-2J2199D01*
G02X-7272Y110075I1488J-2314D01*
G03X-6532Y110057I374J143D01*
G02X-2130I2201J-962D01*
G03X-1390Y110075I366J161D01*
G02X2653Y111419I2571J-980D01*
G03X3907Y111006I1283J1786D01*
G01X3938D01*
G03X5205Y111409I-2J2199D01*
G02X9264Y110075I1488J-2314D01*
G03X10004Y110057I374J143D01*
G02X14405Y110058I2201J-962D01*
G03X15145Y110076I366J161D01*
G02X19188Y111419I2570J-981D01*
G03X20442Y111006I1283J1786D01*
G01X20473D01*
G03X21740Y111409I-2J2199D01*
G02X25799Y110075I1488J-2314D01*
G03X26539Y110057I374J143D01*
G02Y108133I2201J-962D01*
G03X25799Y108115I-366J-161D01*
G02X21756Y106771I-2571J980D01*
G03X20502Y107184I-1283J-1786D01*
G01X20471D01*
G03X19204Y106781I2J-2199D01*
G02X15145Y108114I-1488J2314D01*
G03X14405Y108132I-374J-143D01*
G02X10004Y108133I-2200J963D01*
G03X9264Y108115I-366J-161D01*
G02X5221Y106771I-2571J980D01*
G03X3967Y107184I-1283J-1786D01*
G01X3936D01*
G03X2669Y106781I2J-2199D01*
G02X-1390Y108115I-1488J2314D01*
G03X-2130Y108133I-374J-143D01*
G02X-6532I-2201J962D01*
G03X-7272Y108115I-366J-161D01*
G02X-11315Y106771I-2571J980D01*
G03X-12569Y107184I-1283J-1786D01*
G01X-12599D01*
G03X-13866Y106781I2J-2199D01*
G02X-13882Y111419I-1488J2314D01*
G03X-12628Y111006I1283J1786D01*
G01X-12598D01*
G37*
G36*
G01X603350Y108965D02*
G02X602992Y110681I-1250J635D01*
G03X603611Y110824I255J309D01*
G02X603974Y109082I1366J-624D01*
G03X603350Y108965I-267J-298D01*
G37*
G36*
G01X1258689Y111984D02*
G02X1256948Y112014I-889J-1084D01*
G03X1256946Y112651I-243J318D01*
G02X1256980Y115074I904J1199D01*
G03Y115726I-232J326D01*
G02X1258747Y118155I870J1224D01*
G03X1259321Y118259I238J321D01*
G02X1259721Y116334I1179J-759D01*
G03X1259152Y116201I-222J-332D01*
G02X1258720Y115726I-1301J750D01*
G03Y115074I232J-326D01*
G02X1258713Y112621I-870J-1224D01*
G03X1258689Y111984I230J-328D01*
G37*
G36*
G01X622008Y113589D02*
G02X620798Y112220I192J-1389D01*
G03X620326Y112619I-400J6D01*
G02X618552Y114062I-272J1477D01*
G03X617994Y114421I-400J-8D01*
G02X616152Y116636I-594J1379D01*
G03X615897Y117251I-332J223D01*
G02X615446Y117424I269J1376D01*
G03X614896Y117284I-206J-343D01*
G02X614442Y119292I-1294J763D01*
G03X614999Y119402I224J332D01*
G02X617359Y117889I1168J-775D01*
G03X617636Y117283I340J-211D01*
G02X618902Y115834I-236J-1483D01*
G03X619460Y115475I400J8D01*
G02X621553Y114008I594J-1379D01*
G03X622008Y113589I399J-23D01*
G37*
G36*
G01X1375250Y114376D02*
G02X1373073Y115617I-1400J74D01*
G03Y116283I-222J333D01*
G02Y118617I777J1167D01*
G03Y119283I-222J333D01*
G02Y121617I777J1167D01*
G03Y122283I-222J333D01*
G02X1374211Y124805I777J1167D01*
G03X1374711Y125138I104J386D01*
G02X1375739Y123595I1389J-188D01*
G03X1375239Y123262I-104J-386D01*
G02X1374627Y122283I-1389J188D01*
G03Y121617I222J-333D01*
G02X1374647Y121603I-794J-1155D01*
G03X1375273Y121895I228J329D01*
G02X1377446Y120596I1396J-132D01*
G03Y119930I222J-333D01*
G02X1377346Y117535I-777J-1167D01*
G03X1377219Y116944I193J-351D01*
G02X1375749Y114743I-1119J-844D01*
G03X1375250Y114376I-99J-388D01*
G37*
G36*
G01X649566Y116708D02*
G02X649105Y114797I741J-1190D01*
G03X648550Y114931I-343J-206D01*
G02X646607Y115400I-741J1190D01*
G03X646052Y115534I-343J-206D01*
G02X644209Y115857I-741J1190D01*
G03X643674Y115943I-314J-247D01*
G02X641615Y116549I-775J1169D01*
G03X640981Y116686I-366J-160D01*
G02X641327Y118291I-938J1042D01*
G03X641961Y118154I366J160D01*
G02X644001Y117979I938J-1042D01*
G03X644536Y117893I314J247D01*
G02X646513Y117445I774J-1169D01*
G03X647068Y117311I343J206D01*
G02X649011Y116842I741J-1190D01*
G03X649566Y116708I343J206D01*
G37*
G36*
G01X9056Y118880D02*
G03X10323Y119283I-2J2199D01*
G02X14382Y117949I1488J-2314D01*
G03X15122Y117931I374J143D01*
G02X19524I2201J-962D01*
G03X20264Y117949I366J161D01*
G02X24307Y119293I2571J-980D01*
G03X25561Y118880I1283J1786D01*
G01X25591D01*
G03X26858Y119283I-2J2199D01*
G02X30917Y117949I1488J-2314D01*
G03X31657Y117931I374J143D01*
G02Y116007I2201J-962D01*
G03X30917Y115989I-366J-161D01*
G02X26874Y114645I-2571J980D01*
G03X25620Y115058I-1283J-1786D01*
G01X25590D01*
G03X24323Y114655I2J-2199D01*
G02X20264Y115989I-1488J2314D01*
G03X19524Y116007I-374J-143D01*
G02X15122I-2201J962D01*
G03X14382Y115989I-366J-161D01*
G02X10339Y114645I-2571J980D01*
G03X9085Y115058I-1283J-1786D01*
G01X9054D01*
G03X7787Y114655I2J-2199D01*
G02X3728Y115989I-1488J2314D01*
G03X2988Y116007I-374J-143D01*
G02Y117931I-2201J962D01*
G03X3728Y117949I366J161D01*
G02X7771Y119293I2571J-980D01*
G03X9025Y118880I1283J1786D01*
G01X9056D01*
G37*
G36*
G01X671956Y115503D02*
G02X669054Y116278I-1453J381D01*
G03X668667Y116783I-386J105D01*
G02X669469Y119334I-2J1402D01*
G03X670042Y119458I229J328D01*
G02X672631Y118510I1207J-714D01*
G03X673146Y118061I395J-67D01*
G02X673280Y118097I430J-1334D01*
G03X673575Y118622I-82J391D01*
G02X676063Y119870I1321J471D01*
G03X676729I333J222D01*
G02X678174Y117719I1167J-777D01*
G03X677863Y117241I80J-392D01*
G02X675415Y116045I-1369J-301D01*
G03X674765Y115997I-308J-255D01*
G02X672614Y115695I-1199J727D01*
G03X671956Y115503I-271J-294D01*
G37*
G36*
G01X1403778Y117090D02*
G02X1402565Y117801I-1278J-790D01*
G03X1402922Y118410I17J399D01*
G02X1404135Y117699I1278J790D01*
G03X1403778Y117090I-17J-399D01*
G37*
G36*
G01X1398444Y117893D02*
G02X1397340Y117114I156J-1393D01*
G03X1396936Y117687I-360J175D01*
G02X1398040Y118466I-156J1393D01*
G03X1398444Y117893I360J-175D01*
G37*
G36*
G01X1554838Y121420D02*
G02X1552729Y122171I-1338J-420D01*
G03X1552686Y122863I-220J334D01*
G02X1554724Y124823I667J1346D01*
G03X1555219Y124608I365J163D01*
G02X1556146Y124604I458J-1325D01*
G03X1556663Y124864I134J377D01*
G02X1559101Y123307I1437J-437D01*
G03X1559149Y122674I267J-298D01*
G02X1557608Y122668I-766J-1174D01*
G03X1557568Y123022I-110J167D01*
G02X1557524Y123040I547J1399D01*
G03X1556995Y122806I-153J-369D01*
G02X1555321Y121927I-1318J477D01*
G03X1554838Y121420I-102J-387D01*
G37*
G36*
G01X1401422Y122341D02*
G02X1399879Y122837I-1122J-841D01*
G03X1400078Y123459I-121J381D01*
G02X1399817Y124532I1122J841D01*
G03X1399418Y124998I-394J66D01*
G02X1400783Y126168I-18J1402D01*
G03X1401182Y125702I394J-66D01*
G02X1401621Y122963I18J-1402D01*
G03X1401422Y122341I121J-381D01*
G37*
G36*
G01X654278Y120773D02*
G02Y122327I-1167J777D01*
G03X654944I333J222D01*
G02X656120Y122952I1167J-777D01*
G03X656517Y123418I3J400D01*
G02X657123Y124817I1383J232D01*
G03Y125483I-222J333D01*
G02X659067Y127427I777J1167D01*
G03X659733I333J222D01*
G02X661677Y125483I1167J-777D01*
G03Y124817I222J-333D01*
G02X659733Y122873I-777J-1167D01*
G03X659067I-333J-222D01*
G02X657891Y122248I-1167J777D01*
G03X657494Y121782I-3J-400D01*
G02X654944Y120773I-1383J-232D01*
G03X654278I-333J-222D01*
G37*
G36*
G01X648287Y121923D02*
G02Y123477I-1167J777D01*
G03X648953I333J222D01*
G02Y121923I1167J-777D01*
G03X648287I-333J-222D01*
G37*
G36*
G01X1324767Y122673D02*
G02X1322823Y124617I-1167J777D01*
G03Y125283I-222J333D01*
G02X1324767Y127227I777J1167D01*
G03X1325433I333J222D01*
G02X1327377Y125283I1167J-777D01*
G03Y124617I222J-333D01*
G02X1325433Y122673I-777J-1167D01*
G03X1324767I-333J-222D01*
G37*
G36*
G01X-12598Y126754D02*
G03X-11331Y127157I-2J2199D01*
G02X-7272Y125823I1488J-2314D01*
G03X-6532Y125805I374J143D01*
G02X-2130I2201J-962D01*
G03X-1390Y125823I366J161D01*
G02X2653Y127167I2571J-980D01*
G03X3907Y126754I1283J1786D01*
G01X3938D01*
G03X5205Y127157I-2J2199D01*
G02X9264Y125823I1488J-2314D01*
G03X10004Y125805I374J143D01*
G02Y123881I2201J-962D01*
G03X9264Y123863I-366J-161D01*
G02X5221Y122519I-2571J980D01*
G03X3967Y122932I-1283J-1786D01*
G01X3936D01*
G03X2669Y122529I2J-2199D01*
G02X-1390Y123863I-1488J2314D01*
G03X-2130Y123881I-374J-143D01*
G02X-6532I-2201J962D01*
G03X-7272Y123863I-366J-161D01*
G02X-11315Y122519I-2571J980D01*
G03X-12569Y122932I-1283J-1786D01*
G01X-12599D01*
G03X-13866Y122529I2J-2199D01*
G02X-13882Y127167I-1488J2314D01*
G03X-12628Y126754I1283J1786D01*
G01X-12598D01*
G37*
G36*
G01X639979Y125292D02*
G02X637828Y123610I-879J-1092D01*
G03X637247Y123777I-363J-168D01*
G02X635189Y124408I-766J1174D01*
G03X634545Y124543I-369J-155D01*
G02X634028Y126889I-965J1017D01*
G03X634554Y127301I128J379D01*
G02X637258Y127926I1397J118D01*
G03X637890Y127767I373J145D01*
G02X639913Y125847I911J-1066D01*
G03X639979Y125292I317J-244D01*
G37*
G36*
G01X1864336Y125295D02*
G02X1864310Y123644I1241J-845D01*
G03X1863641Y123655I-338J-214D01*
G02X1863667Y125306I-1241J845D01*
G03X1864336Y125295I338J214D01*
G37*
G36*
G01X1381867Y124673D02*
G02X1379923Y126617I-1167J777D01*
G03Y127283I-222J333D01*
G02X1381867Y129227I777J1167D01*
G03X1382533I333J222D01*
G02X1384867I1167J-777D01*
G03X1385533I333J222D01*
G02X1387477Y127283I1167J-777D01*
G03Y126617I222J-333D01*
G02X1385533Y124673I-777J-1167D01*
G03X1384867I-333J-222D01*
G02X1382533I-1167J777D01*
G03X1381867I-333J-222D01*
G37*
G36*
G01X1920805Y126939D02*
G02X1918599I-1103J-1019D01*
G03Y127482I-294J272D01*
G02X1918820Y129717I1103J1019D01*
G03X1918781Y130390I-234J324D01*
G02X1918343Y132641I733J1311D01*
G03X1918276Y133208I-312J251D01*
G02X1920366Y133456I919J1188D01*
G03X1920433Y132889I312J-251D01*
G02X1920396Y130485I-919J-1188D01*
G03X1920435Y129812I234J-324D01*
G02X1920805Y127482I-733J-1311D01*
G03Y126939I294J-272D01*
G37*
G36*
G01X1357397Y125723D02*
G02Y127277I-1167J777D01*
G03X1358063I333J222D01*
G02X1359107Y127897I1167J-777D01*
G03X1359440Y128451I-35J398D01*
G02X1361897Y129777I1290J549D01*
G03X1362563I333J222D01*
G02X1364897I1167J-777D01*
G03X1365563I333J222D01*
G02X1367897I1167J-777D01*
G03X1368563I333J222D01*
G02X1369853Y127603I1167J-777D01*
G03X1369520Y127049I35J-398D01*
G02X1367063Y125723I-1290J-549D01*
G03X1366397I-333J-222D01*
G02X1364063I-1167J777D01*
G03X1363397I-333J-222D01*
G02X1361063I-1167J777D01*
G03X1360397I-333J-222D01*
G02X1358063I-1167J777D01*
G03X1357397I-333J-222D01*
G37*
G36*
G01X1857943Y127804D02*
G02X1856097I-923J-1185D01*
G03Y128434I-246J315D01*
G02X1855521Y129531I923J1185D01*
G03X1854910Y129846I-399J-24D01*
G02X1853423Y132454I-795J1275D01*
G03X1853601Y132978I-185J355D01*
G02X1855654Y132280I1361J635D01*
G03X1855476Y131756I185J-355D01*
G02X1855614Y131209I-1361J-634D01*
G03X1856225Y130894I399J24D01*
G02X1857943Y128434I795J-1275D01*
G03Y127804I246J-315D01*
G37*
G36*
G01X108474Y127350D02*
G02X107768Y129345I-1220J691D01*
G03X108274Y129541I147J372D01*
G02X110848Y129747I1348J-662D01*
G03X111488Y129729I327J231D01*
G02X111438Y127927I1176J-934D01*
G03X110798Y127945I-327J-231D01*
G02X108990Y127516I-1176J934D01*
G03X108474Y127350I-168J-363D01*
G37*
G36*
G01X1247412Y129280D02*
G02X1247147Y131145I-1161J786D01*
G03X1247744Y131244I256J307D01*
G02X1248181Y131702I1281J-784D01*
G03X1248095Y132408I-225J331D01*
G02X1249460Y132575I520J1409D01*
G03X1249546Y131869I225J-331D01*
G02X1248012Y129351I-521J-1409D01*
G03X1247412Y129280I-269J-296D01*
G37*
G36*
G01X25591Y134628D02*
G03X26858Y135031I-2J2199D01*
G02X30917Y133697I1488J-2314D01*
G03X31657Y133679I374J143D01*
G02Y131755I2201J-962D01*
G03X30917Y131737I-366J-161D01*
G02X26874Y130393I-2571J980D01*
G03X25620Y130806I-1283J-1786D01*
G01X25590D01*
G03X24323Y130403I2J-2199D01*
G02X20264Y131737I-1488J2314D01*
G03X19524Y131755I-374J-143D01*
G02Y133679I-2201J962D01*
G03X20264Y133697I366J161D01*
G02X24307Y135041I2571J-980D01*
G03X25561Y134628I1283J1786D01*
G01X25591D01*
G37*
G36*
G01X1553376Y132283D02*
G02X1553124Y134028I-1205J717D01*
G03X1553740Y134117I272J293D01*
G02X1556097Y134199I1205J-717D01*
G03X1556777Y134238I328J229D01*
G02X1556838Y132711I1323J-712D01*
G03X1556157Y132695I-336J-217D01*
G02X1553992Y132372I-1212J705D01*
G03X1553376Y132283I-272J-293D01*
G37*
G36*
G01X1568396Y134574D02*
G02X1566998Y134762I-876J-1220D01*
G03X1567092Y135462I-139J375D01*
G02X1567013Y137841I876J1220D01*
G03X1567016Y138456I-254J309D01*
G02X1568936Y138448I965J1151D01*
G03X1568933Y137833I254J-309D01*
G02X1568490Y135274I-965J-1151D01*
G03X1568396Y134574I139J-375D01*
G37*
G36*
G01X1262697Y134362D02*
G02X1262517Y132923I1101J-868D01*
G03X1261838Y133008I-365J-163D01*
G02X1262018Y134447I-1101J868D01*
G03X1262697Y134362I365J163D01*
G37*
G36*
G01X1895705Y137455D02*
G02X1894230Y137351I-646J-1356D01*
G03X1894192Y138040I-221J333D01*
G02X1893916Y140345I642J1246D01*
G03X1893906Y140958I-262J302D01*
G02X1895786Y140944I949J1164D01*
G03X1895768Y140332I248J-314D01*
G02X1895645Y138143I-934J-1045D01*
G03X1895705Y137455I232J-326D01*
G37*
G36*
G01X1557043Y139093D02*
G02X1556623Y137754I1057J-1067D01*
G03X1555956Y137975I-394J-71D01*
G02X1556371Y139293I-956J1025D01*
G03X1557043Y139093I391J84D01*
G37*
G36*
G01X-12598Y142502D02*
G03X-11331Y142905I-2J2199D01*
G02X-7272Y141571I1488J-2314D01*
G03X-6532Y141553I374J143D01*
G02X-2130I2201J-962D01*
G03X-1390Y141571I366J161D01*
G02X2653Y142915I2571J-980D01*
G03X3907Y142502I1283J1786D01*
G01X3938D01*
G03X5205Y142905I-2J2199D01*
G02X9264Y141571I1488J-2314D01*
G03X10004Y141553I374J143D01*
G02Y139629I2201J-962D01*
G03X9264Y139611I-366J-161D01*
G02X5221Y138267I-2571J980D01*
G03X3967Y138680I-1283J-1786D01*
G01X3936D01*
G03X2669Y138277I2J-2199D01*
G02X-1390Y139611I-1488J2314D01*
G03X-2130Y139629I-374J-143D01*
G02X-6532I-2201J962D01*
G03X-7272Y139611I-366J-161D01*
G02X-11315Y138267I-2571J980D01*
G03X-12569Y138680I-1283J-1786D01*
G01X-12599D01*
G03X-13866Y138277I2J-2199D01*
G02X-13882Y142915I-1488J2314D01*
G03X-12628Y142502I1283J1786D01*
G01X-12598D01*
G37*
G36*
G01X1900817Y143276D02*
G02X1899095Y143417I-961J-1154D01*
G03X1899161Y144059I-202J345D01*
G02X1900857Y143920I939J1041D01*
G03X1900817Y143276I216J-337D01*
G37*
G36*
G01X662991Y141753D02*
G02X662743Y143236I-1291J546D01*
G03X663409Y143347I298J267D01*
G02X663657Y141864I1291J-546D01*
G03X662991Y141753I-298J-267D01*
G37*
G36*
G01X1329382Y143162D02*
G02X1328225Y144384I-1482J-244D01*
G03X1328709Y144825I87J391D01*
G02X1329848Y143621I1391J175D01*
G03X1329382Y143162I-71J-394D01*
G37*
G36*
G01X1887306Y147734D02*
G02X1887324Y146316I1333J-692D01*
G03X1886625Y146317I-350J-194D01*
G02X1886606Y147714I-1225J682D01*
G03X1887306Y147734I344J204D01*
G37*
G36*
G01X1895112Y147343D02*
G02X1893942Y148513I-1471J-301D01*
G03X1894417Y148971I80J392D01*
G02X1894730Y150106I1383J229D01*
G03X1894687Y150667I-305J259D01*
G02X1896764Y150768I986J1133D01*
G03X1896776Y150206I291J-275D01*
G02X1895569Y147817I-976J-1006D01*
G03X1895112Y147343I-65J-394D01*
G37*
G36*
G01X-7480Y150376D02*
G03X-6213Y150779I-2J2199D01*
G02X-2154Y149445I1488J-2314D01*
G03X-1414Y149427I374J143D01*
G02X2988I2201J-962D01*
G03X3728Y149445I366J161D01*
G02X7771Y150789I2571J-980D01*
G03X9025Y150376I1283J1786D01*
G01X9056D01*
G03X10323Y150779I-2J2199D01*
G02X14382Y149445I1488J-2314D01*
G03X15122Y149427I374J143D01*
G02X19524I2201J-962D01*
G03X20264Y149445I366J161D01*
G02X24307Y150789I2571J-980D01*
G03X25561Y150376I1283J1786D01*
G01X25591D01*
G03X26858Y150779I-2J2199D01*
G02X30917Y149445I1488J-2314D01*
G03X31657Y149427I374J143D01*
G02Y147503I2201J-962D01*
G03X30917Y147485I-366J-161D01*
G02X26874Y146141I-2571J980D01*
G03X25620Y146554I-1283J-1786D01*
G01X25590D01*
G03X24323Y146151I2J-2199D01*
G02X20264Y147485I-1488J2314D01*
G03X19524Y147503I-374J-143D01*
G02X15122I-2201J962D01*
G03X14382Y147485I-366J-161D01*
G02X10339Y146141I-2571J980D01*
G03X9085Y146554I-1283J-1786D01*
G01X9054D01*
G03X7787Y146151I2J-2199D01*
G02X3728Y147485I-1488J2314D01*
G03X2988Y147503I-374J-143D01*
G02X-1414I-2201J962D01*
G03X-2154Y147485I-366J-161D01*
G02X-6197Y146141I-2571J980D01*
G03X-7451Y146554I-1283J-1786D01*
G01X-7481D01*
G03X-8748Y146151I2J-2199D01*
G02X-12807Y147485I-1488J2314D01*
G03X-13547Y147503I-374J-143D01*
G02Y149427I-2201J962D01*
G03X-12807Y149445I366J161D01*
G02X-8764Y150789I2571J-980D01*
G03X-7510Y150376I1283J1786D01*
G01X-7480D01*
G37*
G36*
G01X1907186Y150477D02*
G02X1906789Y148905I1141J-1124D01*
G03X1906129Y149083I-384J-111D01*
G02X1904293Y151442I-1036J1087D01*
G03X1904387Y152037I-213J339D01*
G02X1906339Y151728I1153J963D01*
G03X1906245Y151133I213J-339D01*
G02X1906520Y150634I-1154J-961D01*
G03X1907186Y150477I381J124D01*
G37*
G36*
G01X1578718Y150684D02*
G02X1576965Y150787I-948J-1165D01*
G03X1577002Y151435I-215J337D01*
G02X1576824Y153594I948J1165D01*
G03X1576771Y154173I-300J264D01*
G02X1578826Y154359I929J1180D01*
G03X1578879Y153780I300J-264D01*
G02X1578755Y151332I-929J-1180D01*
G03X1578718Y150684I215J-337D01*
G37*
G36*
G01X77054Y151821D02*
G02X76864Y153278I-1394J559D01*
G03X77556Y153369I321J239D01*
G02X77746Y151912I1394J-559D01*
G03X77054Y151821I-321J-239D01*
G37*
G36*
G01X1879468Y152232D02*
G02X1877009Y151807I-1372J611D01*
G03X1876447Y151824I-290J-276D01*
G02X1874806Y154293I-1022J1101D01*
G03X1874842Y155003I-165J364D01*
G02X1876219Y154932I757J1297D01*
G03X1876183Y154222I165J-364D01*
G02X1876512Y153961I-760J-1296D01*
G03X1877074Y153944I290J276D01*
G02X1879273Y153776I1022J-1101D01*
G03X1879952Y153861I314J248D01*
G02X1880147Y152317I1372J-611D01*
G03X1879468Y152232I-314J-248D01*
G37*
G36*
G01X1263675Y155756D02*
G02X1263568Y153973I1025J-956D01*
G03X1262941Y153997I-323J-236D01*
G02X1263049Y155807I-1141J976D01*
G03X1263675Y155756I333J222D01*
G37*
G36*
G01X1242777Y155687D02*
G02X1242769Y154158I1171J-771D01*
G03X1242098Y154161I-336J-216D01*
G02X1242106Y155690I-1171J771D01*
G03X1242777Y155687I336J216D01*
G37*
G36*
G01X-12598Y158250D02*
G03X-11331Y158653I-2J2199D01*
G02X-7272Y157319I1488J-2314D01*
G03X-6532Y157301I374J143D01*
G02X-2130I2201J-962D01*
G03X-1390Y157319I366J161D01*
G02X2653Y158663I2571J-980D01*
G03X3907Y158250I1283J1786D01*
G01X3938D01*
G03X5205Y158653I-2J2199D01*
G02X9264Y157319I1488J-2314D01*
G03X10004Y157301I374J143D01*
G02X14405Y157302I2201J-962D01*
G03X15145Y157320I366J161D01*
G02X19188Y158663I2570J-981D01*
G03X20442Y158250I1283J1786D01*
G01X20473D01*
G03X21740Y158653I-2J2199D01*
G02X25799Y157319I1488J-2314D01*
G03X26539Y157301I374J143D01*
G02Y155377I2201J-962D01*
G03X25799Y155359I-366J-161D01*
G02X21756Y154015I-2571J980D01*
G03X20502Y154428I-1283J-1786D01*
G01X20471D01*
G03X19204Y154025I2J-2199D01*
G02X15145Y155358I-1488J2314D01*
G03X14405Y155376I-374J-143D01*
G02X10004Y155377I-2200J963D01*
G03X9264Y155359I-366J-161D01*
G02X5221Y154015I-2571J980D01*
G03X3967Y154428I-1283J-1786D01*
G01X3936D01*
G03X2669Y154025I2J-2199D01*
G02X-1390Y155359I-1488J2314D01*
G03X-2130Y155377I-374J-143D01*
G02X-6532I-2201J962D01*
G03X-7272Y155359I-366J-161D01*
G02X-11315Y154015I-2571J980D01*
G03X-12569Y154428I-1283J-1786D01*
G01X-12599D01*
G03X-13866Y154025I2J-2199D01*
G02X-13882Y158663I-1488J2314D01*
G03X-12628Y158250I1283J1786D01*
G01X-12598D01*
G37*
G36*
G01X759177Y157367D02*
G02X757623I-777J-1167D01*
G03Y158033I-222J333D01*
G02X759177I777J1167D01*
G03Y157367I222J-333D01*
G37*
G36*
G01X749534Y162049D02*
G02X748889Y159889I3107J-2104D01*
G03X748292Y160231I-400J-6D01*
G02X748847Y162090I-692J1219D01*
G03X749534Y162049I356J183D01*
G37*
G36*
G01X1403006Y163602D02*
G02X1401139Y163553I-838J-3657D01*
G03X1401237Y164279I-110J384D01*
G02X1400532Y165358I783J1282D01*
G03X1399918Y165640I-396J-54D01*
G02X1400588Y167103I-818J1260D01*
G03X1401202Y166821I396J54D01*
G02X1402869Y164322I818J-1260D01*
G03X1403006Y163602I226J-330D01*
G37*
G36*
G01X-14292Y161645D02*
G02X-14949Y163181I-1476J277D01*
G03X-14337Y163442I219J335D01*
G02X-13680Y161906I1476J-277D01*
G03X-14292Y161645I-219J-335D01*
G37*
G36*
G01X1242851Y171731D02*
G02X1242553Y172980I-1470J309D01*
G03X1242909Y173110I156J125D01*
G02X1242914Y173284I1501J44D01*
G03X1242575Y173715I-398J35D01*
G02X1244296Y175066I225J1485D01*
G03X1244635Y174635I398J-35D01*
G02X1245397Y174282I-225J-1485D01*
G03X1245923I263J302D01*
G02X1246034Y174370I988J-1132D01*
G03X1245981Y175053I-233J326D01*
G02X1247531Y175175I674J1342D01*
G03X1247584Y174492I233J-326D01*
G02X1245923Y172018I-674J-1342D01*
G03X1245397I-263J-302D01*
G02X1243488Y171964I-987J1132D01*
G03X1242851Y171731I-246J-315D01*
G37*
G36*
G01X63478Y177656D02*
G02X62697Y176146I709J-1324D01*
G03X62111Y176449I-397J-50D01*
G02X60518Y178987I-708J1324D01*
G03X60497Y179648I-236J323D01*
G02X62253Y179673I859J1352D01*
G03X62251Y179012I224J-331D01*
G02X62892Y177959I-849J-1239D01*
G03X63478Y177656I397J50D01*
G37*
G36*
G01X1778710Y178036D02*
X1782588D01*
G02X1782683Y178033I0J-1511D01*
G03X1782805Y178400I12J200D01*
G02X1783898Y178211I766J1174D01*
G03X1783698Y177550I94J-389D01*
G02X1784098Y176535I-1111J-1024D01*
G01Y176440D01*
X1784089Y176356D01*
G02X1782587Y175014I-1502J169D01*
G01X1777587D01*
G02X1776498Y177573I0J1511D01*
G03X1776423Y178189I-288J277D01*
G02X1778369Y178645I749J1185D01*
G03X1778710Y178036I342J-209D01*
G37*
G36*
G01X1791408D02*
X1795187D01*
G02X1795281Y178033I-1J-1511D01*
G03X1795403Y178400I12J200D01*
G02X1796496Y178211I766J1174D01*
G03X1796296Y177550I93J-389D01*
G02X1796696Y176535I-1111J-1024D01*
G01Y176440D01*
X1796687Y176356D01*
G02X1795185Y175014I-1502J169D01*
G01X1790185D01*
G02X1789127Y177605I0J1512D01*
G03X1789074Y178220I-280J286D01*
G02X1791067Y178645I796J1154D01*
G03X1791408Y178036I342J-209D01*
G37*
G36*
G01X1803907D02*
X1807785D01*
G02X1807880Y178033I0J-1511D01*
G03X1808002Y178400I12J200D01*
G02X1809095Y178211I766J1174D01*
G03X1808895Y177550I94J-389D01*
G02X1809296Y176535I-1111J-1026D01*
G01Y176440D01*
X1809286Y176356D01*
G02X1807784Y175014I-1502J169D01*
G01X1802784D01*
G02X1801695Y177573I0J1511D01*
G03X1801620Y178189I-288J277D01*
G02X1803566Y178645I749J1185D01*
G03X1803907Y178036I342J-209D01*
G37*
G36*
G01X1816582D02*
X1820383D01*
G02X1820478Y178033I0J-1511D01*
G03X1820600Y178400I12J200D01*
G02X1821693Y178211I766J1174D01*
G03X1821493Y177550I94J-389D01*
G02X1821894Y176535I-1111J-1026D01*
G01Y176440D01*
X1821884Y176356D01*
G02X1820382Y175014I-1502J169D01*
G01X1815382D01*
G02X1814269Y177548I0J1511D01*
G03X1814202Y178147I-295J270D01*
G02X1816231Y178628I798J1153D01*
G03X1816582Y178036I351J-192D01*
G37*
G36*
G01X1489816Y177878D02*
G02X1488305Y177843I-728J-1198D01*
G03X1488278Y178523I-223J332D01*
G02X1489812Y178559I737J1309D01*
G03X1489816Y177878I212J-339D01*
G37*
G36*
G01X1597025Y179619D02*
G02Y180981I-1225J681D01*
G03X1597725I350J194D01*
G02Y179619I1225J-681D01*
G03X1597025I-350J-194D01*
G37*
G36*
G01X115006Y179785D02*
G02Y181215I-1206J715D01*
G03X115694I344J204D01*
G02Y179785I1206J-715D01*
G03X115006I-344J-204D01*
G37*
G36*
G01X87867Y182912D02*
G02X86194Y183018I-915J-1191D01*
G03X86236Y183681I-201J346D01*
G02X87909Y183575I915J1191D01*
G03X87867Y182912I201J-346D01*
G37*
G36*
G01X1855752Y182799D02*
G02X1854077Y182758I-810J-1144D01*
G03X1854048Y183408I-247J315D01*
G02X1855176Y186137I820J1259D01*
G03X1855654Y186476I82J392D01*
G02X1856826Y184907I1390J-184D01*
G03X1856365Y184545I-62J-395D01*
G02X1855748Y183450I-1497J122D01*
G03X1855752Y182799I235J-324D01*
G37*
G36*
G01X1476168Y181714D02*
G02X1476004Y183117I-1285J561D01*
G03X1476695Y183209I320J241D01*
G02X1476861Y181785I1394J-559D01*
G03X1476168Y181714I-326J-231D01*
G37*
G36*
G01X1643138Y183981D02*
G02X1640433Y184087I-1338J419D01*
G03X1639869Y184358I-390J-89D01*
G02X1640658Y185686I-611J1262D01*
G03X1640976Y185534I200J10D01*
G02X1641061Y185591I823J-1135D01*
G03X1641188Y186145I-211J340D01*
G02X1643944Y187159I1269J803D01*
G03X1644361Y186815I396J56D01*
G02X1643722Y184206I72J-1400D01*
G03X1643138Y183981I-203J-345D01*
G37*
G36*
G01X1709041Y188532D02*
G02X1708455Y186890I859J-1232D01*
G03X1707855Y187119I-385J-108D01*
G02X1708432Y188736I-755J1181D01*
G03X1709041Y188532I380J124D01*
G37*
G36*
G01X1536245Y189153D02*
G02X1534585Y189138I-820J-1137D01*
G03X1534579Y189783I-240J320D01*
G02X1536239Y189798I820J1137D01*
G03X1536245Y189153I240J-320D01*
G37*
G36*
G01X1639002Y196064D02*
G02X1636691Y194146I-1133J-986D01*
G03X1636097Y194183I-314J-248D01*
G02X1634120Y194190I-985J998D01*
G03X1633575Y194210I-283J-282D01*
G02X1631125Y195673I-985J1134D01*
G03X1630757Y196160I-390J88D01*
G02X1630564Y196185I83J1399D01*
G03X1630340Y195913I-39J-196D01*
G02X1629039Y196843I-1390J-569D01*
G03X1629456Y197313I23J399D01*
G02X1632072Y198221I1380J247D01*
G03X1632771Y198209I353J189D01*
G02X1635485Y196953I1298J-756D01*
G03X1635696Y196456I377J-133D01*
G02X1636169Y196102I-585J-1274D01*
G03X1636765Y196094I302J263D01*
G02X1636851Y196180I1104J-1018D01*
G03Y196474I-136J147D01*
G02X1639002Y196590I1019J1103D01*
G03Y196064I302J-263D01*
G37*
G36*
G01X1649838Y196575D02*
G02X1648924Y195521I462J-1324D01*
G03X1648389Y195971I-392J76D01*
G02X1649317Y197041I-537J1403D01*
G03X1649838Y196575I390J-88D01*
G37*
G36*
G01X1746082Y198354D02*
X1751083D01*
G02X1751420Y198316I0J-1511D01*
G03X1751909Y198705I89J390D01*
G02X1753063Y197320I1402J-5D01*
G03X1752592Y196909I-71J-394D01*
G02X1752594Y196853I-1509J-82D01*
G01Y196758D01*
X1752584Y196674D01*
G02X1751082Y195332I-1502J169D01*
G01X1746082D01*
G02X1744576Y196973I0J1511D01*
G03X1744138Y197405I-399J34D01*
G02X1742794Y198085I-138J1395D01*
G03X1742106I-344J-204D01*
G02X1740553Y197442I-1206J715D01*
G03X1740058Y196996I-99J-388D01*
G02X1740074Y196786I-1495J-220D01*
G01Y196691D01*
X1740065Y196607D01*
G02X1738563Y195264I-1502J168D01*
G01X1733563D01*
G02X1732521Y195681I1J1512D01*
G03X1731858Y195487I-275J-290D01*
G02X1730322Y197350I-1458J363D01*
G03X1730425Y197715I-10J200D01*
G02X1730205Y197901I790J1158D01*
G03X1729627I-289J-277D01*
G02Y199843I-1011J971D01*
G03X1730205I289J277D01*
G02X1732602Y198662I1011J-971D01*
G03X1733116Y198220I395J-60D01*
G02X1733563Y198288I448J-1444D01*
G01X1738564D01*
G02X1738994Y198225I-2J-1512D01*
G03X1739506Y198651I114J383D01*
G02X1742106Y199515I1394J149D01*
G03X1742794I344J204D01*
G02X1745401Y198748I1206J-715D01*
G03X1745860Y198338I400J-14D01*
G02X1746082Y198354I219J-1495D01*
G37*
G36*
G01X1826682Y195330D02*
X1821681D01*
G02X1820184Y197046I1J1511D01*
G03X1819715Y197494I-396J55D01*
G02X1818236Y198183I-258J1378D01*
G03X1817528Y198161I-348J-197D01*
G02X1816017Y197392I-1262J611D01*
G03X1815547Y196966I-71J-394D01*
G02X1815552Y196851I-1506J-123D01*
G01Y196756D01*
X1815543Y196672D01*
G02X1814041Y195330I-1502J169D01*
G01X1809041D01*
G02X1807530Y196828I0J1511D01*
G03X1807061Y197219I-400J-3D01*
G02X1805834Y197605I-240J1381D01*
G03X1805244Y197576I-282J-284D01*
G02X1803533Y197221I-1078J896D01*
G03X1802952Y196859I-181J-357D01*
G01Y196756D01*
X1802943Y196672D01*
G02X1801441Y195330I-1502J169D01*
G01X1796440D01*
G02X1794943Y197046I1J1511D01*
G03X1794474Y197494I-396J55D01*
G02X1793012Y198153I-258J1378D01*
G03X1792313Y198131I-343J-205D01*
G02X1790817Y197392I-1247J641D01*
G03X1790347Y196966I-71J-394D01*
G02X1790352Y196851I-1506J-123D01*
G01Y196756D01*
X1790343Y196672D01*
G02X1788841Y195330I-1502J169D01*
G01X1783840D01*
G02X1782343Y197046I1J1511D01*
G03X1781874Y197494I-396J55D01*
G02X1780412Y198153I-258J1378D01*
G03X1779713Y198131I-343J-205D01*
G02X1778217Y197392I-1247J641D01*
G03X1777747Y196966I-71J-394D01*
G02X1777752Y196851I-1506J-123D01*
G01Y196756D01*
X1777743Y196672D01*
G02X1776241Y195330I-1502J169D01*
G01X1771240D01*
G02X1769743Y197046I1J1511D01*
G03X1769274Y197494I-396J55D01*
G02X1767812Y198153I-258J1378D01*
G03X1767113Y198131I-343J-205D01*
G02X1765638Y197389I-1247J641D01*
G03X1765175Y196962I-64J-395D01*
G02X1765180Y196853I-1507J-124D01*
G01Y196758D01*
X1765170Y196674D01*
G02X1763668Y195332I-1502J169D01*
G01X1758668D01*
G02X1757162Y196971I0J1511D01*
G03X1756727Y197404I-399J35D01*
G02X1758001Y198750I-127J1396D01*
G03X1758457Y198340I400J-14D01*
G02X1758668Y198354I205J-1497D01*
G01X1763669D01*
G02X1763982Y198322I4J-1511D01*
G03X1764465Y198726I83J391D01*
G02X1767070Y199491I1401J46D01*
G03X1767769Y199513I343J205D01*
G02X1770412Y198741I1247J-641D01*
G03X1770900Y198314I398J-37D01*
G02X1771241Y198352I337J-1473D01*
G01X1776242D01*
G02X1776577Y198315I3J-1511D01*
G03X1777065Y198720I88J390D01*
G02X1779670Y199491I1401J52D01*
G03X1780369Y199513I343J205D01*
G02X1783012Y198741I1247J-641D01*
G03X1783500Y198314I398J-37D01*
G02X1783841Y198352I337J-1473D01*
G01X1788842D01*
G02X1789177Y198315I3J-1511D01*
G03X1789665Y198720I88J390D01*
G02X1792270Y199491I1401J52D01*
G03X1792969Y199513I343J205D01*
G02X1795612Y198741I1247J-641D01*
G03X1796100Y198314I398J-37D01*
G02X1796441Y198352I337J-1473D01*
G01X1801442D01*
G02X1802171Y198164I-1J-1511D01*
G03X1802764Y198505I193J350D01*
G02X1805153Y199467I1402J-33D01*
G03X1805743Y199496I282J284D01*
G02X1808221Y198682I1078J-896D01*
G03X1808708Y198315I399J23D01*
G02X1809040Y198352I332J-1474D01*
G01X1814042D01*
G02X1814377Y198315I3J-1511D01*
G03X1814865Y198720I88J390D01*
G02X1817487Y199461I1401J52D01*
G03X1818195Y199483I348J197D01*
G02X1820853Y198741I1262J-611D01*
G03X1821341Y198314I398J-37D01*
G02X1821682Y198352I337J-1473D01*
G01X1826683D01*
G02X1826854Y198343I6J-1511D01*
G03X1827299Y198753I45J397D01*
G02X1830078Y198542I1401J47D01*
G03X1830459Y198068I393J-74D01*
G02X1828953Y196911I-44J-1501D01*
G03X1828594Y197402I-389J92D01*
G02X1828391Y197432I103J1398D01*
G03X1828152Y197191I-44J-195D01*
G02X1828194Y196851I-1469J-354D01*
G01Y196756D01*
X1828184Y196672D01*
G02X1826682Y195330I-1502J169D01*
G37*
G36*
G01X1865205Y199772D02*
G02X1863859Y199841I-742J-1306D01*
G03X1863896Y200555I-161J366D01*
G02X1865242Y200486I742J1306D01*
G03X1865205Y199772I161J-366D01*
G37*
G36*
G01X1847808Y199983D02*
G02X1846358Y200068I-809J-1383D01*
G03X1846408Y200774I-161J366D01*
G02X1847839Y200691I792J1276D01*
G03X1847808Y199983I170J-362D01*
G37*
G36*
G01X1403994Y206146D02*
G02X1402388Y205876I-594J-1380D01*
G03X1402276Y206538I-270J295D01*
G02X1403882Y206808I594J1380D01*
G03X1403994Y206146I270J-295D01*
G37*
G36*
G01X1479907Y208294D02*
G02X1477808Y207964I-907J-1069D01*
G03X1477709Y208494I-340J211D01*
G02X1477264Y209030I902J1201D01*
G03X1476589Y209098I-359J-177D01*
G02X1475972Y208628I-1188J919D01*
G03X1475750Y208117I152J-370D01*
G02X1473834Y208886I-1311J-496D01*
G03X1474028Y209409I-172J361D01*
G02X1476748Y210682I1373J608D01*
G03X1477423Y210614I359J177D01*
G02X1479839Y208830I1188J-919D01*
G03X1479907Y208294I327J-231D01*
G37*
G36*
G01X1354924Y208312D02*
G02X1354865Y209719I-1355J648D01*
G03X1355571Y209748I345J202D01*
G02X1357899Y210244I1355J-648D01*
G03X1358441Y210265I260J304D01*
G02X1360442Y210370I1059J-1065D01*
G03X1360968Y210391I251J311D01*
G02X1361058Y208130I1032J-1091D01*
G03X1360532Y208109I-251J-311D01*
G02X1358527Y208056I-1032J1091D01*
G03X1357985Y208035I-260J-304D01*
G02X1355630Y208341I-1059J1065D01*
G03X1354924Y208312I-345J-202D01*
G37*
G36*
G01X1809125Y213742D02*
X1814126D01*
G02X1815636Y212241I-1J-1511D01*
G01Y212146D01*
X1815627Y212062D01*
G02X1815527Y211665I-1502J167D01*
G03X1815847Y211119I371J-149D01*
G02X1814455Y210427I-177J-1391D01*
G03X1814263Y210726I-174J100D01*
G02X1814125Y210720I-135J1505D01*
G01X1809125D01*
G02X1809060Y210721I-9J1511D01*
G03X1808889Y210404I-9J-200D01*
G02X1807497Y210965I-1139J-818D01*
G03X1807780Y211541I-73J393D01*
G02X1809125Y213742I1345J690D01*
G37*
G36*
G01X1733483Y213142D02*
X1738485D01*
G02X1739996Y211641I0J-1512D01*
G01Y211546D01*
X1739986Y211462D01*
G02X1739981Y211426I-1499J190D01*
G03X1740451Y210978I396J-55D01*
G02X1741930Y210289I258J-1378D01*
G03X1742638Y210311I348J197D01*
G02X1744149Y211080I1262J-611D01*
G03X1744619Y211506I71J393D01*
G02X1746125Y213142I1506J125D01*
G01X1751126D01*
G02X1752636Y211653I-1J-1511D01*
G03X1753117Y211273I400J12D01*
G02X1754374Y210908I283J-1373D01*
G03X1754951Y210930I278J288D01*
G02X1756633Y211251I1049J-930D01*
G03X1757214Y211613I181J357D01*
G02X1758725Y213142I1511J18D01*
G01X1763726D01*
G02X1765236Y211641I-1J-1511D01*
G01Y211546D01*
X1765227Y211462D01*
G02X1765222Y211426I-1499J190D01*
G03X1765692Y210978I396J-55D01*
G02X1767154Y210319I258J-1378D01*
G03X1767853Y210341I343J205D01*
G02X1769349Y211080I1247J-641D01*
G03X1769819Y211506I71J393D01*
G02X1771325Y213142I1506J125D01*
G01X1776326D01*
G02X1777836Y211641I-1J-1511D01*
G01Y211546D01*
X1777827Y211462D01*
G02X1777822Y211426I-1499J190D01*
G03X1778292Y210978I396J-55D01*
G02X1779754Y210319I258J-1378D01*
G03X1780453Y210341I343J205D01*
G02X1781949Y211080I1247J-641D01*
G03X1782419Y211506I71J393D01*
G02X1783925Y213142I1506J125D01*
G01X1788926D01*
G02X1790436Y211641I-1J-1511D01*
G01Y211546D01*
X1790427Y211462D01*
G02X1790422Y211426I-1499J190D01*
G03X1790892Y210978I396J-55D01*
G02X1792354Y210319I258J-1378D01*
G03X1793053Y210341I343J205D01*
G02X1793096Y208981I1247J-641D01*
G03X1792397Y208959I-343J-205D01*
G02X1789754Y209731I-1247J641D01*
G03X1789266Y210158I-398J37D01*
G02X1788925Y210120I-337J1473D01*
G01X1783925D01*
G02X1783590Y210157I-3J1511D01*
G03X1783101Y209752I-89J-390D01*
G02X1780496Y208981I-1401J-52D01*
G03X1779797Y208959I-343J-205D01*
G02X1777154Y209731I-1247J641D01*
G03X1776666Y210158I-398J37D01*
G02X1776325Y210120I-337J1473D01*
G01X1771325D01*
G02X1770990Y210157I-3J1511D01*
G03X1770501Y209752I-89J-390D01*
G02X1767896Y208981I-1401J-52D01*
G03X1767197Y208959I-343J-205D01*
G02X1764554Y209731I-1247J641D01*
G03X1764066Y210158I-398J37D01*
G02X1763725Y210120I-337J1473D01*
G01X1758725D01*
G02X1757995Y210308I0J1511D01*
G03X1757402Y209967I-193J-350D01*
G02X1755026Y208992I-1402J33D01*
G03X1754449Y208970I-278J-288D01*
G02X1752001Y209807I-1049J930D01*
G03X1751502Y210167I-399J-27D01*
G02X1751125Y210120I-374J1464D01*
G01X1746125D01*
G02X1745790Y210157I-3J1511D01*
G03X1745301Y209752I-89J-390D01*
G02X1742679Y209011I-1401J-52D01*
G03X1741971Y208989I-348J-197D01*
G02X1739313Y209731I-1262J611D01*
G03X1738825Y210158I-398J37D01*
G02X1738484Y210120I-337J1473D01*
G01X1733484D01*
G02X1733144Y210158I-3J1511D01*
G03X1732656Y209731I-90J-390D01*
G02X1731517Y210978I-1396J-131D01*
G03X1731986Y211426I73J393D01*
G02X1733483Y213142I1498J205D01*
G37*
G36*
G01X1801526Y210720D02*
X1796526D01*
G02Y213742I0J1511D01*
G01X1801527D01*
G02X1803038Y212241I0J-1512D01*
G01Y212146D01*
X1803028Y212062D01*
G02X1802928Y211665I-1502J167D01*
G03X1803248Y211119I371J-149D01*
G02X1801857Y210427I-176J-1391D01*
G03X1801665Y210726I-173J100D01*
G02X1801526Y210720I-135J1505D01*
G37*
G36*
G01X1848953Y212120D02*
G02Y213772I-1254J826D01*
G03X1849622I335J220D01*
G02Y212120I1254J-826D01*
G03X1848953I-334J-220D01*
G37*
G36*
G01X1334259Y215577D02*
G02X1331841Y215643I-1185J923D01*
G03X1331193Y215655I-328J-229D01*
G02Y217345I-1119J845D01*
G03X1331841Y217357I320J241D01*
G02X1334259Y217423I1233J-857D01*
G03X1334889I315J246D01*
G02Y215577I1185J-923D01*
G03X1334259I-315J-246D01*
G37*
G36*
G01X31500Y219939D02*
G02X29239Y222200I-1200J1061D01*
G03Y222800I-265J300D01*
G02X28838Y224655I1061J1200D01*
G03X28363Y225203I-365J164D01*
G02X29873Y226240I-804J2789D01*
G03X30213Y225600I319J-241D01*
G02X31500Y225061I86J-1600D01*
G03X32100I300J265D01*
G02X32932Y225559I1200J-1061D01*
G03X33154Y226196I-92J389D01*
G02X37349Y225812I2279J1796D01*
G03X37350Y225210I264J-301D01*
G02X37361Y222800I-1050J-1210D01*
G03Y222200I265J-300D01*
G02X35100Y219939I-1061J-1200D01*
G03X34500I-300J-265D01*
G02X32100I-1200J1061D01*
G03X31500I-300J-265D01*
G37*
G36*
G01X1461480Y222392D02*
G02X1461467Y221032I1220J-692D01*
G03X1460768Y221039I-351J-190D01*
G02X1460781Y222399I-1220J692D01*
G03X1461480Y222392I351J190D01*
G37*
G36*
G01X1499094Y222803D02*
G02X1497466Y223187I-1072J-903D01*
G03X1497613Y223812I-159J367D01*
G02X1499241Y223428I1072J903D01*
G03X1499094Y222803I159J-367D01*
G37*
G36*
G01X1481639Y223940D02*
G02X1480549Y222856I365J-1457D01*
G03X1480065Y223344I-387J100D01*
G02X1481155Y224428I-365J1457D01*
G03X1481639Y223940I387J-100D01*
G37*
G36*
G01X-2029Y230179D02*
G02X-5802Y230215I-1908J-2187D01*
G03X-5897Y230887I-257J306D01*
G02X-6286Y231133I653J1463D01*
G03X-6806I-260J-304D01*
G02Y233569I-1040J1218D01*
G03X-6286I260J304D01*
G02X-4164Y233533I1041J-1218D01*
G03X-3636Y233522I270J295D01*
G02X-1933Y230844I1036J-1221D01*
G03X-2029Y230179I167J-364D01*
G37*
G36*
G01X1667179Y243236D02*
G02X1665498Y243227I-834J-1249D01*
G03X1665495Y243890I-226J330D01*
G02X1667176Y243899I834J1249D01*
G03X1667179Y243236I226J-330D01*
G37*
G36*
G01X1684710Y243483D02*
G02X1682478Y241514I-981J-1137D01*
G03X1681856Y241568I-333J-222D01*
G02X1680316Y244037I-1087J1037D01*
G03X1680524Y244646I-121J381D01*
G02X1682796Y246587I1236J854D01*
G03X1683374Y246615I276J290D01*
G02X1684874Y244174I1135J-984D01*
G03X1684710Y243483I97J-388D01*
G37*
G36*
G01X19715Y243162D02*
G02X19645Y245435I-2595J1058D01*
G03X20375Y245458I360J174D01*
G02X25475Y245655I2595J-1058D01*
G03X26193Y245661I358J179D01*
G02X26215Y243195I2527J-1211D01*
G03X25497Y243189I-358J-179D01*
G02X20445Y243185I-2527J1211D01*
G03X19715Y243162I-360J-174D01*
G37*
G36*
G01X1472672Y244426D02*
G02X1470967Y242143I-472J-1426D01*
G03X1470308Y242140I-328J-228D01*
G02X1470271Y243773I-1158J791D01*
G03X1470929Y243800I320J240D01*
G02X1471258Y244170I1272J-799D01*
G03X1471132Y244861I-251J311D01*
G02X1470577Y245191I472J1426D01*
G03X1470031I-273J-292D01*
G02X1468327Y244946I-1027J1096D01*
G03X1467781Y244749I-180J-357D01*
G02X1467081Y246691I-1377J601D01*
G03X1467627Y246888I180J357D01*
G02X1470031Y247383I1377J-601D01*
G03X1470577I273J292D01*
G02X1472947Y246961I1027J-1096D01*
G03X1473661I357J179D01*
G02Y245613I1343J-674D01*
G03X1472947I-357J-179D01*
G02X1472546Y245117I-1342J675D01*
G03X1472672Y244426I251J-311D01*
G37*
G36*
G01X54506Y244076D02*
G02X53319Y246203I-1502J556D01*
G03X53773Y246456I79J392D01*
G02X55508Y247485I1502J-556D01*
G03X55944Y248012I58J396D01*
G02X56274Y249617I1513J525D01*
G03Y250157I-295J270D01*
G02X56414Y252453I1183J1080D01*
G03X56437Y253039I-260J304D01*
G02X56692Y255366I1063J1061D01*
G03X56670Y256053I-215J337D01*
G02X56300Y258578I774J1403D01*
G03X56311Y259126I-285J280D01*
G02X56323Y261287I1189J1074D01*
G03X56343Y261807I-294J272D01*
G02X58777Y261713I1257J993D01*
G03X58757Y261193I294J-272D01*
G02X58644Y259078I-1257J-993D01*
G03X58633Y258530I285J-280D01*
G02X58264Y256080I-1189J-1074D01*
G03X58265Y255392I205J-344D01*
G02X58531Y253008I-765J-1292D01*
G03X58536Y252421I274J-291D01*
G02X58640Y250157I-1079J-1184D01*
G03Y249617I295J-270D01*
G02X58803Y247669I-1183J-1080D01*
G03X58887Y247142I336J-217D01*
G02X56835Y244682I-1012J-1242D01*
G03X56315I-260J-304D01*
G02X54960Y244329I-1041J1218D01*
G03X54506Y244076I-79J-392D01*
G37*
G36*
G01X-16833Y246623D02*
G02Y248177I-1167J777D01*
G03X-16167I333J222D01*
G02Y246623I1167J-777D01*
G03X-16833I-333J-222D01*
G37*
G36*
G01X1663986Y249465D02*
G02X1662827Y248123I338J-1463D01*
G03X1662338Y248545I-399J32D01*
G02X1663497Y249887I-338J1463D01*
G03X1663986Y249465I399J-32D01*
G37*
G36*
G01X-16833Y261923D02*
G02Y263477I-1167J777D01*
G03X-16167I333J222D01*
G02Y261923I1167J-777D01*
G03X-16833I-333J-222D01*
G37*
G36*
G01X69880Y262117D02*
G02X67617Y264380I-1080J1183D01*
G03Y264920I-295J270D01*
G02X67612Y264925I1129J1134D01*
G03X66953Y264825I-296J-268D01*
G02X64420Y264317I-1453J675D01*
G03X63880I-270J-295D01*
G02X61680Y264355I-1080J1183D01*
G03X61120I-280J-286D01*
G02Y266645I-1120J1145D01*
G03X61680I280J286D01*
G02X63880Y266683I1120J-1145D01*
G03X64420I270J295D01*
G02X66688Y266575I1080J-1183D01*
G03X67347Y266675I296J268D01*
G02X69880Y267183I1453J-675D01*
G03X70420I270J295D01*
G02X72683Y264920I1080J-1183D01*
G03Y264380I295J-270D01*
G02X70420Y262117I-1183J-1080D01*
G03X69880I-270J-295D01*
G37*
G36*
G01X20977Y265799D02*
G02X20955Y268265I-2527J1211D01*
G03X21673Y268271I358J179D01*
G02X21695Y265805I2527J-1211D01*
G03X20977Y265799I-358J-179D01*
G37*
G36*
G01X54127Y275699D02*
G02X52673I-727J-1199D01*
G03Y276383I-207J342D01*
G02X54127I727J1199D01*
G03Y275699I207J-342D01*
G37*
G36*
G01X59921Y282125D02*
G02X59789Y284034I-1221J875D01*
G03X60404Y284076I290J275D01*
G02X60820Y284469I1221J-875D01*
G03X60878Y285100I-214J338D01*
G02X62705Y284932I1022J1100D01*
G03X62647Y284301I214J-338D01*
G02X60536Y282167I-1022J-1100D01*
G03X59921Y282125I-290J-275D01*
G37*
G36*
G01X77121Y310560D02*
G02X74280Y309752I-1495J-142D01*
G03X73628Y309847I-359J-177D01*
G02X73833Y311468I-1028J953D01*
G03X74487Y311398I351J191D01*
G02X75611Y311920I1138J-980D01*
G03X76005Y312358I-4J400D01*
G02X76624Y313720I1495J142D01*
G03X76592Y314390I-234J325D01*
G02X78158Y314491I708J1210D01*
G03X78212Y313822I244J-317D01*
G02X77515Y310998I-712J-1322D01*
G03X77121Y310560I4J-400D01*
G37*
G36*
G01X80856Y334377D02*
G02X80357Y336497I-1256J823D01*
G03X80894Y336623I202J345D01*
G02X83452Y336548I1256J-823D01*
G03X84132Y336526I347J199D01*
G02X85478Y337141I1168J-776D01*
G03X85922Y337466I51J397D01*
G02X87125Y335723I1478J-266D01*
G03X86663Y335423I-73J-393D01*
G02X84108Y335011I-1363J327D01*
G03X83428I-340J-210D01*
G02X81393Y334503I-1278J789D01*
G03X80856Y334377I-202J-345D01*
G37*
G36*
G01X69590Y336919D02*
G02X67676Y337339I-1172J-769D01*
G03X67787Y337914I-212J339D01*
G02X67711Y338029I1214J885D01*
G03X67038Y338050I-343J-206D01*
G02X64573Y338033I-1238J850D01*
G03X63948Y338068I-326J-231D01*
G02X64009Y339857I-1048J931D01*
G03X64636Y339849I317J245D01*
G02X67089Y339671I1164J-949D01*
G03X67762Y339650I343J206D01*
G02X70185Y339723I1238J-850D01*
G03X70815I315J246D01*
G02X73087Y339836I1185J-923D01*
G03X73676Y339847I289J276D01*
G02X73713Y337814I1124J-996D01*
G03X73124Y337803I-289J-276D01*
G02X70815Y337877I-1124J997D01*
G03X70185I-315J-246D01*
G02X69730Y337488I-1184J924D01*
G03X69590Y336919I195J-350D01*
G37*
G36*
G01X54151Y338469D02*
G02X52807Y338961I-1126J-994D01*
G03X53096Y339555I-58J396D01*
G02X55902Y340302I1304J745D01*
G03X56302Y339902I400J0D01*
G02X57410Y339356I-2J-1402D01*
G03X58090Y339432I317J244D01*
G02X58233Y337922I1362J-633D01*
G03X57552Y337868I-324J-234D01*
G02X54900Y338423I-1252J632D01*
G03X54480Y338800I-399J-22D01*
G02X54313Y338801I-75J1500D01*
G03X54151Y338469I-12J-200D01*
G37*
G36*
G01X49828Y342014D02*
G02X48428Y341938I-628J-1364D01*
G03X48389Y342645I-206J343D01*
G02X47885Y344996I628J1364D01*
G03Y345522I-302J263D01*
G02X47926Y347541I1132J987D01*
G03X47947Y348067I-290J275D01*
G02X47975Y349984I1170J942D01*
G03X47969Y350510I-304J260D01*
G02X48167Y352693I1122J999D01*
G03X48168Y353322I-247J315D01*
G02X50296Y355409I932J1178D01*
G03X50922Y355396I318J242D01*
G02Y353604I1078J-896D01*
G03X50296Y353591I-308J-255D01*
G02X50024Y353316I-1195J910D01*
G03X50023Y352687I247J-315D01*
G02X50377Y352285I-932J-1178D01*
G03X50968Y352178I343J206D01*
G02X50515Y350420I932J-1178D01*
G03X50185Y350479I-184J-78D01*
G02X50122Y350416I-1093J1030D01*
G03X50125Y350123I137J-145D01*
G02X50208Y347977I-1008J-1114D01*
G03X50187Y347451I290J-275D01*
G02X50320Y347257I-1169J-944D01*
G03X50945Y347169I347J199D01*
G02X50621Y345643I978J-1005D01*
G03X50269Y345679I-185J-74D01*
G02X50149Y345522I-1251J832D01*
G03Y344996I302J-263D01*
G02X49789Y342721I-1132J-987D01*
G03X49828Y342014I206J-343D01*
G37*
G36*
G01X88660Y345360D02*
G02X87260Y345321I-660J-1460D01*
G03X87240Y346040I-185J355D01*
G02X88640Y346079I660J1460D01*
G03X88660Y345360I185J-355D01*
G37*
G36*
G01X65611Y349258D02*
G02X65075Y347156I739J-1308D01*
G03X64539Y347292I-339J-212D01*
G02X62698Y347580I-738J1308D01*
G03X62070Y347528I-294J-272D01*
G02X61888Y349295I-1170J772D01*
G03X62512Y349373I281J284D01*
G02X65075Y349394I1288J-773D01*
G03X65611Y349258I339J212D01*
G37*
G36*
G01X-7480Y359273D02*
G03X-6213Y359676I-2J2199D01*
G02X-2154Y358342I1488J-2314D01*
G03X-1414Y358324I374J143D01*
G02X2988I2201J-962D01*
G03X3728Y358342I366J161D01*
G02X7771Y359686I2571J-980D01*
G03X9025Y359273I1283J1786D01*
G01X9056D01*
G03X10323Y359676I-2J2199D01*
G02X14382Y358342I1488J-2314D01*
G03X15122Y358324I374J143D01*
G02X19524I2201J-962D01*
G03X20264Y358342I366J161D01*
G02X24307Y359686I2571J-980D01*
G03X25561Y359273I1283J1786D01*
G01X25591D01*
G03X26858Y359676I-2J2199D01*
G02X30917Y358342I1488J-2314D01*
G03X31657Y358324I374J143D01*
G02Y356400I2201J-962D01*
G03X30917Y356382I-366J-161D01*
G02X26874Y355038I-2571J980D01*
G03X25620Y355451I-1283J-1786D01*
G01X25590D01*
G03X24323Y355048I2J-2199D01*
G02X20264Y356382I-1488J2314D01*
G03X19524Y356400I-374J-143D01*
G02X15122I-2201J962D01*
G03X14382Y356382I-366J-161D01*
G02X10339Y355038I-2571J980D01*
G03X9085Y355451I-1283J-1786D01*
G01X9054D01*
G03X7787Y355048I2J-2199D01*
G02X3728Y356382I-1488J2314D01*
G03X2988Y356400I-374J-143D01*
G02X-1414I-2201J962D01*
G03X-2154Y356382I-366J-161D01*
G02X-6197Y355038I-2571J980D01*
G03X-7451Y355451I-1283J-1786D01*
G01X-7481D01*
G03X-8748Y355048I2J-2199D01*
G02X-12807Y356382I-1488J2314D01*
G03X-13547Y356400I-374J-143D01*
G02Y358324I-2201J962D01*
G03X-12807Y358342I366J161D01*
G02X-8764Y359686I2571J-980D01*
G03X-7510Y359273I1283J1786D01*
G01X-7480D01*
G37*
G36*
G01X60254Y363533D02*
G02X59542Y362141I680J-1226D01*
G03X58951Y362443I-397J-48D01*
G02X59663Y363835I-680J1226D01*
G03X60254Y363533I397J48D01*
G37*
G36*
G01X-12598Y367147D02*
G03X-11331Y367550I-2J2199D01*
G02X-7272Y366216I1488J-2314D01*
G03X-6532Y366198I374J143D01*
G02X-2130I2201J-962D01*
G03X-1390Y366216I366J161D01*
G02X2653Y367560I2571J-980D01*
G03X3907Y367147I1283J1786D01*
G01X3938D01*
G03X5205Y367550I-2J2199D01*
G02X9264Y366216I1488J-2314D01*
G03X10004Y366198I374J143D01*
G02X14405Y366199I2201J-962D01*
G03X15145Y366217I366J161D01*
G02X19188Y367560I2570J-981D01*
G03X20442Y367147I1283J1786D01*
G01X20473D01*
G03X21740Y367550I-2J2199D01*
G02X25799Y366216I1488J-2314D01*
G03X26539Y366198I374J143D01*
G02Y364274I2201J-962D01*
G03X25799Y364256I-366J-161D01*
G02X21756Y362912I-2571J980D01*
G03X20502Y363325I-1283J-1786D01*
G01X20471D01*
G03X19204Y362922I2J-2199D01*
G02X15145Y364255I-1488J2314D01*
G03X14405Y364273I-374J-143D01*
G02X10004Y364274I-2200J963D01*
G03X9264Y364256I-366J-161D01*
G02X5221Y362912I-2571J980D01*
G03X3967Y363325I-1283J-1786D01*
G01X3936D01*
G03X2669Y362922I2J-2199D01*
G02X-1390Y364256I-1488J2314D01*
G03X-2130Y364274I-374J-143D01*
G02X-6532I-2201J962D01*
G03X-7272Y364256I-366J-161D01*
G02X-11315Y362912I-2571J980D01*
G03X-12569Y363325I-1283J-1786D01*
G01X-12599D01*
G03X-13866Y362922I2J-2199D01*
G02X-13882Y367560I-1488J2314D01*
G03X-12628Y367147I1283J1786D01*
G01X-12598D01*
G37*
G36*
G01X57378Y368197D02*
G02X56028Y367107I17J-1402D01*
G03X55633Y367596I-390J89D01*
G02X54645Y370009I-17J1402D01*
G03X54619Y370609I-277J289D01*
G02X56471Y370689I881J1091D01*
G03X56497Y370089I277J-289D01*
G02X56983Y368686I-881J-1091D01*
G03X57378Y368197I390J-89D01*
G37*
G36*
G01X9056Y375021D02*
G03X10323Y375424I-2J2199D01*
G02X14382Y374090I1488J-2314D01*
G03X15122Y374072I374J143D01*
G02X19524I2201J-962D01*
G03X20264Y374090I366J161D01*
G02X24307Y375434I2571J-980D01*
G03X25561Y375021I1283J1786D01*
G01X25591D01*
G03X26858Y375424I-2J2199D01*
G02X30917Y374090I1488J-2314D01*
G03X31657Y374072I374J143D01*
G02Y372148I2201J-962D01*
G03X30917Y372130I-366J-161D01*
G02X26874Y370786I-2571J980D01*
G03X25620Y371199I-1283J-1786D01*
G01X25590D01*
G03X24323Y370796I2J-2199D01*
G02X20264Y372130I-1488J2314D01*
G03X19524Y372148I-374J-143D01*
G02X15122I-2201J962D01*
G03X14382Y372130I-366J-161D01*
G02X10339Y370786I-2571J980D01*
G03X9085Y371199I-1283J-1786D01*
G01X9054D01*
G03X7787Y370796I2J-2199D01*
G02X3728Y372130I-1488J2314D01*
G03X2988Y372148I-374J-143D01*
G02Y374072I-2201J962D01*
G03X3728Y374090I366J161D01*
G02X7771Y375434I2571J-980D01*
G03X9025Y375021I1283J1786D01*
G01X9056D01*
G37*
G36*
G01X-12598Y382895D02*
G03X-11331Y383298I-2J2199D01*
G02X-7272Y381964I1488J-2314D01*
G03X-6532Y381946I374J143D01*
G02X-2130I2201J-962D01*
G03X-1390Y381964I366J161D01*
G02X2653Y383308I2571J-980D01*
G03X3907Y382895I1283J1786D01*
G01X3938D01*
G03X5205Y383298I-2J2199D01*
G02X9264Y381964I1488J-2314D01*
G03X10004Y381946I374J143D01*
G02Y380022I2201J-962D01*
G03X9264Y380004I-366J-161D01*
G02X5221Y378660I-2571J980D01*
G03X3967Y379073I-1283J-1786D01*
G01X3936D01*
G03X2669Y378670I2J-2199D01*
G02X-1390Y380004I-1488J2314D01*
G03X-2130Y380022I-374J-143D01*
G02X-6532I-2201J962D01*
G03X-7272Y380004I-366J-161D01*
G02X-11315Y378660I-2571J980D01*
G03X-12569Y379073I-1283J-1786D01*
G01X-12599D01*
G03X-13866Y378670I2J-2199D01*
G02X-13882Y383308I-1488J2314D01*
G03X-12628Y382895I1283J1786D01*
G01X-12598D01*
G37*
G36*
G01X25591Y390769D02*
G03X26858Y391172I-2J2199D01*
G02X30917Y389838I1488J-2314D01*
G03X31657Y389820I374J143D01*
G02Y387896I2201J-962D01*
G03X30917Y387878I-366J-161D01*
G02X26874Y386534I-2571J980D01*
G03X25620Y386947I-1283J-1786D01*
G01X25590D01*
G03X24323Y386544I2J-2199D01*
G02X20264Y387878I-1488J2314D01*
G03X19524Y387896I-374J-143D01*
G02Y389820I-2201J962D01*
G03X20264Y389838I366J161D01*
G02X24307Y391182I2571J-980D01*
G03X25561Y390769I1283J1786D01*
G01X25591D01*
G37*
G36*
G01X56932Y389382D02*
G02X56134Y387785I568J-1282D01*
G03X55567Y388054I-390J-90D01*
G02X56377Y389674I-667J1346D01*
G03X56932Y389382I393J74D01*
G37*
G36*
G01X-12598Y398643D02*
G03X-11331Y399046I-2J2199D01*
G02X-7272Y397712I1488J-2314D01*
G03X-6532Y397694I374J143D01*
G02X-2130I2201J-962D01*
G03X-1390Y397712I366J161D01*
G02X2653Y399056I2571J-980D01*
G03X3907Y398643I1283J1786D01*
G01X3938D01*
G03X5205Y399046I-2J2199D01*
G02X9264Y397712I1488J-2314D01*
G03X10004Y397694I374J143D01*
G02Y395770I2201J-962D01*
G03X9264Y395752I-366J-161D01*
G02X5221Y394408I-2571J980D01*
G03X3967Y394821I-1283J-1786D01*
G01X3936D01*
G03X2669Y394418I2J-2199D01*
G02X-1390Y395752I-1488J2314D01*
G03X-2130Y395770I-374J-143D01*
G02X-6532I-2201J962D01*
G03X-7272Y395752I-366J-161D01*
G02X-11315Y394408I-2571J980D01*
G03X-12569Y394821I-1283J-1786D01*
G01X-12599D01*
G03X-13866Y394418I2J-2199D01*
G02X-13882Y399056I-1488J2314D01*
G03X-12628Y398643I1283J1786D01*
G01X-12598D01*
G37*
G36*
G01X-7480Y406517D02*
G03X-6213Y406920I-2J2199D01*
G02X-2154Y405586I1488J-2314D01*
G03X-1414Y405568I374J143D01*
G02X2988I2201J-962D01*
G03X3728Y405586I366J161D01*
G02X7771Y406930I2571J-980D01*
G03X9025Y406517I1283J1786D01*
G01X9056D01*
G03X10323Y406920I-2J2199D01*
G02X14382Y405586I1488J-2314D01*
G03X15122Y405568I374J143D01*
G02X19524I2201J-962D01*
G03X20264Y405586I366J161D01*
G02X24307Y406930I2571J-980D01*
G03X25561Y406517I1283J1786D01*
G01X25591D01*
G03X26858Y406920I-2J2199D01*
G02X30917Y405586I1488J-2314D01*
G03X31657Y405568I374J143D01*
G02Y403644I2201J-962D01*
G03X30917Y403626I-366J-161D01*
G02X26874Y402282I-2571J980D01*
G03X25620Y402695I-1283J-1786D01*
G01X25590D01*
G03X24323Y402292I2J-2199D01*
G02X20264Y403626I-1488J2314D01*
G03X19524Y403644I-374J-143D01*
G02X15122I-2201J962D01*
G03X14382Y403626I-366J-161D01*
G02X10339Y402282I-2571J980D01*
G03X9085Y402695I-1283J-1786D01*
G01X9054D01*
G03X7787Y402292I2J-2199D01*
G02X3728Y403626I-1488J2314D01*
G03X2988Y403644I-374J-143D01*
G02X-1414I-2201J962D01*
G03X-2154Y403626I-366J-161D01*
G02X-6197Y402282I-2571J980D01*
G03X-7451Y402695I-1283J-1786D01*
G01X-7481D01*
G03X-8748Y402292I2J-2199D01*
G02X-12807Y403626I-1488J2314D01*
G03X-13547Y403644I-374J-143D01*
G02Y405568I-2201J962D01*
G03X-12807Y405586I366J161D01*
G02X-8764Y406930I2571J-980D01*
G03X-7510Y406517I1283J1786D01*
G01X-7480D01*
G37*
G36*
G01X-12598Y414391D02*
G03X-11331Y414794I-2J2199D01*
G02X-7272Y413460I1488J-2314D01*
G03X-6532Y413442I374J143D01*
G02X-2130I2201J-962D01*
G03X-1390Y413460I366J161D01*
G02X2653Y414804I2571J-980D01*
G03X3907Y414391I1283J1786D01*
G01X3938D01*
G03X5205Y414794I-2J2199D01*
G02X9264Y413460I1488J-2314D01*
G03X10004Y413442I374J143D01*
G02X14405Y413443I2201J-962D01*
G03X15145Y413461I366J161D01*
G02X19188Y414804I2570J-981D01*
G03X20442Y414391I1283J1786D01*
G01X20473D01*
G03X21740Y414794I-2J2199D01*
G02X25799Y413460I1488J-2314D01*
G03X26539Y413442I374J143D01*
G02Y411518I2201J-962D01*
G03X25799Y411500I-366J-161D01*
G02X21756Y410156I-2571J980D01*
G03X20502Y410569I-1283J-1786D01*
G01X20471D01*
G03X19204Y410166I2J-2199D01*
G02X15145Y411499I-1488J2314D01*
G03X14405Y411517I-374J-143D01*
G02X10004Y411518I-2200J963D01*
G03X9264Y411500I-366J-161D01*
G02X5221Y410156I-2571J980D01*
G03X3967Y410569I-1283J-1786D01*
G01X3936D01*
G03X2669Y410166I2J-2199D01*
G02X-1390Y411500I-1488J2314D01*
G03X-2130Y411518I-374J-143D01*
G02X-6532I-2201J962D01*
G03X-7272Y411500I-366J-161D01*
G02X-11315Y410156I-2571J980D01*
G03X-12569Y410569I-1283J-1786D01*
G01X-12599D01*
G03X-13866Y410166I2J-2199D01*
G02X-13882Y414804I-1488J2314D01*
G03X-12628Y414391I1283J1786D01*
G01X-12598D01*
G37*
G36*
G01X1668695Y414289D02*
G02X1667241Y414313I-749J-1302D01*
G03X1667264Y415007I-187J354D01*
G02X1667031Y417213I736J1193D01*
G03X1667053Y417768I-277J289D01*
G02X1669069Y417687I1047J932D01*
G03X1669047Y417132I277J-289D01*
G02X1668696Y414983I-1047J-932D01*
G03X1668695Y414289I198J-347D01*
G37*
G36*
G01X50776Y420624D02*
G03X51335Y420257I400J0D01*
G02X52781Y417888I554J-1288D01*
G03X52743Y417306I254J-309D01*
G02X52777Y417268I-1102J-1020D01*
G03X53411Y417310I301J263D01*
G02X53530Y415491I1251J-832D01*
G03X52896Y415449I-301J-263D01*
G02X50750Y417487I-1251J832D01*
G03X50818Y418067I-238J322D01*
G02X50793Y418096I1049J930D01*
G03X50477Y418091I-156J-124D01*
G02X47754Y418995I-1211J904D01*
G01Y423996D01*
G02X50180Y425198I1511J-1D01*
G03X50748Y425284I242J318D01*
G02X51335Y423183I1142J-813D01*
G03X50776Y422816I-159J-367D01*
G01Y420624D01*
G37*
G36*
G01X1668579Y425859D02*
G02X1666942Y425900I-850J-1238D01*
G03X1666959Y426571I-209J341D01*
G02X1666846Y428962I850J1238D01*
G03X1666813Y429601I-256J307D01*
G02X1666878Y432138I836J1248D01*
G03X1666866Y432832I-205J344D01*
G02X1668359Y432860I722J1317D01*
G03X1668371Y432166I205J-344D01*
G02X1668612Y429696I-722J-1317D01*
G03X1668645Y429057I256J-307D01*
G02X1668596Y426530I-836J-1248D01*
G03X1668579Y425859I209J-341D01*
G37*
G36*
G01X3422Y426362D02*
X5628D01*
G03X5938Y427014I0J400D01*
G02X7849Y426765I1087J886D01*
G03X7862Y426109I235J-323D01*
G02X8536Y424860I-837J-1258D01*
G01Y424765D01*
X8527Y424681D01*
G02X7025Y423338I-1502J168D01*
G01X2024D01*
G02X1188Y426109I1J1512D01*
G03X1201Y426765I-222J333D01*
G02X3112Y427014I824J1135D01*
G03X3422Y426362I310J-252D01*
G37*
G36*
G01X13422D02*
X17025D01*
G02X18284Y425687I0J-1512D01*
G03X18940Y425674I333J222D01*
G02Y424026I1135J-824D01*
G03X18284Y424013I-323J-235D01*
G02X17025Y423338I-1259J837D01*
G01X12024D01*
G02X11188Y426109I1J1512D01*
G03X11201Y426765I-222J333D01*
G02X13112Y427014I824J1135D01*
G03X13422Y426362I310J-252D01*
G37*
G36*
G01X42458Y429594D02*
G02X41587Y430801I-1493J-160D01*
G03X42152Y431195I166J364D01*
G02X43010Y430006I1398J105D01*
G03X42458Y429594I-154J-369D01*
G37*
G36*
G01X635495Y436263D02*
G02X635317Y437648I-1295J538D01*
G03X636005Y437737I318J242D01*
G02X638310Y438172I1295J-537D01*
G03X638956Y438271I288J278D01*
G02X639179Y436600I1344J-671D01*
G03X638530Y436526I-298J-266D01*
G02X636183Y436352I-1230J674D01*
G03X635495Y436263I-318J-242D01*
G37*
G36*
G01X1665820Y439101D02*
G02X1663704I-1058J-1066D01*
G03Y439669I-282J284D01*
G02X1663839Y441920I1058J1066D01*
G03Y442550I-246J315D01*
G02X1665685I923J1185D01*
G03Y441920I246J-315D01*
G02X1665828Y441793I-924J-1184D01*
G03X1666396I284J282D01*
G02X1668449Y441867I1066J-1058D01*
G03X1668975I263J302D01*
G02X1669106Y441969I987J-1132D01*
G03X1669076Y442646I-227J329D01*
G02X1668684Y444940I740J1307D01*
G03Y445466I-302J263D01*
G02Y447440I1132J987D01*
G03Y447966I-302J263D01*
G02X1671200Y449537I1132J987D01*
G03X1671884Y449446I369J155D01*
G02X1674198Y447533I1184J-924D01*
G03Y447007I301J-263D01*
G02X1673952Y444810I-1134J-985D01*
G03X1674054Y444111I236J-322D01*
G02X1674795Y441857I-504J-1415D01*
G03X1675126Y441233I332J-224D01*
G02X1673875Y440570I-5J-1502D01*
G03X1673544Y441194I-332J224D01*
G02X1672662Y443908I6J1502D01*
G03X1672560Y444607I-236J322D01*
G02X1671681Y445436I504J1415D01*
G03X1670998Y445526I-368J-156D01*
G02X1670948Y445466I-1178J931D01*
G03Y444940I302J-263D01*
G02X1670672Y442719I-1132J-987D01*
G03X1670702Y442042I227J-329D01*
G02X1670640Y439395I-740J-1307D01*
G03X1670454Y438879I181J-357D01*
G02X1667641Y438726I-1378J-598D01*
G03X1667302Y439242I-382J118D01*
G02X1666396Y439677I160J1493D01*
G03X1665828I-284J-282D01*
G02X1665820Y439669I-1066J1058D01*
G03Y439101I282J-284D01*
G37*
G36*
G01X1286966Y440969D02*
G02X1285411Y441521I-1197J-907D01*
G03X1285634Y442151I-96J388D01*
G02X1286812Y444560I1197J907D01*
G03X1287199Y445039I-5J400D01*
G02X1288690Y443836I1472J299D01*
G03X1288303Y443357I5J-400D01*
G02X1287189Y441599I-1472J-299D01*
G03X1286966Y440969I96J-388D01*
G37*
G36*
G01X10786Y443296D02*
X15788D01*
G02X17045Y442622I-1J-1511D01*
G03X17701Y442609I333J222D01*
G02Y440961I1135J-824D01*
G03X17045Y440948I-323J-235D01*
G02X15788Y440274I-1258J837D01*
G01X10786D01*
G02X9528Y440948I0J1511D01*
G03X8871Y440962I-333J-221D01*
G02Y442608I-1135J823D01*
G03X9528Y442622I324J235D01*
G02X10786Y443296I1258J-837D01*
G37*
G36*
G01X587529Y446495D02*
G02X586415Y447709I-1393J-160D01*
G03X586892Y448146I80J392D01*
G02X588006Y446932I1393J160D01*
G03X587529Y446495I-80J-392D01*
G37*
G36*
G01X1887409Y446826D02*
G02X1887369Y449230I-1079J1184D01*
G03X1887897Y449238I259J304D01*
G02X1890236Y449043I1079J-1184D01*
G03X1890866I315J247D01*
G02X1893386I1260J-989D01*
G03X1894015I315J247D01*
G02X1896665Y448850I1260J-989D01*
G03X1897326Y448800I347J199D01*
G02X1899650Y448612I1099J-870D01*
G03X1900349I349J194D01*
G02X1902754Y448688I1225J-682D01*
G03X1903434Y448699I337J216D01*
G02X1905903Y448860I1290J-769D01*
G03X1906585Y448951I314J248D01*
G02X1909099Y449082I1289J-551D01*
G03X1909798I350J194D01*
G02Y447718I1225J-682D01*
G03X1909099I-349J-194D01*
G02X1906802Y447497I-1225J682D01*
G03X1906123Y447384I-306J-258D01*
G02X1903434Y447161I-1399J546D01*
G03X1902754Y447172I-343J-205D01*
G02X1900349Y447248I-1180J758D01*
G03X1899650I-350J-194D01*
G02X1897261Y447149I-1225J682D01*
G03X1896598Y447151I-332J-223D01*
G02X1894015Y447065I-1323J903D01*
G03X1893386I-314J-247D01*
G02X1890866I-1260J989D01*
G03X1890236I-315J-247D01*
G02X1887937Y446834I-1260J989D01*
G03X1887409Y446826I-259J-304D01*
G37*
G36*
G01X1873956Y448977D02*
G02X1871764I-1096J-1027D01*
G03Y449523I-292J273D01*
G02X1871431Y451012I1096J1027D01*
G03X1871001Y451532I-381J123D01*
G02X1869722Y451992I-186J1490D01*
G03X1869133Y451984I-291J-275D01*
G02X1867965Y451486I-1118J1003D01*
G03X1867552Y451089I-13J-400D01*
G02X1866100Y452601I-1502J11D01*
G03X1866513Y452998I13J400D01*
G02X1869108Y454017I1502J-11D01*
G03X1869697Y454025I291J275D01*
G02X1872244Y452560I1118J-1003D01*
G03X1872674Y452040I381J-123D01*
G02X1873956Y449523I186J-1490D01*
G03Y448977I292J-273D01*
G37*
G36*
G01X1764900Y448624D02*
G02X1764882Y447205I1200J-725D01*
G03X1764192Y447214I-348J-198D01*
G02X1764210Y448633I-1200J725D01*
G03X1764900Y448624I348J198D01*
G37*
G36*
G01X1805305Y448413D02*
G02X1804314Y449266I-1305J-513D01*
G03X1804772Y449813I90J390D01*
G02X1806161Y451920I1389J595D01*
G01X1811161D01*
G02X1812672Y450418I-1J-1512D01*
G01Y450323D01*
X1812663Y450239D01*
G02X1811161Y448896I-1502J169D01*
G01X1806161D01*
G02X1805779Y448946I4J1512D01*
G03X1805305Y448413I-102J-387D01*
G37*
G36*
G01X1865545Y447255D02*
G02Y448545I-1245J645D01*
G03X1866255I355J184D01*
G02Y447255I1245J-645D01*
G03X1865545I-355J-184D01*
G37*
G36*
G01X1818760Y451920D02*
X1823760D01*
G02X1825272Y450418I0J-1512D01*
G01Y450323D01*
X1825262Y450239D01*
G02X1825188Y449914I-1502J171D01*
G03X1825659Y449394I378J-131D01*
G02X1824645Y448445I325J-1364D01*
G03X1824158Y448950I-382J119D01*
G02X1823760Y448896I-400J1458D01*
G01X1818760D01*
G02X1818412Y448937I2J1512D01*
G03X1817924Y448493I-92J-389D01*
G02X1815384Y447499I-1389J-193D01*
G03X1814685Y447420I-328J-229D01*
G02X1814536Y448746I-1300J525D01*
G03X1815235Y448825I328J229D01*
G02X1816803Y449676I1300J-525D01*
G03X1817273Y450140I76J393D01*
G02X1818760Y451920I1488J268D01*
G37*
G36*
G01X1751632Y447381D02*
G02X1749052Y448446I-1239J656D01*
G03X1748565Y448949I-382J117D01*
G02X1748169Y448896I-397J1459D01*
G01X1743169D01*
G02X1742849Y448931I3J1512D01*
G03X1742364Y448526I-85J-391D01*
G02X1739807Y447682I-1401J-50D01*
G03X1739104Y447599I-330J-226D01*
G02X1736649Y448907I-1310J500D01*
G03X1736496Y449498I-327J231D01*
G02X1738337Y449930I654J1352D01*
G03X1738463Y449333I316J-245D01*
G02X1738951Y448894I-668J-1233D01*
G03X1739654Y448977I330J226D01*
G02X1741197Y449858I1309J-501D01*
G03X1741663Y450285I67J394D01*
G02X1743169Y451920I1507J123D01*
G01X1748169D01*
G02X1749680Y450418I-1J-1512D01*
G01Y450323D01*
X1749671Y450239D01*
G02X1749599Y449920I-1501J171D01*
G03X1750070Y449401I379J-130D01*
G02X1751605Y448742I323J-1364D01*
G03X1752304Y448756I346J201D01*
G02X1753849Y449468I1239J-656D01*
G03X1754320Y449973I88J390D01*
G02X1755767Y451920I1448J435D01*
G01X1760767D01*
G02X1762278Y450418I-1J-1512D01*
G01Y450323D01*
X1762269Y450239D01*
G02X1760767Y448896I-1502J169D01*
G01X1755767D01*
G02X1755387Y448945I2J1512D01*
G03X1754899Y448457I-101J-387D01*
G02X1752331Y447395I-1356J-357D01*
G03X1751632Y447381I-346J-201D01*
G37*
G36*
G01X1860393Y448506D02*
G02X1858580Y449393I-1334J-430D01*
G03X1858824Y449892I-137J376D01*
G02X1858861Y450855I1334J431D01*
G03X1858523Y451405I-370J152D01*
G02X1859930Y452270I110J1398D01*
G03X1860268Y451720I370J-152D01*
G02X1860637Y449005I-110J-1398D01*
G03X1860393Y448506I137J-376D01*
G37*
G36*
G01X1768366Y451920D02*
X1773366D01*
G02X1774878Y450418I0J-1512D01*
G01Y450323D01*
X1774868Y450239D01*
G02X1774814Y449974I-1502J168D01*
G03X1775284Y449468I383J-116D01*
G02X1776815Y448781I306J-1368D01*
G03X1777515I350J194D01*
G02X1779046Y449468I1225J-681D01*
G03X1779516Y449974I87J390D01*
G02X1780964Y451920I1448J434D01*
G01X1785964D01*
G02X1787476Y450418I0J-1512D01*
G01Y450323D01*
X1787466Y450239D01*
G02X1787452Y450140I-1503J162D01*
G03X1787921Y449676I393J-71D01*
G02X1789392Y449019I268J-1376D01*
G03X1790091Y449042I343J206D01*
G02X1791593Y449779I1247J-642D01*
G03X1792063Y450221I73J393D01*
G02X1793563Y451920I1500J187D01*
G01X1798563D01*
G02X1800074Y450418I-1J-1512D01*
G01Y450323D01*
X1800065Y450239D01*
G02X1798563Y448896I-1502J169D01*
G01X1793562D01*
G02X1793224Y448935I3J1512D01*
G03X1792735Y448513I-90J-390D01*
G02X1790135Y447681I-1397J-112D01*
G03X1789436Y447658I-343J-206D01*
G02X1786800Y448493I-1247J641D01*
G03X1786312Y448937I-396J55D01*
G02X1785964Y448896I-350J1471D01*
G01X1780963D01*
G02X1780583Y448945I2J1512D01*
G03X1780096Y448456I-100J-387D01*
G02X1777515Y447419I-1356J-355D01*
G03X1776815I-350J-194D01*
G02X1774234Y448456I-1225J682D01*
G03X1773747Y448945I-387J102D01*
G02X1773366Y448896I-382J1463D01*
G01X1768366D01*
G02Y451920I0J1512D01*
G37*
G36*
G01X1829823Y449415D02*
G02X1829523Y451155I-1223J685D01*
G03X1830144Y451277I263J301D01*
G02X1831495Y452112I1352J-677D01*
G01X1836495D01*
G02X1837749Y451444I0J-1512D01*
G03X1838374Y451395I332J223D01*
G02X1838275Y449604I1026J-955D01*
G03X1837649Y449623I-321J-239D01*
G02X1836495Y449088I-1154J977D01*
G01X1831494D01*
G02X1830449Y449509I2J1512D01*
G03X1829823Y449415I-277J-289D01*
G37*
G36*
G01X1887351Y453165D02*
G02X1884768Y453561I-1151J1115D01*
G03X1884063Y453579I-357J-180D01*
G02X1884101Y455087I-1394J790D01*
G03X1884806Y455069I357J180D01*
G02X1887264Y455477I1394J-789D01*
G03X1887817Y455498I266J299D01*
G02X1890228Y455372I1151J-1115D01*
G03X1890858I315J247D01*
G02X1893467Y455247I1260J-989D01*
G03X1894130Y455232I337J216D01*
G02X1896500Y455103I1144J-810D01*
G03X1897200I350J194D01*
G02X1899604Y455180I1225J-681D01*
G03X1900284Y455192I336J217D01*
G02X1902864Y455191I1290J-770D01*
G03X1903544Y455180I343J205D01*
G02X1905949Y455103I1179J-758D01*
G03X1906649I350J194D01*
G02Y453741I1225J-681D01*
G03X1905949I-350J-194D01*
G02X1903544Y453664I-1226J681D01*
G03X1902864Y453653I-337J-216D01*
G02X1900284Y453652I-1290J769D01*
G03X1899604Y453664I-344J-205D01*
G02X1897200Y453741I-1179J758D01*
G03X1896500I-350J-194D01*
G02X1894151Y453584I-1225J681D01*
G03X1893488Y453553I-321J-239D01*
G02X1890858Y453394I-1370J830D01*
G03X1890228I-315J-247D01*
G02X1887904Y453186I-1260J989D01*
G03X1887351Y453165I-266J-299D01*
G37*
G36*
G01X22038Y453348D02*
G02X19937Y455766I-1040J1218D01*
G03Y456366I-265J300D01*
G02X20141Y458919I1061J1200D01*
G03X20165Y459579I-214J338D01*
G02X22158Y462084I953J1287D01*
G03X22678I260J304D01*
G02X24758I1040J-1218D01*
G03X25278I260J304D01*
G02X27382Y462064I1041J-1218D01*
G03X27915Y462066I265J299D01*
G02X29845Y459523I1073J-1190D01*
G03X29821Y458863I214J-338D01*
G02X29929Y456376I-953J-1287D01*
G03Y455776I265J-300D01*
G02X27804Y453378I-1061J-1200D01*
G03X27271Y453376I-265J-299D01*
G02X25158Y453348I-1072J1190D01*
G03X24638I-260J-304D01*
G02X22558I-1040J1218D01*
G03X22038I-260J-304D01*
G37*
G36*
G01X1370783Y458965D02*
G02X1370811Y457244I1245J-840D01*
G03X1370165Y457246I-324J-234D01*
G02X1370136Y458941I-1131J828D01*
G03X1370783Y458965I315J247D01*
G37*
G36*
G01X1261832Y463030D02*
G02X1261198Y461801I868J-1226D01*
G03X1260577Y462133I-400J-1D01*
G02X1261201Y463344I-777J1167D01*
G03X1261832Y463030I400J12D01*
G37*
G36*
G01X608723Y464975D02*
G02X607410Y464044I77J-1500D01*
G03X607034Y464595I-370J151D01*
G02X607020Y467399I-22J1402D01*
G03X607396Y467941I2J400D01*
G02X608736Y466974I1404J534D01*
G03X608340Y466447I-17J-399D01*
G02X608328Y465513I-1328J-450D01*
G03X608723Y464975I375J-139D01*
G37*
G36*
G01X1325145Y463100D02*
G02X1322522Y463000I-1330J443D01*
G03X1321947Y463188I-369J-155D01*
G02X1322582Y464991I-775J1286D01*
G03X1323148Y464776I376J137D01*
G02X1324672Y464653I667J-1233D01*
G03X1325296Y464843I245J316D01*
G02X1327682Y465322I1330J-443D01*
G03X1328285I301J263D01*
G02X1328242Y463404I1134J-985D01*
G03X1327640Y463431I-313J-249D01*
G02X1325769Y463290I-1014J969D01*
G03X1325145Y463100I-245J-316D01*
G37*
G36*
G01X-5037Y465901D02*
G02X-6839Y466148I-1063J-1061D01*
G03X-6753Y466779I-197J348D01*
G02X-4951Y466532I1063J1061D01*
G03X-5037Y465901I197J-348D01*
G37*
G36*
G01X1302222Y465814D02*
G02X1302177Y467261I-1222J686D01*
G03X1302868Y467294I336J217D01*
G02X1302914Y465824I1332J-694D01*
G03X1302222Y465814I-343J-206D01*
G37*
G36*
G01X1273159Y473023D02*
G02X1271613Y472356I-329J-1363D01*
G03X1271345Y472947I-347J199D01*
G02X1272914Y473624I295J1473D01*
G03X1273159Y473023I339J-212D01*
G37*
G36*
G01X66912Y475954D02*
G02X65589Y477106I-1462J-344D01*
G03X66015Y477596I37J398D01*
G02X67338Y476444I1462J344D01*
G03X66912Y475954I-37J-398D01*
G37*
G36*
G01X4143Y479487D02*
G02X3736Y477702I957J-1157D01*
G03X3117Y477843I-364J-167D01*
G02X912Y478164I-957J1157D01*
G03X248I-332J-223D01*
G02X-1706Y480326I-1248J836D01*
G03X-1685Y481020I-188J353D01*
G02X-194Y480974I786J1280D01*
G03X-215Y480280I188J-353D01*
G02X248Y479836I-784J-1281D01*
G03X912I332J223D01*
G02X1422Y480308I1248J-836D01*
G03X1512Y480936I-196J349D01*
G02X3813Y482853I1076J1047D01*
G03X4465I326J232D01*
G02Y481113I1224J-870D01*
G03X3813I-326J-232D01*
G02X3327Y480675I-1224J870D01*
G03X3237Y480047I196J-349D01*
G02X3524Y479628I-1078J-1046D01*
G03X4143Y479487I364J167D01*
G37*
G36*
G01X90959Y478858D02*
G02X90269Y480490I-1462J344D01*
G03X90864Y480741I206J343D01*
G02X92986Y481747I1462J-343D01*
G03X93548Y482003I176J360D01*
G02X94338Y480263I1450J-391D01*
G03X93776Y480007I-176J-360D01*
G02X91554Y479109I-1450J391D01*
G03X90959Y478858I-206J-343D01*
G37*
G36*
G01X626920Y480911D02*
G02X626691Y482566I-1351J656D01*
G03X627349Y482657I298J266D01*
G02X627578Y481002I1351J-656D01*
G03X626920Y480911I-298J-266D01*
G37*
G36*
G01X1362050Y480753D02*
G02X1362095Y482533I-1187J921D01*
G03X1362728Y482504I328J229D01*
G02X1364641Y482722I1072J-904D01*
G03X1365188Y482786I240J320D01*
G02X1365373Y480674I1153J-963D01*
G03X1364823Y480642I-258J-306D01*
G02X1362685Y480750I-1023J958D01*
G03X1362050Y480753I-319J-242D01*
G37*
G36*
G01X670277Y482767D02*
G02X668723I-777J-1167D01*
G03Y483433I-222J333D01*
G02X668333Y483823I777J1167D01*
G03X667667I-333J-222D01*
G02X665723Y485767I-1167J777D01*
G03Y486433I-222J333D01*
G02X667277I777J1167D01*
G03Y485767I222J-333D01*
G02X667667Y485377I-777J-1167D01*
G03X668333I333J222D01*
G02X670277Y483433I1167J-777D01*
G03Y482767I222J-333D01*
G37*
G36*
G01X32628Y481823D02*
G02X32555Y483834I-1151J965D01*
G03X33149Y483855I288J278D01*
G02X35646Y483556I1151J-965D01*
G03X36352Y483534I359J177D01*
G02X38556Y483831I1216J-698D01*
G03X39137Y483849I282J284D01*
G02X39197Y481923I1048J-931D01*
G03X38616Y481905I-282J-284D01*
G02X36330Y482179I-1048J931D01*
G03X35624Y482180I-353J-188D01*
G02X33222Y481844I-1324J710D01*
G03X32628Y481823I-288J-278D01*
G37*
G36*
G01X1361979Y485673D02*
G02X1361910Y487467I-1238J851D01*
G03X1362541Y487478I311J251D01*
G02X1364644Y487636I1121J-842D01*
G03X1365216Y487648I280J286D01*
G02X1365202Y485603I1093J-1030D01*
G03X1364630Y485622I-295J-270D01*
G02X1362609Y485710I-968J1014D01*
G03X1361979Y485673I-301J-264D01*
G37*
G36*
G01X657120Y488003D02*
G02X655039Y487963I-1020J-1103D01*
G03X655043Y488524I-283J283D01*
G02X657402Y489870I1007J976D01*
G03X658073Y489694I386J105D01*
G02X657669Y488750I997J-985D01*
G03X657292Y488849I-200J6D01*
G02X657093Y488564I-1240J654D01*
G03X657120Y488003I298J-267D01*
G37*
G36*
G01X729810Y487918D02*
G02X729279Y489554I-1437J438D01*
G03X729902Y489757I240J319D01*
G02X730433Y488121I1437J-438D01*
G03X729810Y487918I-240J-319D01*
G37*
G36*
G01X704195Y491823D02*
G02X702251Y493767I-1167J777D01*
G03Y494433I-222J333D01*
G02X704195Y496377I777J1167D01*
G03X704861I333J222D01*
G02X707195I1167J-777D01*
G03X707861I333J222D01*
G02Y494823I1167J-777D01*
G03X707195I-333J-222D01*
G02X706805Y494433I-1167J777D01*
G03Y493767I222J-333D01*
G02X704861Y491823I-777J-1167D01*
G03X704195I-333J-222D01*
G37*
G36*
G01X1270425Y496507D02*
G02X1267750Y495193I-1420J-490D01*
G03X1267152Y495274I-334J-220D01*
G02X1267418Y497227I-990J1129D01*
G03X1268016Y497146I334J220D01*
G02X1269244Y497499I990J-1130D01*
G03X1269686Y498025I64J395D01*
G02X1270867Y497033I1419J491D01*
G03X1270425Y496507I-64J-395D01*
G37*
G36*
G01X1320594Y499773D02*
G02X1318998Y499049I-294J-1473D01*
G03X1318745Y499637I-347J199D01*
G02X1318149Y499948I332J1362D01*
G03X1317616Y499944I-264J-301D01*
G02X1315733Y499945I-941J1039D01*
G03X1315199Y499949I-269J-296D01*
G02X1313299Y499990I-928J1051D01*
G03X1312745I-277J-288D01*
G02X1311771Y499598I-972J1010D01*
G03X1311371Y499210I0J-400D01*
G02X1309954Y500754I-1501J44D01*
G03X1310375Y501119I23J399D01*
G02X1312745Y502010I1397J-119D01*
G03X1313299I277J288D01*
G02X1315214Y502038I972J-1010D01*
G03X1315748Y502034I269J296D01*
G02X1317601Y502035I927J-1051D01*
G03X1318134Y502039I264J301D01*
G02X1320317Y500351I940J-1040D01*
G03X1320594Y499773I355J-185D01*
G37*
G36*
G01X723743Y500493D02*
G02X722373Y499367I5J-1402D01*
G03X721963Y499846I-392J79D01*
G02X723353Y500988I-69J1500D01*
G03X723743Y500493I388J-95D01*
G37*
G36*
G01X55164Y501438D02*
G02X53088Y503514I-1264J812D01*
G03Y504186I-216J336D01*
G02X55164Y506262I812J1264D01*
G03X55836I336J216D01*
G02X58364I1264J-812D01*
G03X59036I336J216D01*
G02X59488Y506714I1264J-812D01*
G03Y507386I-216J336D01*
G02X61112I812J1264D01*
G03Y506714I216J-336D01*
G02Y504186I-812J-1264D01*
G03Y503514I216J-336D01*
G02X59036Y501438I-812J-1264D01*
G03X58364I-336J-216D01*
G02X55836I-1264J812D01*
G03X55164I-336J-216D01*
G37*
G36*
G01X680346Y502988D02*
G02X680219Y504688I-1297J758D01*
G03X680868Y504724I312J251D01*
G02X683217Y504747I1182J-754D01*
G03X683883I333J222D01*
G02Y503193I1167J-777D01*
G03X683217I-333J-222D01*
G02X680993Y503049I-1167J777D01*
G03X680346Y502988I-302J-263D01*
G37*
G36*
G01X-16228Y504962D02*
G02X-17656Y504700I-498J-1311D01*
G03X-17791Y505378I-265J300D01*
G02X-16342Y505643I489J1420D01*
G03X-16228Y504962I256J-307D01*
G37*
G36*
G01X1345941Y508897D02*
G02X1345750Y507224I1140J-978D01*
G03X1345102Y507310I-354J-186D01*
G02X1345290Y508959I-1029J953D01*
G03X1345941Y508897I347J198D01*
G37*
G36*
G01X713248Y511896D02*
G02X713116Y513666I-1148J804D01*
G03X713743Y513726I290J275D01*
G02X713877Y511929I1266J-809D01*
G03X713248Y511896I-302J-263D01*
G37*
G36*
G01X653167Y513123D02*
G02Y514677I-1167J777D01*
G03X653833I333J222D01*
G02Y513123I1167J-777D01*
G03X653167I-333J-222D01*
G37*
G36*
G01X659667D02*
G02Y514677I-1167J777D01*
G03X660333I333J222D01*
G02Y513123I1167J-777D01*
G03X659667I-333J-222D01*
G37*
G36*
G01X58748Y517276D02*
G02X57124I-812J-1264D01*
G03Y517948I-216J336D01*
G02X56933Y518094I814J1263D01*
G03X56420Y518113I-268J-297D01*
G02X54397Y518281I-920J1187D01*
G03X54103I-147J-136D01*
G02X54037Y518214I-1102J1020D01*
G03X54036Y517925I138J-145D01*
G02X51848Y517819I-1044J-1079D01*
G03X51849Y518335I-305J259D01*
G02X51868Y520287I1151J965D01*
G03Y520813I-302J263D01*
G02Y522787I1132J987D01*
G03Y523313I-302J263D01*
G02X51736Y523488I1130J990D01*
G03X51064I-336J-216D01*
G02X48577Y523428I-1264J812D01*
G03X47885Y523355I-325J-233D01*
G02X46049Y525384I-1378J598D01*
G03X46230Y526025I-122J381D01*
G02X47827Y525574I1139J980D01*
G03X47646Y524933I122J-381D01*
G02X47730Y524825I-1143J-975D01*
G03X48422Y524898I325J233D01*
G02X51064Y525112I1378J-598D01*
G03X51736I336J216D01*
G02X53987Y525432I1264J-812D01*
G03X54513I263J302D01*
G02X56487I987J-1132D01*
G03X57013I263J302D01*
G02X58096Y525799I987J-1132D01*
G03X58517Y526262I26J399D01*
G02X59904Y525001I1483J238D01*
G03X59483Y524538I-26J-399D01*
G02X59132Y523313I-1483J-238D01*
G03Y522787I302J-263D01*
G02X59158Y522757I-1122J-999D01*
G03X59475Y522769I154J128D01*
G02X59673Y520804I1225J-869D01*
G03X59105Y520783I-274J-292D01*
G02X59075Y520751I-1111J1011D01*
G03X59061Y520207I286J-280D01*
G02X58748Y517948I-1125J-995D01*
G03Y517276I216J-336D01*
G37*
G36*
G01X1389321Y517663D02*
G02X1389190Y515874I1009J-973D01*
G03X1388577Y515919I-325J-233D01*
G02X1386599Y515879I-1009J973D01*
G03X1386036Y515869I-276J-289D01*
G02X1384096Y515805I-1003J979D01*
G03X1383551Y515796I-268J-297D01*
G02X1383515Y517848I-973J1009D01*
G03X1384060Y517857I268J297D01*
G02X1386002Y517861I973J-1009D01*
G03X1386565Y517871I276J289D01*
G02X1387959Y518239I1004J-979D01*
G03X1388120Y518600I54J192D01*
G02X1387833Y518839I746J1187D01*
G03X1387277Y518871I-294J-271D01*
G02X1385386Y518921I-918J1060D01*
G03X1384832I-277J-288D01*
G02X1382781Y519035I-973J1010D01*
G03X1382167Y519037I-308J-256D01*
G02X1380132Y518921I-1072J903D01*
G03X1379580Y518919I-275J-290D01*
G02X1377636Y518921I-971J1012D01*
G03X1377082I-277J-288D01*
G02X1375031Y519035I-973J1010D01*
G03X1374417Y519037I-308J-256D01*
G02X1374423Y520836I-1072J903D01*
G03X1375037Y520834I308J256D01*
G02X1377082Y520941I1073J-903D01*
G03X1377636I277J288D01*
G02X1379572Y520950I973J-1010D01*
G03X1380124Y520952I275J290D01*
G02X1382173Y520836I970J-1012D01*
G03X1382787Y520834I308J256D01*
G02X1384832Y520941I1073J-903D01*
G03X1385386I277J288D01*
G02X1387391Y520880I973J-1010D01*
G03X1387947Y520848I294J271D01*
G02X1387970Y520867I904J-1071D01*
G03X1387968Y521176I-128J154D01*
G02X1388072Y523433I882J1090D01*
G03X1388083Y524090I-222J332D01*
G02X1389678Y524063I817J1140D01*
G03X1389667Y523406I222J-332D01*
G02X1389874Y521308I-817J-1140D01*
G03X1389877Y520758I292J-273D01*
G02X1388967Y518390I-1012J-970D01*
G03X1388679Y517747I29J-399D01*
G02X1388708Y517708I-1110J-856D01*
G03X1389321Y517663I325J233D01*
G37*
G36*
G01X5432Y517745D02*
G02X5384Y516393I1316J-724D01*
G03X4670Y516419I-364J-167D01*
G02X4718Y517771I-1316J724D01*
G03X5432Y517745I364J167D01*
G37*
G36*
G01X716858Y523292D02*
G02X715546Y523223I-591J-1272D01*
G03X715509Y523928I-206J343D01*
G02X715090Y526173I591J1272D01*
G03Y526727I-288J277D01*
G02X715006Y526823I1012J970D01*
G03X714694I-156J-125D01*
G02X713488Y526302I-1094J877D01*
G03X713067Y525810I-32J-399D01*
G02X711816Y526881I-1363J-327D01*
G03X712237Y527373I32J399D01*
G02X712590Y528673I1363J328D01*
G03Y529227I-288J277D01*
G02Y531173I1010J973D01*
G03Y531727I-288J277D01*
G02X714573Y533710I1010J973D01*
G03X715127I277J288D01*
G02X717110Y531727I973J-1010D01*
G03Y531173I288J-277D01*
G02Y529227I-1010J-973D01*
G03Y528673I288J-277D01*
G02Y526727I-1010J-973D01*
G03Y526173I288J-277D01*
G02X716821Y523997I-1010J-973D01*
G03X716858Y523292I206J-343D01*
G37*
G36*
G01X-1302Y523348D02*
G02X-3807Y523740I-1128J992D01*
G03X-4508Y523800I-367J-159D01*
G02X-4411Y525167I-1172J770D01*
G03X-3709Y525128I362J171D01*
G02X-1310Y525340I1279J-788D01*
G03X-725Y525328I298J267D01*
G02X-717Y523365I1005J-977D01*
G03X-1302Y523348I-285J-281D01*
G37*
G36*
G01X733399Y525402D02*
G02X731512Y525281I-877J-1094D01*
G03Y525835I-288J277D01*
G02X731479Y527745I1010J973D01*
G03X731461Y528298I-298J267D01*
G02X731416Y530256I981J1002D01*
G03X731407Y530810I-293J272D01*
G02X733373Y532810I993J990D01*
G03X733927I277J288D01*
G02X735751Y530686I972J-1010D01*
G03X735744Y530374I121J-159D01*
G02X735799Y530325I-905J-1071D01*
G03X736366Y530347I273J293D01*
G02X737967Y530682I1034J-947D01*
G03X738511Y531166I162J366D01*
G02X739483Y529282I5781J1790D01*
G03X738774Y529119I-317J-243D01*
G02X736443Y528375I-1374J281D01*
G03X735876Y528353I-273J-293D01*
G02X735757Y528238I-1032J949D01*
G03X735767Y527927I131J-151D01*
G02X733988Y525762I-845J-1119D01*
G03X733456I-266J-298D01*
G02X733399Y525714I-931J1048D01*
G03Y525402I125J-156D01*
G37*
G36*
G01X652335Y529277D02*
G02X649999Y531165I-1185J923D01*
G03X649988Y531690I-307J256D01*
G02X652296Y533609I1112J1010D01*
G03X652948Y533630I319J242D01*
G02X655107Y533997I1252J-830D01*
G03X655748Y534313I241J319D01*
G02X658237Y535432I1502J-13D01*
G03X658763I263J302D01*
G02X660673Y533115I987J-1132D01*
G03Y532485I246J-315D01*
G02X658763Y530168I-923J-1185D01*
G03X658237I-263J-302D01*
G02X656278Y530155I-987J1132D01*
G03X655626Y529923I-259J-305D01*
G02X652965Y529277I-1476J277D01*
G03X652335I-315J-246D01*
G37*
G36*
G01X20111Y531329D02*
G02X17752Y532685I-1011J971D01*
G03X17319Y533192I-385J110D01*
G02X16007Y535670I-180J1491D01*
G03Y536196I-302J263D01*
G02X15650Y537378I1132J987D01*
G03X15469Y537604I-198J27D01*
G02X15357Y537618I130J1496D01*
G03X15126Y537393I-33J-197D01*
G02X14771Y536196I-1487J-210D01*
G03Y535670I302J-263D01*
G02X12507I-1132J-987D01*
G03Y536196I-302J263D01*
G02X13686Y538684I1132J987D01*
G03X14098Y539087I12J400D01*
G02X15294Y540571I1502J13D01*
G03X15610Y541012I-81J392D01*
G02X15615Y541428I1490J190D01*
G03X15342Y541870I-395J61D01*
G02Y544730I458J1430D01*
G03X15615Y545172I-122J381D01*
G02Y545628I1485J228D01*
G03X15342Y546070I-395J61D01*
G02X15432Y548956I458J1430D01*
G03X15577Y549198I-49J194D01*
G02X15558Y549830I1458J360D01*
G03X15295Y550281I-393J73D01*
G02X15504Y553175I492J1419D01*
G03X15662Y553408I-38J196D01*
G02X17422Y552208I1477J275D01*
G03X17264Y551975I38J-196D01*
G02Y551428I-1477J-273D01*
G03X17527Y550977I393J-73D01*
G02X17403Y548102I-492J-1419D01*
G03X17258Y547860I49J-194D01*
G02X17285Y547272I-1458J-362D01*
G03X17558Y546830I395J-61D01*
G02Y543970I-458J-1430D01*
G03X17285Y543528I122J-381D01*
G02Y543072I-1485J-228D01*
G03X17558Y542630I395J-61D01*
G02X17406Y539729I-458J-1430D01*
G03X17090Y539288I81J-392D01*
G02X17101Y539061I-1490J-186D01*
G03X17425Y538657I400J-11D01*
G02X18271Y536196I-286J-1474D01*
G03Y535670I302J-263D01*
G02X18568Y534219I-1132J-988D01*
G03X18982Y533697I380J-124D01*
G02X20111Y533271I118J-1397D01*
G03X20689I289J277D01*
G02Y531329I1011J-971D01*
G03X20111I-289J-277D01*
G37*
G36*
G01X726180Y532943D02*
G02X726154Y534496I-1180J757D01*
G03X726820Y534507I329J227D01*
G02X726846Y532954I1180J-757D01*
G03X726180Y532943I-329J-227D01*
G37*
G36*
G01X42873Y534083D02*
G02X41481Y535202I-1373J-283D01*
G03X41868Y535682I-5J400D01*
G02X42447Y537121I1373J283D01*
G03X42506Y537731I-226J330D01*
G02X44379Y539810I999J983D01*
G03X45022Y540049I250J312D01*
G02X45526Y538694I1378J-259D01*
G03X44883Y538455I-250J-312D01*
G02X44299Y537558I-1378J259D01*
G03X44240Y536948I226J-330D01*
G02X44402Y536751I-997J-985D01*
G03X45103Y536823I331J224D01*
G02X45239Y535504I1297J-533D01*
G03X44538Y535432I-331J-224D01*
G02X43260Y534563I-1297J533D01*
G03X42873Y534083I5J-400D01*
G37*
G36*
G01X1383531Y543094D02*
G02X1383233Y544892I-1200J725D01*
G03X1383833Y544991I258J306D01*
G02X1386145Y545120I1200J-724D01*
G03X1386783Y545124I317J244D01*
G02X1386795Y543433I1124J-838D01*
G03X1386157Y543429I-317J-244D01*
G02X1384131Y543193I-1124J838D01*
G03X1383531Y543094I-258J-306D01*
G37*
G36*
G01X1363515Y546822D02*
G02X1362082Y549388I-987J1132D01*
G03X1362319Y549952I-119J382D01*
G02X1364693Y551426I1249J637D01*
G03X1365334I320J239D01*
G02X1366668Y549203I1125J-837D01*
G03X1366370Y548628I60J-396D01*
G02X1364041Y546822I-1342J-674D01*
G03X1363515I-263J-302D01*
G37*
G36*
G01X721367Y550973D02*
G02X719423Y552917I-1167J777D01*
G03Y553583I-222J333D01*
G02X721367Y555527I777J1167D01*
G03X722033I333J222D01*
G02X724367I1167J-777D01*
G03X725033I333J222D01*
G02X726977Y553583I1167J-777D01*
G03Y552917I222J-333D01*
G02X725033Y550973I-777J-1167D01*
G03X724367I-333J-222D01*
G02X722033I-1167J777D01*
G03X721367I-333J-222D01*
G37*
G36*
G01X652006Y551483D02*
G02Y553517I-1106J1017D01*
G03X652594I294J270D01*
G02X655043Y553174I1106J-1017D01*
G03X655757I357J179D01*
G02X658324Y553370I1342J-674D01*
G03X658976I326J232D01*
G02Y551630I1224J-870D01*
G03X658324I-326J-232D01*
G02X655757Y551826I-1225J870D01*
G03X655043I-357J-179D01*
G02X652594Y551483I-1343J674D01*
G03X652006I-294J-270D01*
G37*
G36*
G01X697167Y552473D02*
G02Y554027I-1167J777D01*
G03X697833I333J222D01*
G02X698877Y554647I1167J-777D01*
G03X699210Y555201I-35J398D01*
G02X701667Y556527I1290J549D01*
G03X702333I333J222D01*
G02X704667I1167J-777D01*
G03X705333I333J222D01*
G02X707667I1167J-777D01*
G03X708333I333J222D01*
G02X709623Y554353I1167J-777D01*
G03X709290Y553799I35J-398D01*
G02X706833Y552473I-1290J-549D01*
G03X706167I-333J-222D01*
G02X703833I-1167J777D01*
G03X703167I-333J-222D01*
G02X700833I-1167J777D01*
G03X700167I-333J-222D01*
G02X697833I-1167J777D01*
G03X697167I-333J-222D01*
G37*
G36*
G01X1345866Y553247D02*
G02X1343603Y554849I-1253J630D01*
G03Y555403I-288J277D01*
G02Y557349I1010J973D01*
G03Y557903I-288J277D01*
G02Y559849I1010J973D01*
G03Y560403I-288J277D01*
G02X1343217Y561509I1010J973D01*
G03X1342865Y561944I-398J38D01*
G02X1342053Y562327I161J1393D01*
G03X1341499I-277J-288D01*
G02X1339553I-973J1010D01*
G03X1338999I-277J-288D01*
G02X1337053I-973J1010D01*
G03X1336499I-277J-288D01*
G02X1334553I-973J1010D01*
G03X1333999I-277J-288D01*
G02X1332194Y564465I-973J1010D01*
G03Y565109I-238J322D01*
G02X1333999Y567247I832J1128D01*
G03X1334553I277J288D01*
G02X1336462Y567280I972J-1010D01*
G03X1337012Y567294I268J298D01*
G02X1339050Y567229I988J-994D01*
G03X1339650I300J265D01*
G02X1341634Y567346I1050J-929D01*
G03X1342166I266J298D01*
G02X1343869Y565127I934J-1046D01*
G03X1343852Y564470I219J-334D01*
G02X1344422Y563204I-826J-1133D01*
G03X1344774Y562769I398J-38D01*
G02X1345623Y560403I-161J-1393D01*
G03Y559849I288J-277D01*
G02Y557903I-1010J-973D01*
G03Y557349I288J-277D01*
G02Y555403I-1010J-973D01*
G03Y554849I288J-277D01*
G02X1345762Y554679I-1013J-970D01*
G03X1346447Y554729I328J230D01*
G02X1346551Y553297I1253J-629D01*
G03X1345866Y553247I-328J-230D01*
G37*
G36*
G01X46588Y555920D02*
G02X45172I-708J-1210D01*
G03Y556610I-203J345D01*
G02X46588I708J1210D01*
G03Y555920I203J-345D01*
G37*
G36*
G01X1361720Y560797D02*
G02X1360474Y560236I-120J-1397D01*
G03X1360176Y560873I-321J238D01*
G02X1359896Y560916I87J1500D01*
G03X1359672Y560627I-48J-194D01*
G02X1357314Y559122I-1232J-669D01*
G03X1356673I-321J-239D01*
G02Y560796I-1125J837D01*
G03X1357314I320J239D01*
G02X1358456Y561361I1125J-837D01*
G03X1358839Y561890I4J400D01*
G02X1361440Y561443I1422J483D01*
G03X1361720Y560797I314J-247D01*
G37*
G36*
G01X1377086Y560726D02*
G02X1374974Y560635I-1016J-966D01*
G03X1374935Y561176I-313J249D01*
G02X1377398Y562710I1026J1097D01*
G03X1378051Y562532I383J117D01*
G02X1377603Y561386I949J-1032D01*
G03X1377234Y561476I-199J-16D01*
G02X1377078Y561269I-1273J797D01*
G03X1377086Y560726I298J-267D01*
G37*
G36*
G01X1361953Y567101D02*
G02X1360500Y565516I47J-1501D01*
G03X1360132Y565892I-399J-23D01*
G02X1360380Y568886I115J1498D01*
G03X1360598Y569087I18J199D01*
G02X1360601Y569189I1502J7D01*
G03X1360413Y569401I-200J12D01*
G02X1360333Y572393I87J1499D01*
G03X1360509Y572616I-22J199D01*
G02Y572984I1491J184D01*
G03X1360333Y573207I-198J24D01*
G02X1360187Y576169I167J1493D01*
G03X1360502Y576590I-84J391D01*
G02X1360514Y576918I1498J109D01*
G03X1360148Y577375I-396J58D01*
G02X1359129Y579860I113J1498D01*
G03Y580386I-302J263D01*
G02X1360286Y582875I1132J987D01*
G03X1360656Y583444I7J400D01*
G02X1360916Y585010I1270J594D01*
G03Y585564I-288J277D01*
G02X1360766Y585750I1012J970D01*
G03X1360413Y585708I-166J-112D01*
G02X1357733Y586510I-1313J492D01*
G03X1357355Y586999I-390J89D01*
G02X1356587Y589542I45J1401D01*
G03X1356659Y590127I-232J326D01*
G02X1358699Y592047I1067J910D01*
G03X1359253I277J288D01*
G02X1359315Y592102I961J-1021D01*
G03X1359311Y592409I-130J152D01*
G02X1359761Y594989I950J1164D01*
G03X1360021Y595437I-134J377D01*
G02X1360015Y595928I1479J264D01*
G03X1359742Y596370I-395J61D01*
G02X1359818Y599253I458J1430D01*
G03X1360112Y599694I-102J387D01*
G02Y600106I1488J206D01*
G03X1359818Y600547I-396J54D01*
G02X1359755Y603435I382J1453D01*
G03X1360029Y603897I-118J382D01*
G02X1360015Y604428I1471J304D01*
G03X1359742Y604870I-395J61D01*
G02X1360041Y607794I458J1430D01*
G03X1360398Y608193I-43J398D01*
G02Y608201I1502J4D01*
G03X1360019Y608600I-400J0D01*
G02X1359026Y611151I81J1500D01*
G03X1359060Y611671I-286J280D01*
G02X1361335Y611522I1201J902D01*
G03X1361301Y611002I286J-280D01*
G02X1361602Y610100I-1201J-902D01*
G01Y610099D01*
G03X1361981Y609700I400J0D01*
G02X1362049Y609695I-76J-1500D01*
G03X1362267Y609915I19J199D01*
G02X1362629Y611060I1494J157D01*
G03Y611586I-302J263D01*
G02X1364893I1132J987D01*
G03Y611060I302J-263D01*
G02X1363793Y608571I-1132J-987D01*
G03X1363402Y608177I9J-400D01*
G02X1362059Y606706I-1502J23D01*
G03X1361702Y606307I43J-398D01*
G02X1361685Y606072I-1502J-9D01*
G03X1361958Y605630I395J-61D01*
G02X1361945Y602765I-458J-1430D01*
G03X1361671Y602303I118J-382D01*
G02X1361688Y601794I-1471J-304D01*
G03X1361982Y601353I396J-54D01*
G02Y598447I-382J-1453D01*
G03X1361688Y598006I102J-387D01*
G02X1361685Y597572I-1488J-207D01*
G03X1361958Y597130I395J-61D01*
G02X1362000Y594284I-458J-1430D01*
G03X1361740Y593836I134J-377D01*
G02X1361311Y592499I-1479J-263D01*
G03X1361288Y591952I280J-286D01*
G02X1361130Y589966I-1062J-915D01*
G03X1361102Y589380I258J-306D01*
G02X1361501Y588352I-1002J-980D01*
G03X1361906Y587939I400J-13D01*
G02X1362858Y587584I19J-1402D01*
G03X1363413Y587606I266J299D01*
G02X1365436Y585664I1013J-969D01*
G03Y585110I288J-277D01*
G02X1365077Y582895I-1010J-973D01*
G03X1364947Y582295I185J-354D01*
G02X1362424Y582058I-1186J-922D01*
G03X1362037Y582639I-356J182D01*
G02X1361950Y582635I-108J1398D01*
G03X1361600Y582054I6J-400D01*
G02X1361393Y580386I-1339J-681D01*
G03Y579860I302J-263D01*
G02X1361747Y578655I-1132J-987D01*
G03X1362113Y578198I396J-58D01*
G02X1362313Y575231I-113J-1498D01*
G03X1361998Y574810I84J-391D01*
G02X1361991Y574516I-1498J-111D01*
G03X1362167Y574293I198J-24D01*
G02Y571307I-167J-1493D01*
G03X1361991Y571084I22J-199D01*
G02X1361999Y570811I-1491J-180D01*
G03X1362187Y570599I200J-12D01*
G02X1361967Y567604I-87J-1499D01*
G03X1361749Y567403I-18J-199D01*
G02X1361747Y567312I-1502J-13D01*
G03X1361953Y567101I200J-11D01*
G37*
G36*
G01X1375668Y585155D02*
G02X1375520Y583756I1132J-827D01*
G03X1374832Y583829I-365J-163D01*
G02X1372689Y583685I-1132J827D01*
G03X1372111I-289J-277D01*
G02Y585627I-1011J971D01*
G03X1372689I289J277D01*
G02X1374980Y585228I1011J-971D01*
G03X1375668Y585155I365J163D01*
G37*
G36*
G01X1399147Y586309D02*
G02X1396604Y587353I-1167J777D01*
G03X1396076Y587805I-393J75D01*
G02X1392058Y590669I-1016J2825D01*
G02X1393362Y593106I443J1331D01*
G02X1397950Y591441I1698J-2476D01*
G02X1399282Y590629I60J-1401D01*
G03X1399942Y590528I363J168D01*
G02X1401990Y588613I1038J-942D01*
G03Y588059I288J-277D01*
G02X1399813Y586309I-1010J-972D01*
G03X1399147I-333J-222D01*
G37*
G36*
G01X1385819Y603959D02*
G02X1383979Y603801I-819J-1259D01*
G03X1383925Y604430I-272J293D01*
G02X1383485Y604870I819J1259D01*
G03X1382950Y604999I-336J-218D01*
G02X1381627Y607689I-750J1302D01*
G03X1381709Y608383I-152J370D01*
G02X1381461Y610598I877J1220D01*
G03X1381465Y611123I-299J265D01*
G02X1383730Y611106I1140J979D01*
G03X1383726Y610581I299J-265D01*
G02X1383159Y608213I-1140J-979D01*
G03X1383077Y607519I152J-370D01*
G02X1383459Y607119I-877J-1220D01*
G03X1383994Y606990I336J218D01*
G02X1385765Y604588I749J-1302D01*
G03X1385819Y603959I272J-293D01*
G37*
G36*
G01X22936Y442957D02*
G03X22283Y443267I-400J0D01*
G02X22532Y445178I-886J1087D01*
G03X23188Y445191I323J235D01*
G02X25958Y444364I1259J-837D01*
G01X25959Y439354D01*
X25958D01*
Y439269D01*
X25949Y439185D01*
G02X23188Y438517I-1502J169D01*
G03X22532Y438530I-333J-222D01*
G02X22283Y440441I-1135J824D01*
G03X22936Y440751I253J310D01*
G01Y442957D01*
G37*
G36*
G01X606831Y91885D02*
G02Y93313I-1321J714D01*
G03X607535I352J191D01*
G02X610178I1321J-714D01*
G03X610881I352J190D01*
G02X613524I1321J-714D01*
G03X614228I352J191D01*
G02Y91885I1321J-714D01*
G03X613524I-352J-191D01*
G02X610881I-1321J714D01*
G03X610178I-352J-190D01*
G02X607535I-1321J714D01*
G03X606831I-352J-191D01*
G37*
G36*
G01Y64985D02*
G02Y66413I-1321J714D01*
G03X607535I352J191D01*
G02X610178I1321J-714D01*
G03X610881I352J190D01*
G02X613524I1321J-714D01*
G03X614228I352J191D01*
G02Y64985I1321J-714D01*
G03X613524I-352J-191D01*
G02X610881I-1321J714D01*
G03X610178I-352J-190D01*
G02X607535I-1321J714D01*
G03X606831I-352J-191D01*
G37*
G36*
G01X653040Y30143D02*
G03X652485Y30144I-278J-287D01*
G02X650411Y30133I-1043J1081D01*
G03X649870Y30140I-274J-291D01*
G02X649898Y32350I-1003J1118D01*
G03X650439Y32343I274J291D01*
G02X652546Y32244I1003J-1118D01*
G03X653101Y32212I294J271D01*
G02X653040Y30143I915J-1062D01*
G37*
G36*
G01X652310Y19027D02*
G03Y18473I288J-277D01*
G02X650290I-1010J-973D01*
G03Y19027I-288J277D01*
G02X652310I1010J973D01*
G37*
G36*
G01X624830Y-2141D02*
G03X624458Y-2637I16J-399D01*
G02X622940Y-1499I-1458J-363D01*
G03X623312Y-1003I-16J399D01*
G02X624830Y-2141I1458J363D01*
G37*
G36*
G01X648096Y-10527D02*
G03Y-11073I292J-273D01*
G02X645904I-1096J-1027D01*
G03Y-10527I-292J273D01*
G02X646086Y-8308I1096J1027D01*
G03X646170Y-7762I-244J317D01*
G02X648314Y-8092I1230J862D01*
G03X648230Y-8638I244J-317D01*
G02X648096Y-10527I-1230J-862D01*
G37*
G36*
G01X606831Y16285D02*
G02Y17713I-1321J714D01*
G03X607535I352J191D01*
G02X610178I1321J-714D01*
G03X610881I352J190D01*
G02X613524I1321J-714D01*
G03X614228I352J191D01*
G02Y16285I1321J-714D01*
G03X613524I-352J-191D01*
G02X610881I-1321J714D01*
G03X610178I-352J-190D01*
G02X607535I-1321J714D01*
G03X606831I-352J-191D01*
G37*
G36*
G01X649601Y7476D02*
G02X647633Y9740I-1051J1074D01*
G03X647622Y10381I-244J316D01*
G02X649485Y12734I879J1218D01*
G03X650031Y12755I262J302D01*
G02X651998Y10496I1069J-1055D01*
G03Y9854I239J-321D01*
G02X650137Y7498I-898J-1204D01*
G03X649601Y7476I-256J-307D01*
G37*
G36*
G01X606831Y-10615D02*
G02Y-9187I-1321J714D01*
G03X607535I352J191D01*
G02X610178I1321J-714D01*
G03X610881I352J190D01*
G02X613524I1321J-714D01*
G03X614228I352J191D01*
G02Y-10615I1321J-714D01*
G03X613524I-352J-191D01*
G02X610881I-1321J714D01*
G03X610178I-352J-190D01*
G02X607535I-1321J714D01*
G03X606831I-352J-191D01*
G37*
G36*
G01X596456Y89417D02*
G03X596470Y88834I281J-285D01*
G02X594470I-1000J-1120D01*
G03X594484Y89417I-267J298D01*
G02X596456I986J997D01*
G37*
G36*
G01X589763D02*
G03X589777Y88834I281J-285D01*
G02X587777I-1000J-1120D01*
G03X587791Y89417I-267J298D01*
G02X589763I986J997D01*
G37*
G36*
G01X572331D02*
G03X572345Y88834I281J-285D01*
G02X570345I-1000J-1120D01*
G03X570359Y89417I-267J298D01*
G02X572331I986J997D01*
G37*
G36*
G01X559645D02*
G03X559659Y88834I281J-285D01*
G02X557659I-1000J-1120D01*
G03X557673Y89417I-267J298D01*
G02X559645I986J997D01*
G37*
G36*
G01X552952D02*
G03X552966Y88834I281J-285D01*
G02X550966I-1000J-1120D01*
G03X550980Y89417I-267J298D01*
G02X552952I986J997D01*
G37*
G36*
G01X581206Y86343D02*
G03X581187Y85736I251J-312D01*
G02X579315Y85751I-944J-1036D01*
G03X579306Y86359I-265J300D01*
G02X579170Y88541I960J1155D01*
G03Y89087I-292J273D01*
G02X579225Y91197I1096J1027D01*
G03X579241Y91758I-277J289D01*
G02X581291I1025J956D01*
G03X581307Y91197I293J-272D01*
G02X581362Y89087I-1041J-1083D01*
G03Y88541I292J-273D01*
G02X581206Y86343I-1096J-1027D01*
G37*
G36*
G01X544395D02*
G03X544376Y85736I251J-312D01*
G02X542504Y85751I-944J-1036D01*
G03X542495Y86359I-265J300D01*
G02X542359Y88541I960J1155D01*
G03Y89087I-292J273D01*
G02X542414Y91197I1096J1027D01*
G03X542430Y91758I-277J289D01*
G02X544480I1025J956D01*
G03X544496Y91197I293J-272D01*
G02X544551Y89087I-1041J-1083D01*
G03Y88541I292J-273D01*
G02X544395Y86343I-1096J-1027D01*
G37*
G36*
G01X576206Y86216D02*
G03X576191Y85655I277J-288D01*
G02X574141I-1025J-957D01*
G03X574126Y86216I-292J273D01*
G02X574070Y88327I1040J1084D01*
G03Y88873I-292J273D01*
G02X574115Y90973I1096J1027D01*
G03X574125Y91535I-280J286D01*
G02X576176Y91553I1017J965D01*
G03X576197Y90992I295J-270D01*
G02X576262Y88873I-1031J-1092D01*
G03Y88327I292J-273D01*
G02X576206Y86216I-1096J-1027D01*
G37*
G36*
G01X576233Y67467D02*
G03X576217Y66906I277J-289D01*
G02X574167I-1025J-956D01*
G03X574151Y67467I-293J272D01*
G02X574104Y69585I1041J1083D01*
G03X574098Y70142I-290J275D01*
G02X574125Y72282I1068J1057D01*
G03X574141Y72843I-277J289D01*
G02X576191I1025J956D01*
G03X576207Y72282I293J-272D01*
G02X576254Y70164I-1041J-1083D01*
G03X576260Y69607I290J-275D01*
G02X576233Y67467I-1068J-1057D01*
G37*
G36*
G01X581311Y67261D02*
G03X581298Y66699I278J-288D01*
G02X579250Y66689I-1019J-963D01*
G03X579232Y67250I-293J271D01*
G02X579173Y69370I1034J1090D01*
G03Y69919I-291J274D01*
G02X579236Y72043I1093J1031D01*
G03X579257Y72604I-274J291D01*
G02X581307Y72583I1035J946D01*
G03X581317Y72022I290J-275D01*
G02X581359Y69919I-1051J-1073D01*
G03Y69370I291J-274D01*
G02X581311Y67261I-1093J-1030D01*
G37*
G36*
G01X544500D02*
G03X544487Y66699I278J-288D01*
G02X542439Y66689I-1019J-963D01*
G03X542421Y67250I-293J271D01*
G02X542362Y69370I1034J1090D01*
G03Y69919I-291J274D01*
G02X542425Y72043I1093J1031D01*
G03X542446Y72604I-274J291D01*
G02X544496Y72583I1035J946D01*
G03X544506Y72022I290J-275D01*
G02X544548Y69919I-1051J-1073D01*
G03Y69370I291J-274D01*
G02X544500Y67261I-1093J-1030D01*
G37*
G36*
G01X596456Y51617D02*
G03X596470Y51034I281J-285D01*
G02X594470I-1000J-1120D01*
G03X594484Y51617I-267J298D01*
G02X596456I986J997D01*
G37*
G36*
G01X589763D02*
G03X589777Y51034I281J-285D01*
G02X587777I-1000J-1120D01*
G03X587791Y51617I-267J298D01*
G02X589763I986J997D01*
G37*
G36*
G01X572331D02*
G03X572345Y51034I281J-285D01*
G02X570345I-1000J-1120D01*
G03X570359Y51617I-267J298D01*
G02X572331I986J997D01*
G37*
G36*
G01X559645D02*
G03X559659Y51034I281J-285D01*
G02X557659I-1000J-1120D01*
G03X557673Y51617I-267J298D01*
G02X559645I986J997D01*
G37*
G36*
G01X552952D02*
G03X552966Y51034I281J-285D01*
G02X550966I-1000J-1120D01*
G03X550980Y51617I-267J298D01*
G02X552952I986J997D01*
G37*
G36*
G01X581362Y51287D02*
G03Y50741I292J-273D01*
G02X579170I-1096J-1027D01*
G03Y51287I-292J273D01*
G02X579225Y53397I1096J1027D01*
G03X579241Y53958I-277J289D01*
G02X581291I1025J956D01*
G03X581307Y53397I293J-272D01*
G02X581362Y51287I-1041J-1083D01*
G37*
G36*
G01X544428Y48570D02*
G03X544402Y47984I259J-305D01*
G02X542443Y48021I-998J-984D01*
G03X542440Y48607I-274J292D01*
G02X542359Y50741I1015J1107D01*
G03Y51287I-292J273D01*
G02X542414Y53397I1096J1027D01*
G03X542430Y53958I-277J289D01*
G02X544480I1025J956D01*
G03X544496Y53397I293J-272D01*
G02X544551Y51287I-1041J-1083D01*
G03Y50741I292J-273D01*
G02X544428Y48570I-1096J-1027D01*
G37*
G36*
G01X576206Y48416D02*
G03X576191Y47855I277J-288D01*
G02X574141I-1025J-957D01*
G03X574126Y48416I-292J273D01*
G02X574070Y50527I1040J1084D01*
G03Y51073I-292J273D01*
G02X576262I1096J1027D01*
G03Y50527I292J-273D01*
G02X576206Y48416I-1096J-1027D01*
G37*
G36*
G01X603485Y84043D02*
G02Y85471I-1322J714D01*
G03X604188I351J190D01*
G02X606831I1322J-714D01*
G03X607535I352J191D01*
G02X610178I1321J-714D01*
G03X610881I352J190D01*
G02X613524I1321J-714D01*
G03X614228I352J191D01*
G02Y84043I1321J-714D01*
G03X613524I-352J-191D01*
G02X610881I-1321J714D01*
G03X610178I-352J-190D01*
G02X607535I-1321J714D01*
G03X606831I-352J-191D01*
G02X604188I-1321J714D01*
G03X603485I-352J-190D01*
G37*
G36*
G01Y73143D02*
G02Y74571I-1322J714D01*
G03X604188I351J190D01*
G02X606831I1322J-714D01*
G03X607535I352J191D01*
G02X610178I1321J-714D01*
G03X610881I352J190D01*
G02X613524I1321J-714D01*
G03X614228I352J191D01*
G02Y73143I1321J-714D01*
G03X613524I-352J-191D01*
G02X610881I-1321J714D01*
G03X610178I-352J-190D01*
G02X607535I-1321J714D01*
G03X606831I-352J-191D01*
G02X604188I-1321J714D01*
G03X603485I-352J-190D01*
G37*
G36*
G01Y54085D02*
G02X600829Y54108I-1322J714D01*
G03X600126Y54120I-355J-184D01*
G02X600151Y55548I-1309J737D01*
G03X600854Y55536I355J184D01*
G02X603485Y55513I1309J-737D01*
G03X604188I351J190D01*
G02X606831I1322J-714D01*
G03X607535I352J191D01*
G02X610178I1321J-714D01*
G03X610881I352J190D01*
G02X613524I1321J-714D01*
G03X614228I352J191D01*
G02Y54085I1321J-714D01*
G03X613524I-352J-191D01*
G02X610881I-1321J714D01*
G03X610178I-352J-190D01*
G02X607535I-1321J714D01*
G03X606831I-352J-191D01*
G02X604188I-1321J714D01*
G03X603485I-352J-190D01*
G37*
G36*
G01X566047Y51039D02*
G02X564304Y51217I-995J-1125D01*
G03X564382Y51852I-199J347D01*
G02X566099Y51677I971J1012D01*
G03X566047Y51039I213J-338D01*
G37*
G36*
G01X603485Y46243D02*
G02Y47671I-1322J714D01*
G03X604188I351J190D01*
G02X606831I1322J-714D01*
G03X607535I352J191D01*
G02X610178I1321J-714D01*
G03X610881I352J190D01*
G02X613524I1321J-714D01*
G03X614228I352J191D01*
G02Y46243I1321J-714D01*
G03X613524I-352J-191D01*
G02X610881I-1321J714D01*
G03X610178I-352J-190D01*
G02X607535I-1321J714D01*
G03X606831I-352J-191D01*
G02X604188I-1321J714D01*
G03X603485I-352J-190D01*
G37*
G36*
G01Y35343D02*
G02Y36771I-1322J714D01*
G03X604188I351J190D01*
G02X606831I1322J-714D01*
G03X607535I352J191D01*
G02X610178I1321J-714D01*
G03X610881I352J190D01*
G02X613524I1321J-714D01*
G03X614228I352J191D01*
G02Y35343I1321J-714D01*
G03X613524I-352J-191D01*
G02X610881I-1321J714D01*
G03X610178I-352J-190D01*
G02X607535I-1321J714D01*
G03X606831I-352J-191D01*
G02X604188I-1321J714D01*
G03X603485I-352J-190D01*
G37*
G36*
G01X576213Y29648D02*
G03X576198Y29077I272J-293D01*
G02X574186I-1006J-977D01*
G03X574171Y29648I-287J278D01*
G02X574104Y31785I1021J1102D01*
G03X574098Y32342I-290J275D01*
G02X574125Y34482I1068J1057D01*
G03X574141Y35043I-277J289D01*
G02X576191I1025J956D01*
G03X576207Y34482I293J-272D01*
G02X576254Y32364I-1041J-1083D01*
G03X576260Y31807I290J-275D01*
G02X576213Y29648I-1068J-1057D01*
G37*
G36*
G01X581311Y29461D02*
G03X581298Y28899I278J-288D01*
G02X579250Y28889I-1019J-963D01*
G03X579232Y29450I-293J271D01*
G02X579173Y31570I1034J1090D01*
G03Y32119I-291J274D01*
G02X579196Y34203I1093J1030D01*
G03X579195Y34764I-286J280D01*
G02X581243Y34823I996J986D01*
G03X581275Y34262I300J-264D01*
G02X581359Y32119I-1009J-1113D01*
G03Y31570I291J-275D01*
G02X581311Y29461I-1093J-1030D01*
G37*
G36*
G01X544500D02*
G03X544487Y28899I278J-288D01*
G02X542439Y28889I-1019J-963D01*
G03X542421Y29450I-293J271D01*
G02X542362Y31570I1034J1090D01*
G03Y32119I-291J274D01*
G02X542418Y34236I1093J1030D01*
G03X542424Y34808I-276J289D01*
G02X544435Y34838I991J992D01*
G03X544459Y34266I291J-274D01*
G02X544548Y32119I-1004J-1117D01*
G03Y31570I291J-275D01*
G02X544500Y29461I-1093J-1030D01*
G37*
G36*
G01X596456Y13817D02*
G03X596470Y13234I281J-285D01*
G02X594470I-1000J-1120D01*
G03X594484Y13817I-267J298D01*
G02X596456I986J997D01*
G37*
G36*
G01X589763D02*
G03X589777Y13234I281J-285D01*
G02X587777I-1000J-1120D01*
G03X587791Y13817I-267J298D01*
G02X589763I986J997D01*
G37*
G36*
G01X572331D02*
G03X572345Y13234I281J-285D01*
G02X570345I-1000J-1120D01*
G03X570359Y13817I-267J298D01*
G02X572331I986J997D01*
G37*
G36*
G01X566039Y13782D02*
G03X566067Y13221I299J-266D01*
G02X563987Y13173I-1015J-1107D01*
G03X563989Y13734I-284J282D01*
G02X566039Y13782I1003J980D01*
G37*
G36*
G01X559645Y13817D02*
G03X559659Y13234I281J-285D01*
G02X557659I-1000J-1120D01*
G03X557673Y13817I-267J298D01*
G02X559645I986J997D01*
G37*
G36*
G01X552952D02*
G03X552966Y13234I281J-285D01*
G02X550966I-1000J-1120D01*
G03X550980Y13817I-267J298D01*
G02X552952I986J997D01*
G37*
G36*
G01X581270Y10797D02*
G03X581239Y10233I267J-298D01*
G02X579200Y10291I-1047J-933D01*
G03X579201Y10855I-283J283D01*
G02X579170Y12941I1065J1059D01*
G03Y13487I-292J273D01*
G02X579225Y15597I1096J1027D01*
G03X579241Y16158I-277J289D01*
G02X581291I1025J956D01*
G03X581307Y15597I293J-272D01*
G02X581362Y13487I-1041J-1083D01*
G03Y12941I292J-273D01*
G02X581270Y10797I-1096J-1027D01*
G37*
G36*
G01X544474Y10810D02*
G03X544450Y10246I271J-294D01*
G02X542410Y10277I-1035J-946D01*
G03X542403Y10842I-287J279D01*
G02X542359Y12941I1052J1072D01*
G03Y13487I-292J273D01*
G02X542414Y15597I1096J1027D01*
G03X542430Y16158I-277J289D01*
G02X544480I1025J956D01*
G03X544496Y15597I293J-272D01*
G02X544551Y13487I-1041J-1083D01*
G03Y12941I292J-273D01*
G02X544474Y10810I-1096J-1027D01*
G37*
G36*
G01X576206Y10616D02*
G03X576191Y10055I277J-288D01*
G02X574141I-1025J-957D01*
G03X574126Y10616I-292J273D01*
G02X574070Y12727I1040J1084D01*
G03Y13273I-292J273D01*
G02X574132Y15389I1096J1027D01*
G03X574151Y15950I-275J290D01*
G02X576202Y15938I1031J950D01*
G03X576213Y15376I290J-275D01*
G02X576262Y13273I-1047J-1076D01*
G03Y12727I292J-273D01*
G02X576206Y10616I-1096J-1027D01*
G37*
G36*
G01X576222Y-8143D02*
G03X576212Y-8715I274J-291D01*
G02X574200Y-8732I-998J-985D01*
G03X574180Y-8160I-289J276D01*
G02X574104Y-6015I1012J1110D01*
G03X574098Y-5458I-290J275D01*
G02X574125Y-3318I1068J1057D01*
G03X574141Y-2757I-277J289D01*
G02X576191I1025J956D01*
G03X576207Y-3318I293J-272D01*
G02X576254Y-5436I-1041J-1083D01*
G03X576260Y-5993I290J-275D01*
G02X576222Y-8143I-1068J-1056D01*
G37*
G36*
G01X581311Y-8339D02*
G03X581298Y-8901I278J-288D01*
G02X579250Y-8911I-1019J-963D01*
G03X579232Y-8350I-293J271D01*
G02X579173Y-6230I1034J1090D01*
G03Y-5681I-291J274D01*
G02X579266Y-3531I1093J1030D01*
G03X579291Y-2959I-267J298D01*
G02X581302Y-2995I1023J959D01*
G03X581306Y-3568I281J-285D01*
G02X581359Y-5681I-1040J-1083D01*
G03Y-6230I291J-274D01*
G02X581311Y-8339I-1093J-1030D01*
G37*
G36*
G01X544500D02*
G03X544487Y-8901I278J-288D01*
G02X542439Y-8911I-1019J-963D01*
G03X542421Y-8350I-293J271D01*
G02X542362Y-6230I1034J1090D01*
G03Y-5681I-291J274D01*
G02X542455Y-3531I1093J1030D01*
G03X542480Y-2959I-267J298D01*
G02X544491Y-2995I1023J959D01*
G03X544495Y-3568I281J-285D01*
G02X544548Y-5681I-1040J-1083D01*
G03Y-6230I291J-274D01*
G02X544500Y-8339I-1093J-1030D01*
G37*
G36*
G01X603485Y27185D02*
G02Y28613I-1322J714D01*
G03X604188I351J190D01*
G02X606831I1322J-714D01*
G03X607535I352J191D01*
G02X610178I1321J-714D01*
G03X610881I352J190D01*
G02X613524I1321J-714D01*
G03X614228I352J191D01*
G02Y27185I1321J-714D01*
G03X613524I-352J-191D01*
G02X610881I-1321J714D01*
G03X610178I-352J-190D01*
G02X607535I-1321J714D01*
G03X606831I-352J-191D01*
G02X604188I-1321J714D01*
G03X603485I-352J-190D01*
G37*
G36*
G01Y8443D02*
G02Y9871I-1322J714D01*
G03X604188I351J190D01*
G02X606831I1322J-714D01*
G03X607535I352J191D01*
G02X610178I1321J-714D01*
G03X610881I352J190D01*
G02X613524I1321J-714D01*
G03X614228I352J191D01*
G02Y8443I1321J-714D01*
G03X613524I-352J-191D01*
G02X610881I-1321J714D01*
G03X610178I-352J-190D01*
G02X607535I-1321J714D01*
G03X606831I-352J-191D01*
G02X604188I-1321J714D01*
G03X603485I-352J-190D01*
G37*
G36*
G01Y-2457D02*
G02Y-1029I-1322J714D01*
G03X604188I351J190D01*
G02X606831I1322J-714D01*
G03X607535I352J191D01*
G02X610178I1321J-714D01*
G03X610881I352J190D01*
G02X613524I1321J-714D01*
G03X614228I352J191D01*
G02Y-2457I1321J-714D01*
G03X613524I-352J-191D01*
G02X610881I-1321J714D01*
G03X610178I-352J-190D01*
G02X607535I-1321J714D01*
G03X606831I-352J-191D01*
G02X604188I-1321J714D01*
G03X603485I-352J-190D01*
G37*
G36*
G01X535520Y89417D02*
G03X535534Y88834I281J-285D01*
G02X533534I-1000J-1120D01*
G03X533548Y89417I-267J298D01*
G02X535520I986J997D01*
G37*
G36*
G01X529234Y89378D02*
G03X529261Y88817I298J-267D01*
G02X527180Y88777I-1020J-1103D01*
G03X527184Y89338I-283J283D01*
G02X529234Y89378I1006J976D01*
G37*
G36*
G01X522834Y89417D02*
G03X522848Y88834I281J-285D01*
G02X520848I-1000J-1120D01*
G03X520862Y89417I-267J298D01*
G02X522834I986J997D01*
G37*
G36*
G01X516141D02*
G03X516155Y88834I281J-285D01*
G02X514155I-1000J-1120D01*
G03X514169Y89417I-267J298D01*
G02X516141I986J997D01*
G37*
G36*
G01X498709D02*
G03X498723Y88834I281J-285D01*
G02X496723I-1000J-1120D01*
G03X496737Y89417I-267J298D01*
G02X498709I986J997D01*
G37*
G36*
G01X492423Y89378D02*
G03X492450Y88817I298J-267D01*
G02X490369Y88777I-1020J-1103D01*
G03X490373Y89338I-283J283D01*
G02X492423Y89378I1006J976D01*
G37*
G36*
G01X486023Y89417D02*
G03X486037Y88834I281J-285D01*
G02X484037I-1000J-1120D01*
G03X484051Y89417I-267J298D01*
G02X486023I986J997D01*
G37*
G36*
G01X507584Y86343D02*
G03X507565Y85736I251J-312D01*
G02X505693Y85751I-944J-1036D01*
G03X505684Y86359I-265J300D01*
G02X505548Y88541I960J1155D01*
G03Y89087I-292J273D01*
G02X505603Y91197I1096J1027D01*
G03X505619Y91758I-277J289D01*
G02X507669I1025J956D01*
G03X507685Y91197I293J-272D01*
G02X507740Y89087I-1041J-1083D01*
G03Y88541I292J-273D01*
G02X507584Y86343I-1096J-1027D01*
G37*
G36*
G01X539395Y86216D02*
G03X539380Y85655I277J-288D01*
G02X537330I-1025J-957D01*
G03X537315Y86216I-292J273D01*
G02X537259Y88327I1040J1084D01*
G03Y88873I-292J273D01*
G02X537304Y90973I1096J1027D01*
G03X537314Y91535I-280J286D01*
G02X539365Y91553I1017J965D01*
G03X539386Y90992I295J-270D01*
G02X539451Y88873I-1031J-1092D01*
G03Y88327I292J-273D01*
G02X539395Y86216I-1096J-1027D01*
G37*
G36*
G01X502584D02*
G03X502569Y85655I277J-288D01*
G02X500519I-1025J-957D01*
G03X500504Y86216I-292J273D01*
G02X500448Y88327I1040J1084D01*
G03Y88873I-292J273D01*
G02X500493Y90973I1096J1027D01*
G03X500503Y91535I-280J286D01*
G02X502554Y91553I1017J965D01*
G03X502575Y90992I295J-270D01*
G02X502640Y88873I-1031J-1092D01*
G03Y88327I292J-273D01*
G02X502584Y86216I-1096J-1027D01*
G37*
G36*
G01X539422Y67467D02*
G03X539406Y66906I277J-289D01*
G02X537356I-1025J-956D01*
G03X537340Y67467I-293J272D01*
G02X537293Y69585I1041J1083D01*
G03X537287Y70142I-290J275D01*
G02X537314Y72282I1068J1057D01*
G03X537330Y72843I-277J289D01*
G02X539380I1025J956D01*
G03X539396Y72282I293J-272D01*
G02X539443Y70164I-1041J-1083D01*
G03X539449Y69607I290J-275D01*
G02X539422Y67467I-1068J-1057D01*
G37*
G36*
G01X502611D02*
G03X502595Y66906I277J-289D01*
G02X500545I-1025J-956D01*
G03X500529Y67467I-293J272D01*
G02X500482Y69585I1041J1083D01*
G03X500476Y70142I-290J275D01*
G02X500503Y72282I1068J1057D01*
G03X500519Y72843I-277J289D01*
G02X502569I1025J956D01*
G03X502585Y72282I293J-272D01*
G02X502632Y70164I-1041J-1083D01*
G03X502638Y69607I290J-275D01*
G02X502611Y67467I-1068J-1057D01*
G37*
G36*
G01X507689Y67261D02*
G03X507676Y66699I278J-288D01*
G02X505628Y66689I-1019J-963D01*
G03X505610Y67250I-293J271D01*
G02X505551Y69370I1034J1090D01*
G03Y69919I-291J274D01*
G02X505614Y72043I1093J1031D01*
G03X505635Y72604I-274J291D01*
G02X507685Y72583I1035J946D01*
G03X507695Y72022I290J-275D01*
G02X507737Y69919I-1051J-1073D01*
G03Y69370I291J-274D01*
G02X507689Y67261I-1093J-1030D01*
G37*
G36*
G01X535520Y51617D02*
G03X535534Y51034I281J-285D01*
G02X533534I-1000J-1120D01*
G03X533548Y51617I-267J298D01*
G02X535520I986J997D01*
G37*
G36*
G01X522834D02*
G03X522848Y51034I281J-285D01*
G02X520848I-1000J-1120D01*
G03X520862Y51617I-267J298D01*
G02X522834I986J997D01*
G37*
G36*
G01X516141D02*
G03X516155Y51034I281J-285D01*
G02X514155I-1000J-1120D01*
G03X514169Y51617I-267J298D01*
G02X516141I986J997D01*
G37*
G36*
G01X498709D02*
G03X498723Y51034I281J-285D01*
G02X496723I-1000J-1120D01*
G03X496737Y51617I-267J298D01*
G02X498709I986J997D01*
G37*
G36*
G01X486023D02*
G03X486037Y51034I281J-285D01*
G02X484037I-1000J-1120D01*
G03X484051Y51617I-267J298D01*
G02X486023I986J997D01*
G37*
G36*
G01X507616Y48570D02*
G03X507590Y47984I259J-305D01*
G02X505631Y48021I-998J-984D01*
G03X505628Y48607I-274J292D01*
G02X505547Y50741I1015J1107D01*
G03Y51287I-292J273D01*
G02X505603Y53397I1096J1027D01*
G03X505618Y53958I-277J288D01*
G02X507669I1025J956D01*
G03X507684Y53396I292J-273D01*
G02X507739Y51287I-1041J-1082D01*
G03Y50741I292J-273D01*
G02X507616Y48570I-1096J-1027D01*
G37*
G36*
G01X539395Y48416D02*
G03X539380Y47855I277J-288D01*
G02X537330I-1025J-957D01*
G03X537315Y48416I-292J273D01*
G02X537259Y50527I1040J1084D01*
G03Y51073I-292J273D01*
G02X537293Y53162I1096J1027D01*
G03X537298Y53724I-282J284D01*
G02X539348Y53764I1006J976D01*
G03X539374Y53203I298J-267D01*
G02X539451Y51073I-1019J-1103D01*
G03Y50527I292J-273D01*
G02X539395Y48416I-1096J-1027D01*
G37*
G36*
G01X502584Y48417D02*
G03X502568Y47855I277J-289D01*
G02X500519Y47854I-1024J-957D01*
G03X500503Y48416I-292J273D01*
G02X500447Y50527I1040J1084D01*
G03Y51073I-292J273D01*
G02X500481Y53162I1096J1027D01*
G03X500486Y53724I-282J284D01*
G02X502536Y53764I1006J976D01*
G03X502562Y53203I298J-267D01*
G02X502639Y51073I-1019J-1103D01*
G03Y50527I292J-273D01*
G02X502584Y48417I-1096J-1027D01*
G37*
G36*
G01X539416Y29662D02*
G03X539408Y29089I275J-290D01*
G02X537397Y29064I-993J-989D01*
G03X537374Y29635I-291J274D01*
G02X537293Y31785I1007J1114D01*
G03X537287Y32342I-290J275D01*
G02X537314Y34482I1068J1057D01*
G03X537330Y35043I-277J289D01*
G02X539380I1025J956D01*
G03X539396Y34482I293J-272D01*
G02X539443Y32364I-1041J-1083D01*
G03X539449Y31807I290J-275D01*
G02X539416Y29662I-1068J-1056D01*
G37*
G36*
G01X502604D02*
G03X502596Y29089I275J-290D01*
G02X500585Y29064I-993J-989D01*
G03X500562Y29635I-291J274D01*
G02X500481Y31785I1007J1114D01*
G03X500475Y32342I-290J275D01*
G02X500503Y34482I1068J1056D01*
G03X500518Y35043I-277J288D01*
G02X502569I1025J956D01*
G03X502584Y34481I292J-273D01*
G02X502631Y32364I-1041J-1082D01*
G03X502637Y31807I290J-275D01*
G02X502604Y29662I-1068J-1056D01*
G37*
G36*
G01X507688Y29461D02*
G03X507676Y28899I278J-287D01*
G02X505628Y28888I-1019J-963D01*
G03X505610Y29450I-294J272D01*
G02X505550Y31570I1033J1090D01*
G03Y32119I-291J274D01*
G02X505606Y34236I1093J1030D01*
G03X505612Y34808I-276J289D01*
G02X507623Y34838I991J992D01*
G03X507647Y34266I291J-274D01*
G02X507736Y32119I-1004J-1117D01*
G03Y31570I291J-275D01*
G02X507688Y29461I-1093J-1030D01*
G37*
G36*
G01X535520Y13817D02*
G03X535534Y13234I281J-285D01*
G02X533534I-1000J-1120D01*
G03X533548Y13817I-267J298D01*
G02X535520I986J997D01*
G37*
G36*
G01X529234Y13778D02*
G03X529261Y13217I298J-267D01*
G02X527180Y13177I-1020J-1103D01*
G03X527184Y13738I-283J283D01*
G02X529234Y13778I1006J976D01*
G37*
G36*
G01X522834Y13817D02*
G03X522848Y13234I281J-285D01*
G02X520848I-1000J-1120D01*
G03X520862Y13817I-267J298D01*
G02X522834I986J997D01*
G37*
G36*
G01X516141D02*
G03X516155Y13234I281J-285D01*
G02X514155I-1000J-1120D01*
G03X514169Y13817I-267J298D01*
G02X516141I986J997D01*
G37*
G36*
G01X498709D02*
G03X498723Y13234I281J-285D01*
G02X496723I-1000J-1120D01*
G03X496737Y13817I-267J298D01*
G02X498709I986J997D01*
G37*
G36*
G01X492423Y13778D02*
G03X492450Y13217I298J-267D01*
G02X490369Y13177I-1020J-1103D01*
G03X490373Y13738I-283J283D01*
G02X492423Y13778I1006J976D01*
G37*
G36*
G01X486023Y13817D02*
G03X486037Y13234I281J-285D01*
G02X484037I-1000J-1120D01*
G03X484051Y13817I-267J298D01*
G02X486023I986J997D01*
G37*
G36*
G01X507663Y10810D02*
G03X507639Y10246I271J-294D01*
G02X505599Y10277I-1035J-946D01*
G03X505592Y10842I-287J279D01*
G02X505548Y12941I1052J1072D01*
G03Y13487I-292J273D01*
G02X505603Y15597I1096J1027D01*
G03X505619Y16158I-277J289D01*
G02X507669I1025J956D01*
G03X507685Y15597I293J-272D01*
G02X507740Y13487I-1041J-1083D01*
G03Y12941I292J-273D01*
G02X507663Y10810I-1096J-1027D01*
G37*
G36*
G01X539395Y10616D02*
G03X539380Y10055I277J-288D01*
G02X537330I-1025J-957D01*
G03X537315Y10616I-292J273D01*
G02X537259Y12727I1040J1084D01*
G03Y13273I-292J273D01*
G02X537298Y15367I1096J1027D01*
G03X537304Y15928I-282J284D01*
G02X539355Y15960I1011J972D01*
G03X539379Y15399I297J-268D01*
G02X539451Y13273I-1024J-1099D01*
G03Y12727I292J-273D01*
G02X539395Y10616I-1096J-1027D01*
G37*
G36*
G01X502584D02*
G03X502569Y10055I277J-288D01*
G02X500519I-1025J-957D01*
G03X500504Y10616I-292J273D01*
G02X500448Y12727I1040J1084D01*
G03Y13273I-292J273D01*
G02X500487Y15367I1096J1027D01*
G03X500493Y15928I-282J284D01*
G02X502544Y15960I1011J972D01*
G03X502568Y15399I297J-268D01*
G02X502640Y13273I-1024J-1099D01*
G03Y12727I292J-273D01*
G02X502584Y10616I-1096J-1027D01*
G37*
G36*
G01X539411Y-8143D02*
G03X539401Y-8715I274J-291D01*
G02X537389Y-8732I-998J-985D01*
G03X537369Y-8160I-289J276D01*
G02X537293Y-6015I1012J1110D01*
G03X537287Y-5458I-290J275D01*
G02X537314Y-3318I1068J1057D01*
G03X537330Y-2757I-277J289D01*
G02X539380I1025J956D01*
G03X539396Y-3318I293J-272D01*
G02X539443Y-5436I-1041J-1083D01*
G03X539449Y-5993I290J-275D01*
G02X539411Y-8143I-1068J-1056D01*
G37*
G36*
G01X502600D02*
G03X502590Y-8715I274J-291D01*
G02X500578Y-8732I-998J-985D01*
G03X500558Y-8160I-289J276D01*
G02X500482Y-6015I1012J1110D01*
G03X500476Y-5458I-290J275D01*
G02X500503Y-3318I1068J1057D01*
G03X500519Y-2757I-277J289D01*
G02X502569I1025J956D01*
G03X502585Y-3318I293J-272D01*
G02X502632Y-5436I-1041J-1083D01*
G03X502638Y-5993I290J-275D01*
G02X502600Y-8143I-1068J-1056D01*
G37*
G36*
G01X507689Y-8339D02*
G03X507676Y-8901I278J-288D01*
G02X505628Y-8911I-1019J-963D01*
G03X505610Y-8350I-293J271D01*
G02X505551Y-6230I1034J1090D01*
G03Y-5681I-291J274D01*
G02X505644Y-3531I1093J1030D01*
G03X505669Y-2959I-267J298D01*
G02X507680Y-2995I1023J959D01*
G03X507684Y-3568I281J-285D01*
G02X507737Y-5681I-1040J-1083D01*
G03Y-6230I291J-274D01*
G02X507689Y-8339I-1093J-1030D01*
G37*
G36*
G01X479330Y89417D02*
G03X479344Y88834I281J-285D01*
G02X477344I-1000J-1120D01*
G03X477358Y89417I-267J298D01*
G02X479330I986J997D01*
G37*
G36*
G01X461937Y89358D02*
G03X461953Y88797I293J-272D01*
G02X459871I-1041J-1083D01*
G03X459887Y89358I-277J289D01*
G02X461937I1025J956D01*
G37*
G36*
G01X455612Y89378D02*
G03X455639Y88817I298J-267D01*
G02X453558Y88777I-1020J-1103D01*
G03X453562Y89338I-283J283D01*
G02X455612Y89378I1006J976D01*
G37*
G36*
G01X470772Y86343D02*
G03X470753Y85736I251J-312D01*
G02X468881Y85751I-944J-1036D01*
G03X468872Y86359I-265J300D01*
G02X468736Y88541I960J1155D01*
G03Y89087I-292J273D01*
G02X468791Y91197I1096J1027D01*
G03X468807Y91758I-277J289D01*
G02X470857I1025J956D01*
G03X470873Y91197I293J-272D01*
G02X470928Y89087I-1041J-1083D01*
G03Y88541I292J-273D01*
G02X470772Y86343I-1096J-1027D01*
G37*
G36*
G01X465772Y86216D02*
G03X465757Y85655I277J-288D01*
G02X463707I-1025J-957D01*
G03X463692Y86216I-292J273D01*
G02X463636Y88327I1040J1084D01*
G03Y88873I-292J273D01*
G02X463681Y90973I1096J1027D01*
G03X463691Y91535I-280J286D01*
G02X465742Y91553I1017J965D01*
G03X465763Y90992I295J-270D01*
G02X465828Y88873I-1031J-1092D01*
G03Y88327I292J-273D01*
G02X465772Y86216I-1096J-1027D01*
G37*
G36*
G01X465799Y67467D02*
G03X465783Y66906I277J-289D01*
G02X463733I-1025J-956D01*
G03X463717Y67467I-293J272D01*
G02X463670Y69585I1041J1083D01*
G03X463664Y70142I-290J275D01*
G02X463691Y72282I1068J1057D01*
G03X463707Y72843I-277J289D01*
G02X465757I1025J956D01*
G03X465773Y72282I293J-272D01*
G02X465820Y70164I-1041J-1083D01*
G03X465826Y69607I290J-275D01*
G02X465799Y67467I-1068J-1057D01*
G37*
G36*
G01X470877Y67261D02*
G03X470864Y66699I278J-288D01*
G02X468816Y66689I-1019J-963D01*
G03X468798Y67250I-293J271D01*
G02X468739Y69370I1034J1090D01*
G03Y69919I-291J274D01*
G02X468802Y72043I1093J1031D01*
G03X468823Y72604I-274J291D01*
G02X470873Y72583I1035J946D01*
G03X470883Y72022I290J-275D01*
G02X470925Y69919I-1051J-1073D01*
G03Y69370I291J-274D01*
G02X470877Y67261I-1093J-1030D01*
G37*
G36*
G01X449900Y55935D02*
G03X450461Y55966I265J300D01*
G02X450520Y53886I1112J-1009D01*
G03X449958I-281J-285D01*
G02X449900Y55935I-985J997D01*
G37*
G36*
G01X479330Y51617D02*
G03X479344Y51034I281J-285D01*
G02X477344I-1000J-1120D01*
G03X477358Y51617I-267J298D01*
G02X479330I986J997D01*
G37*
G36*
G01X461898D02*
G03X461912Y51034I281J-285D01*
G02X459912I-1000J-1120D01*
G03X459926Y51617I-267J298D01*
G02X461898I986J997D01*
G37*
G36*
G01X470851Y48610D02*
G03X470827Y48046I271J-294D01*
G02X468787Y48077I-1035J-946D01*
G03X468780Y48642I-287J279D01*
G02X468736Y50741I1052J1072D01*
G03Y51287I-292J273D01*
G02X468791Y53397I1096J1027D01*
G03X468807Y53958I-277J289D01*
G02X470857I1025J956D01*
G03X470873Y53397I293J-272D01*
G02X470928Y51287I-1041J-1083D01*
G03Y50741I292J-273D01*
G02X470851Y48610I-1096J-1027D01*
G37*
G36*
G01X465772Y48416D02*
G03X465757Y47855I277J-288D01*
G02X463707I-1025J-957D01*
G03X463692Y48416I-292J273D01*
G02X463636Y50527I1040J1084D01*
G03Y51073I-292J273D01*
G02X463675Y53167I1096J1027D01*
G03X463681Y53728I-282J284D01*
G02X465732Y53760I1011J972D01*
G03X465756Y53199I297J-268D01*
G02X465828Y51073I-1024J-1099D01*
G03Y50527I292J-273D01*
G02X465772Y48416I-1096J-1027D01*
G37*
G36*
G01X450568Y85691D02*
G02X450273Y84189I1005J-977D01*
G03X449615Y84319I-371J-149D01*
G02X449910Y85821I-1005J977D01*
G03X450568Y85691I371J149D01*
G37*
G36*
G01X449516Y69174D02*
G02X447757Y69189I-889J-1084D01*
G03X447762Y69812I-249J314D01*
G02X447699Y71926I889J1084D01*
G03X447688Y72523I-271J294D01*
G02X449700Y74456I910J1066D01*
G03X450361Y74503I315J248D01*
G02X450472Y72932I1212J-704D01*
G03X449811Y72885I-315J-248D01*
G02X449551Y72559I-1214J702D01*
G03X449562Y71962I271J-294D01*
G02X449521Y69797I-911J-1066D01*
G03X449516Y69174I249J-314D01*
G37*
G36*
G01X455482Y50793D02*
G02X453715Y50763I-863J-1229D01*
G03X453717Y51400I-241J319D01*
G02X455458Y51430I852J1114D01*
G03X455482Y50793I254J-309D01*
G37*
G36*
G01X450402Y47672D02*
G02X450366Y46187I1171J-771D01*
G03X449688Y46203I-344J-204D01*
G02X449724Y47688I-1171J771D01*
G03X450402Y47672I344J204D01*
G37*
G36*
G01X449693Y35187D02*
G02X449593Y36520I-1279J574D01*
G03X450294Y36573I336J217D01*
G02X450394Y35240I1279J-574D01*
G03X449693Y35187I-336J-217D01*
G37*
G36*
G01X465793Y29662D02*
G03X465785Y29089I275J-290D01*
G02X463774Y29064I-993J-989D01*
G03X463751Y29635I-291J274D01*
G02X463670Y31785I1007J1114D01*
G03X463664Y32342I-290J275D01*
G02X463691Y34482I1068J1057D01*
G03X463707Y35043I-277J289D01*
G02X465757I1025J956D01*
G03X465773Y34482I293J-272D01*
G02X465820Y32364I-1041J-1083D01*
G03X465826Y31807I290J-275D01*
G02X465793Y29662I-1068J-1056D01*
G37*
G36*
G01X470877Y29461D02*
G03X470864Y28899I278J-288D01*
G02X468816Y28889I-1019J-963D01*
G03X468798Y29450I-293J271D01*
G02X468739Y31570I1034J1090D01*
G03Y32119I-291J274D01*
G02X468795Y34236I1093J1030D01*
G03X468801Y34808I-276J289D01*
G02X470812Y34838I991J992D01*
G03X470836Y34266I291J-274D01*
G02X470925Y32119I-1004J-1117D01*
G03Y31570I291J-275D01*
G02X470877Y29461I-1093J-1030D01*
G37*
G36*
G01X450519Y16087D02*
G03X449939Y16068I-281J-285D01*
G02X449823Y18048I-1047J932D01*
G03X450401Y18097I266J299D01*
G02X450519Y16087I1172J-940D01*
G37*
G36*
G01X479330Y13817D02*
G03X479344Y13234I281J-285D01*
G02X477344I-1000J-1120D01*
G03X477358Y13817I-267J298D01*
G02X479330I986J997D01*
G37*
G36*
G01X461898D02*
G03X461912Y13234I281J-285D01*
G02X459912I-1000J-1120D01*
G03X459926Y13817I-267J298D01*
G02X461898I986J997D01*
G37*
G36*
G01X455612Y13778D02*
G03X455639Y13217I298J-267D01*
G02X453558Y13177I-1020J-1103D01*
G03X453562Y13738I-283J283D01*
G02X455612Y13778I1006J976D01*
G37*
G36*
G01X449293Y12718D02*
G03X449294Y12156I285J-280D01*
G02X447213Y12209I-1068J-1056D01*
G03X447243Y12770I-269J296D01*
G02X449293Y12718I1049J930D01*
G37*
G36*
G01X470851Y10810D02*
G03X470827Y10246I271J-294D01*
G02X468787Y10277I-1035J-946D01*
G03X468780Y10842I-287J279D01*
G02X468736Y12941I1052J1072D01*
G03Y13487I-292J273D01*
G02X468791Y15597I1096J1027D01*
G03X468807Y16158I-277J289D01*
G02X470857I1025J956D01*
G03X470873Y15597I293J-272D01*
G02X470928Y13487I-1041J-1083D01*
G03Y12941I292J-273D01*
G02X470851Y10810I-1096J-1027D01*
G37*
G36*
G01X465772Y10616D02*
G03X465757Y10055I277J-288D01*
G02X463707I-1025J-957D01*
G03X463692Y10616I-292J273D01*
G02X463636Y12727I1040J1084D01*
G03Y13273I-292J273D01*
G02X463675Y15367I1096J1027D01*
G03X463681Y15928I-282J284D01*
G02X465732Y15960I1011J972D01*
G03X465756Y15399I297J-268D01*
G02X465828Y13273I-1024J-1099D01*
G03Y12727I292J-273D01*
G02X465772Y10616I-1096J-1027D01*
G37*
G36*
G01X465798Y-8134D02*
G03X465783Y-8695I277J-288D01*
G02X463733I-1025J-957D01*
G03X463718Y-8134I-292J273D01*
G02X463670Y-6015I1040J1084D01*
G03X463664Y-5458I-290J275D01*
G02X463691Y-3318I1068J1057D01*
G03X463707Y-2757I-277J289D01*
G02X465757I1025J956D01*
G03X465773Y-3318I293J-272D01*
G02X465820Y-5436I-1041J-1083D01*
G03X465826Y-5993I290J-275D01*
G02X465798Y-8134I-1068J-1057D01*
G37*
G36*
G01X470877Y-8339D02*
G03X470864Y-8901I278J-288D01*
G02X468816Y-8911I-1019J-963D01*
G03X468798Y-8350I-293J271D01*
G02X468739Y-6230I1034J1090D01*
G03Y-5681I-291J274D01*
G02X468791Y-3568I1093J1030D01*
G03X468807Y-3007I-277J289D01*
G02X470857I1025J956D01*
G03X470873Y-3568I293J-272D01*
G02X470925Y-5681I-1041J-1083D01*
G03Y-6230I291J-274D01*
G02X470877Y-8339I-1093J-1030D01*
G37*
G36*
G01X364495Y91490D02*
G03X363904I-295J-269D01*
G02Y93510I-1112J1010D01*
G03X364495I296J269D01*
G02Y91490I1112J-1010D01*
G37*
G36*
G01X364129Y86483D02*
G03X363540I-295J-271D01*
G02Y88517I-1105J1017D01*
G03X364129I294J271D01*
G02Y86483I1105J-1017D01*
G37*
G36*
G01X376469Y85390D02*
G03Y84864I302J-263D01*
G02X374205I-1132J-987D01*
G03Y85390I-302J263D01*
G02X376469I1132J987D01*
G37*
G36*
G01X358743Y69924D02*
G03Y69346I277J-289D01*
G02X356801I-971J-1011D01*
G03Y69924I-277J289D01*
G02X358743I971J1011D01*
G37*
G36*
G01X381854Y62047D02*
G03X381873Y61418I256J-307D01*
G02X380018Y61363I-892J-1208D01*
G03X379999Y61992I-256J307D01*
G02X381854Y62047I892J1208D01*
G37*
G36*
G01X358702Y51293D02*
G03Y50699I268J-297D01*
G02X356822I-940J-1040D01*
G03Y51293I-268J297D01*
G02X358702I940J1040D01*
G37*
G36*
G01X363196Y46006D02*
G03X362587I-305J-258D01*
G02Y47822I-1069J908D01*
G03X363196I305J258D01*
G02Y46006I1069J-908D01*
G37*
G36*
G01X375007Y75306D02*
G02X373577I-715J-1206D01*
G03Y75994I-204J344D01*
G02X375007I715J1206D01*
G03Y75306I204J-344D01*
G37*
G36*
G01X362540Y54128D02*
G02Y55556I-1322J714D01*
G03X363243I352J190D01*
G02Y54128I1322J-714D01*
G03X362540I-351J-190D01*
G37*
G36*
G01Y35228D02*
G02Y36656I-1322J714D01*
G03X363243I352J190D01*
G02Y35228I1322J-714D01*
G03X362540I-351J-190D01*
G37*
G36*
G01X359577Y32318D02*
G03X359571Y31740I273J-292D01*
G02X357634Y31760I-979J-1004D01*
G03X357640Y32338I-273J292D01*
G02X359577Y32318I979J1004D01*
G37*
G36*
G01X375354Y18434D02*
G03X375122Y17963I155J-369D01*
G02X373089Y18965I-1452J-383D01*
G03X373321Y19436I-155J369D01*
G02X375354Y18434I1452J383D01*
G37*
G36*
G01X364276Y15953D02*
G03X363719Y15947I-275J-290D01*
G02X363697Y18103I-1057J1067D01*
G03X364254Y18109I275J290D01*
G02X364276Y15953I1057J-1067D01*
G37*
G36*
G01X358463Y13303D02*
G03Y12725I277J-289D01*
G02X356521I-971J-1011D01*
G03Y13303I-277J289D01*
G02X358463I971J1011D01*
G37*
G36*
G01X381635Y26053D02*
G02X379949I-843J-1120D01*
G03Y26692I-241J320D01*
G02X381635I843J1120D01*
G03Y26053I241J-320D01*
G37*
G36*
G01X362540Y8400D02*
G02Y9828I-1322J714D01*
G03X363243I352J190D01*
G02Y8400I1322J-714D01*
G03X362540I-351J-190D01*
G37*
G36*
G01X376959Y5723D02*
G02Y7277I-1167J777D01*
G03X377625I333J222D01*
G02Y5723I1167J-777D01*
G03X376959I-333J-222D01*
G37*
G36*
G01X362540Y-2572D02*
G02Y-1144I-1322J714D01*
G03X363243I352J190D01*
G02Y-2572I1322J-714D01*
G03X362540I-351J-190D01*
G37*
G36*
G01Y-10500D02*
G02Y-9072I-1322J714D01*
G03X363243I352J190D01*
G02Y-10500I1322J-714D01*
G03X362540I-351J-190D01*
G37*
G36*
G01X375810Y-11867D02*
G02X375602Y-10444I-1409J521D01*
G03X376292Y-10354I320J240D01*
G02X378626Y-9933I1300J-526D01*
G03X379212Y-9938I295J270D01*
G02X379198Y-11847I1020J-962D01*
G03X378612Y-11842I-295J-270D01*
G02X376497Y-11756I-1020J962D01*
G03X375810Y-11867I-312J-250D01*
G37*
G36*
G01X305282Y89435D02*
G03X305307Y88853I286J-279D01*
G02X303307Y88816I-979J-1139D01*
G03X303311Y89399I-272J293D01*
G02X305282Y89435I967J1015D01*
G37*
G36*
G01X298621Y89417D02*
G03X298635Y88834I281J-285D01*
G02X296635I-1000J-1120D01*
G03X296649Y89417I-267J298D01*
G02X298621I986J997D01*
G37*
G36*
G01X308938Y69365D02*
G03X308924Y68789I270J-295D01*
G02X306982Y68837I-996J-987D01*
G03X306996Y69413I-270J295D01*
G02X308938Y69365I996J987D01*
G37*
G36*
G01X305314Y51617D02*
G03X305328Y51034I281J-285D01*
G02X303328I-1000J-1120D01*
G03X303342Y51617I-267J298D01*
G02X305314I986J997D01*
G37*
G36*
G01X298621D02*
G03X298635Y51034I281J-285D01*
G02X296635I-1000J-1120D01*
G03X296649Y51617I-267J298D01*
G02X298621I986J997D01*
G37*
G36*
G01X305314Y13817D02*
G03X305328Y13234I281J-285D01*
G02X303328I-1000J-1120D01*
G03X303342Y13817I-267J298D01*
G02X305314I986J997D01*
G37*
G36*
G01X298621D02*
G03X298635Y13234I281J-285D01*
G02X296635I-1000J-1120D01*
G03X296649Y13817I-267J298D01*
G02X298621I986J997D01*
G37*
G36*
G01X281189Y89417D02*
G03X281203Y88834I281J-285D01*
G02X279203I-1000J-1120D01*
G03X279217Y89417I-267J298D01*
G02X281189I986J997D01*
G37*
G36*
G01X274903Y89378D02*
G03X274930Y88817I298J-267D01*
G02X272849Y88777I-1020J-1103D01*
G03X272853Y89338I-283J283D01*
G02X274903Y89378I1006J976D01*
G37*
G36*
G01X268503Y89417D02*
G03X268517Y88834I281J-285D01*
G02X266517I-1000J-1120D01*
G03X266531Y89417I-267J298D01*
G02X268503I986J997D01*
G37*
G36*
G01X261810D02*
G03X261824Y88834I281J-285D01*
G02X259824I-1000J-1120D01*
G03X259838Y89417I-267J298D01*
G02X261810I986J997D01*
G37*
G36*
G01X244378D02*
G03X244392Y88834I281J-285D01*
G02X242392I-1000J-1120D01*
G03X242406Y89417I-267J298D01*
G02X244378I986J997D01*
G37*
G36*
G01X238092Y89378D02*
G03X238119Y88817I298J-267D01*
G02X236038Y88777I-1020J-1103D01*
G03X236042Y89338I-283J283D01*
G02X238092Y89378I1006J976D01*
G37*
G36*
G01X290064Y86343D02*
G03X290045Y85736I251J-312D01*
G02X288173Y85751I-944J-1036D01*
G03X288164Y86359I-265J300D01*
G02X288028Y88541I960J1155D01*
G03Y89087I-292J273D01*
G02X288083Y91197I1096J1027D01*
G03X288099Y91758I-277J289D01*
G02X290149I1025J956D01*
G03X290165Y91197I293J-272D01*
G02X290220Y89087I-1041J-1083D01*
G03Y88541I292J-273D01*
G02X290064Y86343I-1096J-1027D01*
G37*
G36*
G01X253253D02*
G03X253234Y85736I251J-312D01*
G02X251362Y85751I-944J-1036D01*
G03X251353Y86359I-265J300D01*
G02X251217Y88541I960J1155D01*
G03Y89087I-292J273D01*
G02X251272Y91197I1096J1027D01*
G03X251288Y91758I-277J289D01*
G02X253338I1025J956D01*
G03X253354Y91197I293J-272D01*
G02X253409Y89087I-1041J-1083D01*
G03Y88541I292J-273D01*
G02X253253Y86343I-1096J-1027D01*
G37*
G36*
G01X285064Y86216D02*
G03X285049Y85655I277J-288D01*
G02X282999I-1025J-957D01*
G03X282984Y86216I-292J273D01*
G02X282928Y88327I1040J1084D01*
G03Y88873I-292J273D01*
G02X282973Y90973I1096J1027D01*
G03X282983Y91535I-280J286D01*
G02X285034Y91553I1017J965D01*
G03X285055Y90992I295J-270D01*
G02X285120Y88873I-1031J-1092D01*
G03Y88327I292J-273D01*
G02X285064Y86216I-1096J-1027D01*
G37*
G36*
G01X248253D02*
G03X248238Y85655I277J-288D01*
G02X246188I-1025J-957D01*
G03X246173Y86216I-292J273D01*
G02X246117Y88327I1040J1084D01*
G03Y88873I-292J273D01*
G02X246162Y90973I1096J1027D01*
G03X246172Y91535I-280J286D01*
G02X248223Y91553I1017J965D01*
G03X248244Y90992I295J-270D01*
G02X248309Y88873I-1031J-1092D01*
G03Y88327I292J-273D01*
G02X248253Y86216I-1096J-1027D01*
G37*
G36*
G01X285091Y67467D02*
G03X285075Y66906I277J-289D01*
G02X283025I-1025J-956D01*
G03X283009Y67467I-293J272D01*
G02X282962Y69585I1041J1083D01*
G03X282956Y70142I-290J275D01*
G02X282983Y72282I1068J1057D01*
G03X282999Y72843I-277J289D01*
G02X285049I1025J956D01*
G03X285065Y72282I293J-272D01*
G02X285112Y70164I-1041J-1083D01*
G03X285118Y69607I290J-275D01*
G02X285091Y67467I-1068J-1057D01*
G37*
G36*
G01X248280D02*
G03X248264Y66906I277J-289D01*
G02X246214I-1025J-956D01*
G03X246198Y67467I-293J272D01*
G02X246151Y69585I1041J1083D01*
G03X246145Y70142I-290J275D01*
G02X246172Y72282I1068J1057D01*
G03X246188Y72843I-277J289D01*
G02X248238I1025J956D01*
G03X248254Y72282I293J-272D01*
G02X248301Y70164I-1041J-1083D01*
G03X248307Y69607I290J-275D01*
G02X248280Y67467I-1068J-1057D01*
G37*
G36*
G01X290169Y67261D02*
G03X290156Y66699I278J-288D01*
G02X288108Y66689I-1019J-963D01*
G03X288090Y67250I-293J271D01*
G02X288031Y69370I1034J1090D01*
G03Y69919I-291J274D01*
G02X288094Y72043I1093J1031D01*
G03X288115Y72604I-274J291D01*
G02X290165Y72583I1035J946D01*
G03X290175Y72022I290J-275D01*
G02X290217Y69919I-1051J-1073D01*
G03Y69370I291J-274D01*
G02X290169Y67261I-1093J-1030D01*
G37*
G36*
G01X253358D02*
G03X253345Y66699I278J-288D01*
G02X251297Y66689I-1019J-963D01*
G03X251279Y67250I-293J271D01*
G02X251220Y69370I1034J1090D01*
G03Y69919I-291J274D01*
G02X251283Y72043I1093J1031D01*
G03X251304Y72604I-274J291D01*
G02X253354Y72583I1035J946D01*
G03X253364Y72022I290J-275D01*
G02X253406Y69919I-1051J-1073D01*
G03Y69370I291J-274D01*
G02X253358Y67261I-1093J-1030D01*
G37*
G36*
G01X281189Y51617D02*
G03X281203Y51034I281J-285D01*
G02X279203I-1000J-1120D01*
G03X279217Y51617I-267J298D01*
G02X281189I986J997D01*
G37*
G36*
G01X268503D02*
G03X268517Y51034I281J-285D01*
G02X266517I-1000J-1120D01*
G03X266531Y51617I-267J298D01*
G02X268503I986J997D01*
G37*
G36*
G01X261810D02*
G03X261824Y51034I281J-285D01*
G02X259824I-1000J-1120D01*
G03X259838Y51617I-267J298D01*
G02X261810I986J997D01*
G37*
G36*
G01X244378D02*
G03X244392Y51034I281J-285D01*
G02X242392I-1000J-1120D01*
G03X242406Y51617I-267J298D01*
G02X244378I986J997D01*
G37*
G36*
G01X238092Y51578D02*
G03X238119Y51017I298J-267D01*
G02X236038Y50977I-1020J-1103D01*
G03X236042Y51538I-283J283D01*
G02X238092Y51578I1006J976D01*
G37*
G36*
G01X290064Y48543D02*
G03X290045Y47936I251J-312D01*
G02X288173Y47951I-944J-1036D01*
G03X288164Y48559I-265J300D01*
G02X288028Y50741I960J1155D01*
G03Y51287I-292J273D01*
G02X288083Y53397I1096J1027D01*
G03X288099Y53958I-277J289D01*
G02X290149I1025J956D01*
G03X290165Y53397I293J-272D01*
G02X290220Y51287I-1041J-1083D01*
G03Y50741I292J-273D01*
G02X290064Y48543I-1096J-1027D01*
G37*
G36*
G01X253253D02*
G03X253234Y47936I251J-312D01*
G02X251362Y47951I-944J-1036D01*
G03X251353Y48559I-265J300D01*
G02X251217Y50741I960J1155D01*
G03Y51287I-292J273D01*
G02X251272Y53397I1096J1027D01*
G03X251288Y53958I-277J289D01*
G02X253338I1025J956D01*
G03X253354Y53397I293J-272D01*
G02X253409Y51287I-1041J-1083D01*
G03Y50741I292J-273D01*
G02X253253Y48543I-1096J-1027D01*
G37*
G36*
G01X285064Y48416D02*
G03X285049Y47855I277J-288D01*
G02X282999I-1025J-957D01*
G03X282984Y48416I-292J273D01*
G02X282928Y50527I1040J1084D01*
G03Y51073I-292J273D01*
G02X282973Y53173I1096J1027D01*
G03X282983Y53735I-280J286D01*
G02X285034Y53753I1017J965D01*
G03X285055Y53192I295J-270D01*
G02X285120Y51073I-1031J-1092D01*
G03Y50527I292J-273D01*
G02X285064Y48416I-1096J-1027D01*
G37*
G36*
G01X248253D02*
G03X248238Y47855I277J-288D01*
G02X246188I-1025J-957D01*
G03X246173Y48416I-292J273D01*
G02X246117Y50527I1040J1084D01*
G03Y51073I-292J273D01*
G02X246162Y53173I1096J1027D01*
G03X246172Y53735I-280J286D01*
G02X248223Y53753I1017J965D01*
G03X248244Y53192I295J-270D01*
G02X248309Y51073I-1031J-1092D01*
G03Y50527I292J-273D01*
G02X248253Y48416I-1096J-1027D01*
G37*
G36*
G01X285091Y29667D02*
G03X285075Y29106I277J-289D01*
G02X283025I-1025J-956D01*
G03X283009Y29667I-293J272D01*
G02X282962Y31785I1041J1083D01*
G03X282956Y32342I-290J275D01*
G02X282983Y34482I1068J1057D01*
G03X282999Y35043I-277J289D01*
G02X285049I1025J956D01*
G03X285065Y34482I293J-272D01*
G02X285112Y32364I-1041J-1083D01*
G03X285118Y31807I290J-275D01*
G02X285091Y29667I-1068J-1057D01*
G37*
G36*
G01X248280D02*
G03X248264Y29106I277J-289D01*
G02X246214I-1025J-956D01*
G03X246198Y29667I-293J272D01*
G02X246151Y31785I1041J1083D01*
G03X246145Y32342I-290J275D01*
G02X246172Y34482I1068J1057D01*
G03X246188Y35043I-277J289D01*
G02X248238I1025J956D01*
G03X248254Y34482I293J-272D01*
G02X248301Y32364I-1041J-1083D01*
G03X248307Y31807I290J-275D01*
G02X248280Y29667I-1068J-1057D01*
G37*
G36*
G01X290169Y29461D02*
G03X290156Y28899I278J-288D01*
G02X288108Y28889I-1019J-963D01*
G03X288090Y29450I-293J271D01*
G02X288031Y31570I1034J1090D01*
G03Y32119I-291J274D01*
G02X288094Y34243I1093J1031D01*
G03X288115Y34804I-274J291D01*
G02X290165Y34783I1035J946D01*
G03X290175Y34222I290J-275D01*
G02X290217Y32119I-1051J-1073D01*
G03Y31570I291J-275D01*
G02X290169Y29461I-1093J-1030D01*
G37*
G36*
G01X253358D02*
G03X253345Y28899I278J-288D01*
G02X251297Y28889I-1019J-963D01*
G03X251279Y29450I-293J271D01*
G02X251220Y31570I1034J1090D01*
G03Y32119I-291J274D01*
G02X251283Y34243I1093J1031D01*
G03X251304Y34804I-274J291D01*
G02X253354Y34783I1035J946D01*
G03X253364Y34222I290J-275D01*
G02X253406Y32119I-1051J-1073D01*
G03Y31570I291J-275D01*
G02X253358Y29461I-1093J-1030D01*
G37*
G36*
G01X281189Y13817D02*
G03X281203Y13234I281J-285D01*
G02X279203I-1000J-1120D01*
G03X279217Y13817I-267J298D01*
G02X281189I986J997D01*
G37*
G36*
G01X274903Y13778D02*
G03X274930Y13217I298J-267D01*
G02X272849Y13177I-1020J-1103D01*
G03X272853Y13738I-283J283D01*
G02X274903Y13778I1006J976D01*
G37*
G36*
G01X268503Y13817D02*
G03X268517Y13234I281J-285D01*
G02X266517I-1000J-1120D01*
G03X266531Y13817I-267J298D01*
G02X268503I986J997D01*
G37*
G36*
G01X261810D02*
G03X261824Y13234I281J-285D01*
G02X259824I-1000J-1120D01*
G03X259838Y13817I-267J298D01*
G02X261810I986J997D01*
G37*
G36*
G01X244378D02*
G03X244392Y13234I281J-285D01*
G02X242392I-1000J-1120D01*
G03X242406Y13817I-267J298D01*
G02X244378I986J997D01*
G37*
G36*
G01X238092Y13778D02*
G03X238119Y13217I298J-267D01*
G02X236038Y13177I-1020J-1103D01*
G03X236042Y13738I-283J283D01*
G02X238092Y13778I1006J976D01*
G37*
G36*
G01X290064Y10743D02*
G03X290045Y10136I251J-312D01*
G02X288173Y10151I-944J-1036D01*
G03X288164Y10759I-265J300D01*
G02X288028Y12941I960J1155D01*
G03Y13487I-292J273D01*
G02X288083Y15597I1096J1027D01*
G03X288099Y16158I-277J289D01*
G02X290149I1025J956D01*
G03X290165Y15597I293J-272D01*
G02X290220Y13487I-1041J-1083D01*
G03Y12941I292J-273D01*
G02X290064Y10743I-1096J-1027D01*
G37*
G36*
G01X253253D02*
G03X253234Y10136I251J-312D01*
G02X251362Y10151I-944J-1036D01*
G03X251353Y10759I-265J300D01*
G02X251217Y12941I960J1155D01*
G03Y13487I-292J273D01*
G02X251272Y15597I1096J1027D01*
G03X251288Y16158I-277J289D01*
G02X253338I1025J956D01*
G03X253354Y15597I293J-272D01*
G02X253409Y13487I-1041J-1083D01*
G03Y12941I292J-273D01*
G02X253253Y10743I-1096J-1027D01*
G37*
G36*
G01X285064Y10616D02*
G03X285049Y10055I277J-288D01*
G02X282999I-1025J-957D01*
G03X282984Y10616I-292J273D01*
G02X282928Y12727I1040J1084D01*
G03Y13273I-292J273D01*
G02X282973Y15373I1096J1027D01*
G03X282983Y15935I-280J286D01*
G02X285034Y15953I1017J965D01*
G03X285055Y15392I295J-270D01*
G02X285120Y13273I-1031J-1092D01*
G03Y12727I292J-273D01*
G02X285064Y10616I-1096J-1027D01*
G37*
G36*
G01X248253D02*
G03X248238Y10055I277J-288D01*
G02X246188I-1025J-957D01*
G03X246173Y10616I-292J273D01*
G02X246117Y12727I1040J1084D01*
G03Y13273I-292J273D01*
G02X246162Y15373I1096J1027D01*
G03X246172Y15935I-280J286D01*
G02X248223Y15953I1017J965D01*
G03X248244Y15392I295J-270D01*
G02X248309Y13273I-1031J-1092D01*
G03Y12727I292J-273D01*
G02X248253Y10616I-1096J-1027D01*
G37*
G36*
G01X285091Y-8133D02*
G03X285075Y-8694I277J-289D01*
G02X283025I-1025J-956D01*
G03X283009Y-8133I-293J272D01*
G02X282962Y-6015I1041J1083D01*
G03X282956Y-5458I-290J275D01*
G02X282983Y-3318I1068J1057D01*
G03X282999Y-2757I-277J289D01*
G02X285049I1025J956D01*
G03X285065Y-3318I293J-272D01*
G02X285112Y-5436I-1041J-1083D01*
G03X285118Y-5993I290J-275D01*
G02X285091Y-8133I-1068J-1057D01*
G37*
G36*
G01X248280D02*
G03X248264Y-8694I277J-289D01*
G02X246214I-1025J-956D01*
G03X246198Y-8133I-293J272D01*
G02X246151Y-6015I1041J1083D01*
G03X246145Y-5458I-290J275D01*
G02X246172Y-3318I1068J1057D01*
G03X246188Y-2757I-277J289D01*
G02X248238I1025J956D01*
G03X248254Y-3318I293J-272D01*
G02X248301Y-5436I-1041J-1083D01*
G03X248307Y-5993I290J-275D01*
G02X248280Y-8133I-1068J-1057D01*
G37*
G36*
G01X290169Y-8339D02*
G03X290156Y-8901I278J-288D01*
G02X288108Y-8911I-1019J-963D01*
G03X288090Y-8350I-293J271D01*
G02X288031Y-6230I1034J1090D01*
G03Y-5681I-291J274D01*
G02X288094Y-3557I1093J1031D01*
G03X288115Y-2996I-274J291D01*
G02X290165Y-3017I1035J946D01*
G03X290175Y-3578I290J-275D01*
G02X290217Y-5681I-1051J-1073D01*
G03Y-6230I291J-274D01*
G02X290169Y-8339I-1093J-1030D01*
G37*
G36*
G01X253358D02*
G03X253345Y-8901I278J-288D01*
G02X251297Y-8911I-1019J-963D01*
G03X251279Y-8350I-293J271D01*
G02X251220Y-6230I1034J1090D01*
G03Y-5681I-291J274D01*
G02X251283Y-3557I1093J1031D01*
G03X251304Y-2996I-274J291D01*
G02X253354Y-3017I1035J946D01*
G03X253364Y-3578I290J-275D01*
G02X253406Y-5681I-1051J-1073D01*
G03Y-6230I291J-274D01*
G02X253358Y-8339I-1093J-1030D01*
G37*
G36*
G01X231692Y89417D02*
G03X231706Y88834I281J-285D01*
G02X229706I-1000J-1120D01*
G03X229720Y89417I-267J298D01*
G02X231692I986J997D01*
G37*
G36*
G01X224999D02*
G03X225013Y88834I281J-285D01*
G02X223013I-1000J-1120D01*
G03X223027Y89417I-267J298D01*
G02X224999I986J997D01*
G37*
G36*
G01X207567D02*
G03X207581Y88834I281J-285D01*
G02X205581I-1000J-1120D01*
G03X205595Y89417I-267J298D01*
G02X207567I986J997D01*
G37*
G36*
G01X201281Y89378D02*
G03X201308Y88817I298J-267D01*
G02X199227Y88777I-1020J-1103D01*
G03X199231Y89338I-283J283D01*
G02X201281Y89378I1006J976D01*
G37*
G36*
G01X194881Y89417D02*
G03X194895Y88834I281J-285D01*
G02X192895I-1000J-1120D01*
G03X192909Y89417I-267J298D01*
G02X194881I986J997D01*
G37*
G36*
G01X188188D02*
G03X188202Y88834I281J-285D01*
G02X186202I-1000J-1120D01*
G03X186216Y89417I-267J298D01*
G02X188188I986J997D01*
G37*
G36*
G01X216442Y86343D02*
G03X216423Y85736I251J-312D01*
G02X214551Y85751I-944J-1036D01*
G03X214542Y86359I-265J300D01*
G02X214406Y88541I960J1155D01*
G03Y89087I-292J273D01*
G02X214461Y91197I1096J1027D01*
G03X214477Y91758I-277J289D01*
G02X216527I1025J956D01*
G03X216543Y91197I293J-272D01*
G02X216598Y89087I-1041J-1083D01*
G03Y88541I292J-273D01*
G02X216442Y86343I-1096J-1027D01*
G37*
G36*
G01X179631D02*
G03X179612Y85736I251J-312D01*
G02X177740Y85751I-944J-1036D01*
G03X177731Y86359I-265J300D01*
G02X177595Y88541I960J1155D01*
G03Y89087I-292J273D01*
G02X177650Y91197I1096J1027D01*
G03X177666Y91758I-277J289D01*
G02X179716I1025J956D01*
G03X179732Y91197I293J-272D01*
G02X179787Y89087I-1041J-1083D01*
G03Y88541I292J-273D01*
G02X179631Y86343I-1096J-1027D01*
G37*
G36*
G01X211442Y86216D02*
G03X211427Y85655I277J-288D01*
G02X209377I-1025J-957D01*
G03X209362Y86216I-292J273D01*
G02X209306Y88327I1040J1084D01*
G03Y88873I-292J273D01*
G02X209351Y90973I1096J1027D01*
G03X209361Y91535I-280J286D01*
G02X211412Y91553I1017J965D01*
G03X211433Y90992I295J-270D01*
G02X211498Y88873I-1031J-1092D01*
G03Y88327I292J-273D01*
G02X211442Y86216I-1096J-1027D01*
G37*
G36*
G01X174631D02*
G03X174616Y85655I277J-288D01*
G02X172566I-1025J-957D01*
G03X172551Y86216I-292J273D01*
G02X172495Y88327I1040J1084D01*
G03Y88873I-292J273D01*
G02X172540Y90973I1096J1027D01*
G03X172550Y91535I-280J286D01*
G02X174601Y91553I1017J965D01*
G03X174622Y90992I295J-270D01*
G02X174687Y88873I-1031J-1092D01*
G03Y88327I292J-273D01*
G02X174631Y86216I-1096J-1027D01*
G37*
G36*
G01X211469Y67467D02*
G03X211453Y66906I277J-289D01*
G02X209403I-1025J-956D01*
G03X209387Y67467I-293J272D01*
G02X209340Y69585I1041J1083D01*
G03X209334Y70142I-290J275D01*
G02X209361Y72282I1068J1057D01*
G03X209377Y72843I-277J289D01*
G02X211427I1025J956D01*
G03X211443Y72282I293J-272D01*
G02X211490Y70164I-1041J-1083D01*
G03X211496Y69607I290J-275D01*
G02X211469Y67467I-1068J-1057D01*
G37*
G36*
G01X174658D02*
G03X174642Y66906I277J-289D01*
G02X172592I-1025J-956D01*
G03X172576Y67467I-293J272D01*
G02X172529Y69585I1041J1083D01*
G03X172523Y70142I-290J275D01*
G02X172550Y72282I1068J1057D01*
G03X172566Y72843I-277J289D01*
G02X174616I1025J956D01*
G03X174632Y72282I293J-272D01*
G02X174679Y70164I-1041J-1083D01*
G03X174685Y69607I290J-275D01*
G02X174658Y67467I-1068J-1057D01*
G37*
G36*
G01X216547Y67261D02*
G03X216534Y66699I278J-288D01*
G02X214486Y66689I-1019J-963D01*
G03X214468Y67250I-293J271D01*
G02X214409Y69370I1034J1090D01*
G03Y69919I-291J274D01*
G02X214472Y72043I1093J1031D01*
G03X214493Y72604I-274J291D01*
G02X216543Y72583I1035J946D01*
G03X216553Y72022I290J-275D01*
G02X216595Y69919I-1051J-1073D01*
G03Y69370I291J-274D01*
G02X216547Y67261I-1093J-1030D01*
G37*
G36*
G01X179736D02*
G03X179723Y66699I278J-288D01*
G02X177675Y66689I-1019J-963D01*
G03X177657Y67250I-293J271D01*
G02X177598Y69370I1034J1090D01*
G03Y69919I-291J274D01*
G02X177661Y72043I1093J1031D01*
G03X177682Y72604I-274J291D01*
G02X179732Y72583I1035J946D01*
G03X179742Y72022I290J-275D01*
G02X179784Y69919I-1051J-1073D01*
G03Y69370I291J-274D01*
G02X179736Y67261I-1093J-1030D01*
G37*
G36*
G01X231692Y51617D02*
G03X231706Y51034I281J-285D01*
G02X229706I-1000J-1120D01*
G03X229720Y51617I-267J298D01*
G02X231692I986J997D01*
G37*
G36*
G01X224999D02*
G03X225013Y51034I281J-285D01*
G02X223013I-1000J-1120D01*
G03X223027Y51617I-267J298D01*
G02X224999I986J997D01*
G37*
G36*
G01X207567D02*
G03X207581Y51034I281J-285D01*
G02X205581I-1000J-1120D01*
G03X205595Y51617I-267J298D01*
G02X207567I986J997D01*
G37*
G36*
G01X201281Y51578D02*
G03X201308Y51017I298J-267D01*
G02X199227Y50977I-1020J-1103D01*
G03X199231Y51538I-283J283D01*
G02X201281Y51578I1006J976D01*
G37*
G36*
G01X194881Y51617D02*
G03X194895Y51034I281J-285D01*
G02X192895I-1000J-1120D01*
G03X192909Y51617I-267J298D01*
G02X194881I986J997D01*
G37*
G36*
G01X188188D02*
G03X188202Y51034I281J-285D01*
G02X186202I-1000J-1120D01*
G03X186216Y51617I-267J298D01*
G02X188188I986J997D01*
G37*
G36*
G01X216442Y48543D02*
G03X216423Y47936I251J-312D01*
G02X214551Y47951I-944J-1036D01*
G03X214542Y48559I-265J300D01*
G02X214406Y50741I960J1155D01*
G03Y51287I-292J273D01*
G02X214461Y53397I1096J1027D01*
G03X214477Y53958I-277J289D01*
G02X216527I1025J956D01*
G03X216543Y53397I293J-272D01*
G02X216598Y51287I-1041J-1083D01*
G03Y50741I292J-273D01*
G02X216442Y48543I-1096J-1027D01*
G37*
G36*
G01X179631D02*
G03X179612Y47936I251J-312D01*
G02X177740Y47951I-944J-1036D01*
G03X177731Y48559I-265J300D01*
G02X177595Y50741I960J1155D01*
G03Y51287I-292J273D01*
G02X177650Y53397I1096J1027D01*
G03X177666Y53958I-277J289D01*
G02X179716I1025J956D01*
G03X179732Y53397I293J-272D01*
G02X179787Y51287I-1041J-1083D01*
G03Y50741I292J-273D01*
G02X179631Y48543I-1096J-1027D01*
G37*
G36*
G01X211442Y48416D02*
G03X211427Y47855I277J-288D01*
G02X209377I-1025J-957D01*
G03X209362Y48416I-292J273D01*
G02X209306Y50527I1040J1084D01*
G03Y51073I-292J273D01*
G02X209351Y53173I1096J1027D01*
G03X209361Y53735I-280J286D01*
G02X211412Y53753I1017J965D01*
G03X211433Y53192I295J-270D01*
G02X211498Y51073I-1031J-1092D01*
G03Y50527I292J-273D01*
G02X211442Y48416I-1096J-1027D01*
G37*
G36*
G01X174631D02*
G03X174616Y47855I277J-288D01*
G02X172566I-1025J-957D01*
G03X172551Y48416I-292J273D01*
G02X172495Y50527I1040J1084D01*
G03Y51073I-292J273D01*
G02X172540Y53173I1096J1027D01*
G03X172550Y53735I-280J286D01*
G02X174601Y53753I1017J965D01*
G03X174622Y53192I295J-270D01*
G02X174687Y51073I-1031J-1092D01*
G03Y50527I292J-273D01*
G02X174631Y48416I-1096J-1027D01*
G37*
G36*
G01X211469Y29667D02*
G03X211453Y29106I277J-289D01*
G02X209403I-1025J-956D01*
G03X209387Y29667I-293J272D01*
G02X209340Y31785I1041J1083D01*
G03X209334Y32342I-290J275D01*
G02X209361Y34482I1068J1057D01*
G03X209377Y35043I-277J289D01*
G02X211427I1025J956D01*
G03X211443Y34482I293J-272D01*
G02X211490Y32364I-1041J-1083D01*
G03X211496Y31807I290J-275D01*
G02X211469Y29667I-1068J-1057D01*
G37*
G36*
G01X174658D02*
G03X174642Y29106I277J-289D01*
G02X172592I-1025J-956D01*
G03X172576Y29667I-293J272D01*
G02X172529Y31785I1041J1083D01*
G03X172523Y32342I-290J275D01*
G02X172550Y34482I1068J1057D01*
G03X172566Y35043I-277J289D01*
G02X174616I1025J956D01*
G03X174632Y34482I293J-272D01*
G02X174679Y32364I-1041J-1083D01*
G03X174685Y31807I290J-275D01*
G02X174658Y29667I-1068J-1057D01*
G37*
G36*
G01X216547Y29461D02*
G03X216534Y28899I278J-288D01*
G02X214486Y28889I-1019J-963D01*
G03X214468Y29450I-293J271D01*
G02X214409Y31570I1034J1090D01*
G03Y32119I-291J274D01*
G02X214472Y34243I1093J1031D01*
G03X214493Y34804I-274J291D01*
G02X216543Y34783I1035J946D01*
G03X216553Y34222I290J-275D01*
G02X216595Y32119I-1051J-1073D01*
G03Y31570I291J-275D01*
G02X216547Y29461I-1093J-1030D01*
G37*
G36*
G01X179736D02*
G03X179723Y28899I278J-288D01*
G02X177675Y28889I-1019J-963D01*
G03X177657Y29450I-293J271D01*
G02X177598Y31570I1034J1090D01*
G03Y32119I-291J274D01*
G02X177661Y34243I1093J1031D01*
G03X177682Y34804I-274J291D01*
G02X179732Y34783I1035J946D01*
G03X179742Y34222I290J-275D01*
G02X179784Y32119I-1051J-1073D01*
G03Y31570I291J-275D01*
G02X179736Y29461I-1093J-1030D01*
G37*
G36*
G01X231692Y13817D02*
G03X231706Y13234I281J-285D01*
G02X229706I-1000J-1120D01*
G03X229720Y13817I-267J298D01*
G02X231692I986J997D01*
G37*
G36*
G01X224999D02*
G03X225013Y13234I281J-285D01*
G02X223013I-1000J-1120D01*
G03X223027Y13817I-267J298D01*
G02X224999I986J997D01*
G37*
G36*
G01X207567D02*
G03X207581Y13234I281J-285D01*
G02X205581I-1000J-1120D01*
G03X205595Y13817I-267J298D01*
G02X207567I986J997D01*
G37*
G36*
G01X201281Y13778D02*
G03X201308Y13217I298J-267D01*
G02X199227Y13177I-1020J-1103D01*
G03X199231Y13738I-283J283D01*
G02X201281Y13778I1006J976D01*
G37*
G36*
G01X194881Y13817D02*
G03X194895Y13234I281J-285D01*
G02X192895I-1000J-1120D01*
G03X192909Y13817I-267J298D01*
G02X194881I986J997D01*
G37*
G36*
G01X188188D02*
G03X188202Y13234I281J-285D01*
G02X186202I-1000J-1120D01*
G03X186216Y13817I-267J298D01*
G02X188188I986J997D01*
G37*
G36*
G01X216442Y10743D02*
G03X216423Y10136I251J-312D01*
G02X214551Y10151I-944J-1036D01*
G03X214542Y10759I-265J300D01*
G02X214406Y12941I960J1155D01*
G03Y13487I-292J273D01*
G02X214461Y15597I1096J1027D01*
G03X214477Y16158I-277J289D01*
G02X216527I1025J956D01*
G03X216543Y15597I293J-272D01*
G02X216598Y13487I-1041J-1083D01*
G03Y12941I292J-273D01*
G02X216442Y10743I-1096J-1027D01*
G37*
G36*
G01X179631D02*
G03X179612Y10136I251J-312D01*
G02X177740Y10151I-944J-1036D01*
G03X177731Y10759I-265J300D01*
G02X177595Y12941I960J1155D01*
G03Y13487I-292J273D01*
G02X177650Y15597I1096J1027D01*
G03X177666Y16158I-277J289D01*
G02X179716I1025J956D01*
G03X179732Y15597I293J-272D01*
G02X179787Y13487I-1041J-1083D01*
G03Y12941I292J-273D01*
G02X179631Y10743I-1096J-1027D01*
G37*
G36*
G01X211442Y10616D02*
G03X211427Y10055I277J-288D01*
G02X209377I-1025J-957D01*
G03X209362Y10616I-292J273D01*
G02X209306Y12727I1040J1084D01*
G03Y13273I-292J273D01*
G02X209351Y15373I1096J1027D01*
G03X209361Y15935I-280J286D01*
G02X211412Y15953I1017J965D01*
G03X211433Y15392I295J-270D01*
G02X211498Y13273I-1031J-1092D01*
G03Y12727I292J-273D01*
G02X211442Y10616I-1096J-1027D01*
G37*
G36*
G01X174631D02*
G03X174616Y10055I277J-288D01*
G02X172566I-1025J-957D01*
G03X172551Y10616I-292J273D01*
G02X172495Y12727I1040J1084D01*
G03Y13273I-292J273D01*
G02X172540Y15373I1096J1027D01*
G03X172550Y15935I-280J286D01*
G02X174601Y15953I1017J965D01*
G03X174622Y15392I295J-270D01*
G02X174687Y13273I-1031J-1092D01*
G03Y12727I292J-273D01*
G02X174631Y10616I-1096J-1027D01*
G37*
G36*
G01X211469Y-8133D02*
G03X211453Y-8694I277J-289D01*
G02X209403I-1025J-956D01*
G03X209387Y-8133I-293J272D01*
G02X209340Y-6015I1041J1083D01*
G03X209334Y-5458I-290J275D01*
G02X209361Y-3318I1068J1057D01*
G03X209377Y-2757I-277J289D01*
G02X211427I1025J956D01*
G03X211443Y-3318I293J-272D01*
G02X211490Y-5436I-1041J-1083D01*
G03X211496Y-5993I290J-275D01*
G02X211469Y-8133I-1068J-1057D01*
G37*
G36*
G01X174658D02*
G03X174642Y-8694I277J-289D01*
G02X172592I-1025J-956D01*
G03X172576Y-8133I-293J272D01*
G02X172529Y-6015I1041J1083D01*
G03X172523Y-5458I-290J275D01*
G02X172550Y-3318I1068J1057D01*
G03X172566Y-2757I-277J289D01*
G02X174616I1025J956D01*
G03X174632Y-3318I293J-272D01*
G02X174679Y-5436I-1041J-1083D01*
G03X174685Y-5993I290J-275D01*
G02X174658Y-8133I-1068J-1057D01*
G37*
G36*
G01X216547Y-8339D02*
G03X216534Y-8901I278J-288D01*
G02X214486Y-8911I-1019J-963D01*
G03X214468Y-8350I-293J271D01*
G02X214409Y-6230I1034J1090D01*
G03Y-5681I-291J274D01*
G02X214472Y-3557I1093J1031D01*
G03X214493Y-2996I-274J291D01*
G02X216543Y-3017I1035J946D01*
G03X216553Y-3578I290J-275D01*
G02X216595Y-5681I-1051J-1073D01*
G03Y-6230I291J-274D01*
G02X216547Y-8339I-1093J-1030D01*
G37*
G36*
G01X179736D02*
G03X179723Y-8901I278J-288D01*
G02X177675Y-8911I-1019J-963D01*
G03X177657Y-8350I-293J271D01*
G02X177598Y-6230I1034J1090D01*
G03Y-5681I-291J274D01*
G02X177661Y-3557I1093J1031D01*
G03X177682Y-2996I-274J291D01*
G02X179732Y-3017I1035J946D01*
G03X179742Y-3578I290J-275D01*
G02X179784Y-5681I-1051J-1073D01*
G03Y-6230I291J-274D01*
G02X179736Y-8339I-1093J-1030D01*
G37*
G36*
G01X170776Y89387D02*
G03X170791Y88816I287J-278D01*
G02X168749I-1021J-1102D01*
G03X168764Y89387I-272J293D01*
G02X170776I1006J977D01*
G37*
G36*
G01X164470Y89378D02*
G03X164497Y88817I298J-267D01*
G02X162416Y88777I-1020J-1103D01*
G03X162420Y89338I-283J283D01*
G02X164470Y89378I1006J976D01*
G37*
G36*
G01X158070Y89417D02*
G03X158084Y88834I281J-285D01*
G02X156084I-1000J-1120D01*
G03X156098Y89417I-267J298D01*
G02X158070I986J997D01*
G37*
G36*
G01X151377D02*
G03X151391Y88834I281J-285D01*
G02X149391I-1000J-1120D01*
G03X149405Y89417I-267J298D01*
G02X151377I986J997D01*
G37*
G36*
G01X133945D02*
G03X133959Y88834I281J-285D01*
G02X131959I-1000J-1120D01*
G03X131973Y89417I-267J298D01*
G02X133945I986J997D01*
G37*
G36*
G01X127659Y89378D02*
G03X127686Y88817I298J-267D01*
G02X125605Y88777I-1020J-1103D01*
G03X125609Y89338I-283J283D01*
G02X127659Y89378I1006J976D01*
G37*
G36*
G01X142820Y86343D02*
G03X142801Y85736I251J-312D01*
G02X140929Y85751I-944J-1036D01*
G03X140920Y86359I-265J300D01*
G02X140784Y88541I960J1155D01*
G03Y89087I-292J273D01*
G02X140839Y91197I1096J1027D01*
G03X140855Y91758I-277J289D01*
G02X142905I1025J956D01*
G03X142921Y91197I293J-272D01*
G02X142976Y89087I-1041J-1083D01*
G03Y88541I292J-273D01*
G02X142820Y86343I-1096J-1027D01*
G37*
G36*
G01X137820Y86216D02*
G03X137805Y85655I277J-288D01*
G02X135755I-1025J-957D01*
G03X135740Y86216I-292J273D01*
G02X135684Y88327I1040J1084D01*
G03Y88873I-292J273D01*
G02X135729Y90973I1096J1027D01*
G03X135739Y91535I-280J286D01*
G02X137790Y91553I1017J965D01*
G03X137811Y90992I295J-270D01*
G02X137876Y88873I-1031J-1092D01*
G03Y88327I292J-273D01*
G02X137820Y86216I-1096J-1027D01*
G37*
G36*
G01X137847Y67467D02*
G03X137831Y66906I277J-289D01*
G02X135781I-1025J-956D01*
G03X135765Y67467I-293J272D01*
G02X135718Y69585I1041J1083D01*
G03X135712Y70142I-290J275D01*
G02X135739Y72282I1068J1057D01*
G03X135755Y72843I-277J289D01*
G02X137805I1025J956D01*
G03X137821Y72282I293J-272D01*
G02X137868Y70164I-1041J-1083D01*
G03X137874Y69607I290J-275D01*
G02X137847Y67467I-1068J-1057D01*
G37*
G36*
G01X142925Y67261D02*
G03X142912Y66699I278J-288D01*
G02X140864Y66689I-1019J-963D01*
G03X140846Y67250I-293J271D01*
G02X140787Y69370I1034J1090D01*
G03Y69919I-291J274D01*
G02X140850Y72043I1093J1031D01*
G03X140871Y72604I-274J291D01*
G02X142921Y72583I1035J946D01*
G03X142931Y72022I290J-275D01*
G02X142973Y69919I-1051J-1073D01*
G03Y69370I291J-274D01*
G02X142925Y67261I-1093J-1030D01*
G37*
G36*
G01X170756Y51617D02*
G03X170770Y51034I281J-285D01*
G02X168770I-1000J-1120D01*
G03X168784Y51617I-267J298D01*
G02X170756I986J997D01*
G37*
G36*
G01X164470Y51578D02*
G03X164497Y51017I298J-267D01*
G02X162416Y50977I-1020J-1103D01*
G03X162420Y51538I-283J283D01*
G02X164470Y51578I1006J976D01*
G37*
G36*
G01X158070Y51617D02*
G03X158084Y51034I281J-285D01*
G02X156084I-1000J-1120D01*
G03X156098Y51617I-267J298D01*
G02X158070I986J997D01*
G37*
G36*
G01X151377D02*
G03X151391Y51034I281J-285D01*
G02X149391I-1000J-1120D01*
G03X149405Y51617I-267J298D01*
G02X151377I986J997D01*
G37*
G36*
G01X133945D02*
G03X133959Y51034I281J-285D01*
G02X131959I-1000J-1120D01*
G03X131973Y51617I-267J298D01*
G02X133945I986J997D01*
G37*
G36*
G01X127659Y51578D02*
G03X127686Y51017I298J-267D01*
G02X125605Y50977I-1020J-1103D01*
G03X125609Y51538I-283J283D01*
G02X127659Y51578I1006J976D01*
G37*
G36*
G01X142820Y48543D02*
G03X142801Y47936I251J-312D01*
G02X140929Y47951I-944J-1036D01*
G03X140920Y48559I-265J300D01*
G02X140784Y50741I960J1155D01*
G03Y51287I-292J273D01*
G02X140839Y53397I1096J1027D01*
G03X140855Y53958I-277J289D01*
G02X142905I1025J956D01*
G03X142921Y53397I293J-272D01*
G02X142976Y51287I-1041J-1083D01*
G03Y50741I292J-273D01*
G02X142820Y48543I-1096J-1027D01*
G37*
G36*
G01X137820Y48416D02*
G03X137805Y47855I277J-288D01*
G02X135755I-1025J-957D01*
G03X135740Y48416I-292J273D01*
G02X135684Y50527I1040J1084D01*
G03Y51073I-292J273D01*
G02X135729Y53173I1096J1027D01*
G03X135739Y53735I-280J286D01*
G02X137790Y53753I1017J965D01*
G03X137811Y53192I295J-270D01*
G02X137876Y51073I-1031J-1092D01*
G03Y50527I292J-273D01*
G02X137820Y48416I-1096J-1027D01*
G37*
G36*
G01X116770Y71668D02*
G02X115465Y71581I-570J-1281D01*
G03X115408Y72291I-210J340D01*
G02X116732Y72380I572J1389D01*
G03X116770Y71668I200J-346D01*
G37*
G36*
G01X137847Y29667D02*
G03X137831Y29106I277J-289D01*
G02X135781I-1025J-956D01*
G03X135765Y29667I-293J272D01*
G02X135718Y31785I1041J1083D01*
G03X135712Y32342I-290J275D01*
G02X135739Y34482I1068J1057D01*
G03X135755Y35043I-277J289D01*
G02X137805I1025J956D01*
G03X137821Y34482I293J-272D01*
G02X137868Y32364I-1041J-1083D01*
G03X137874Y31807I290J-275D01*
G02X137847Y29667I-1068J-1057D01*
G37*
G36*
G01X142925Y29461D02*
G03X142912Y28899I278J-288D01*
G02X140864Y28889I-1019J-963D01*
G03X140846Y29450I-293J271D01*
G02X140787Y31570I1034J1090D01*
G03Y32119I-291J274D01*
G02X140850Y34243I1093J1031D01*
G03X140871Y34804I-274J291D01*
G02X142921Y34783I1035J946D01*
G03X142931Y34222I290J-275D01*
G02X142973Y32119I-1051J-1073D01*
G03Y31570I291J-275D01*
G02X142925Y29461I-1093J-1030D01*
G37*
G36*
G01X170756Y13817D02*
G03X170770Y13234I281J-285D01*
G02X168770I-1000J-1120D01*
G03X168784Y13817I-267J298D01*
G02X170756I986J997D01*
G37*
G36*
G01X164470Y13778D02*
G03X164497Y13217I298J-267D01*
G02X162416Y13177I-1020J-1103D01*
G03X162420Y13738I-283J283D01*
G02X164470Y13778I1006J976D01*
G37*
G36*
G01X158070Y13817D02*
G03X158084Y13234I281J-285D01*
G02X156084I-1000J-1120D01*
G03X156098Y13817I-267J298D01*
G02X158070I986J997D01*
G37*
G36*
G01X151377D02*
G03X151391Y13234I281J-285D01*
G02X149391I-1000J-1120D01*
G03X149405Y13817I-267J298D01*
G02X151377I986J997D01*
G37*
G36*
G01X133945D02*
G03X133959Y13234I281J-285D01*
G02X131959I-1000J-1120D01*
G03X131973Y13817I-267J298D01*
G02X133945I986J997D01*
G37*
G36*
G01X127659Y13778D02*
G03X127686Y13217I298J-267D01*
G02X125605Y13177I-1020J-1103D01*
G03X125609Y13738I-283J283D01*
G02X127659Y13778I1006J976D01*
G37*
G36*
G01X142820Y10743D02*
G03X142801Y10136I251J-312D01*
G02X140929Y10151I-944J-1036D01*
G03X140920Y10759I-265J300D01*
G02X140784Y12941I960J1155D01*
G03Y13487I-292J273D01*
G02X140839Y15597I1096J1027D01*
G03X140855Y16158I-277J289D01*
G02X142905I1025J956D01*
G03X142921Y15597I293J-272D01*
G02X142976Y13487I-1041J-1083D01*
G03Y12941I292J-273D01*
G02X142820Y10743I-1096J-1027D01*
G37*
G36*
G01X137820Y10616D02*
G03X137805Y10055I277J-288D01*
G02X135755I-1025J-957D01*
G03X135740Y10616I-292J273D01*
G02X135684Y12727I1040J1084D01*
G03Y13273I-292J273D01*
G02X135729Y15373I1096J1027D01*
G03X135739Y15935I-280J286D01*
G02X137790Y15953I1017J965D01*
G03X137811Y15392I295J-270D01*
G02X137876Y13273I-1031J-1092D01*
G03Y12727I292J-273D01*
G02X137820Y10616I-1096J-1027D01*
G37*
G36*
G01X115148Y5044D02*
G03X115127Y4493I279J-287D01*
G02X112952Y4576I-1127J-993D01*
G03X112973Y5127I-279J287D01*
G02X115148Y5044I1127J993D01*
G37*
G36*
G01X137847Y-8133D02*
G03X137831Y-8694I277J-289D01*
G02X135781I-1025J-956D01*
G03X135765Y-8133I-293J272D01*
G02X135718Y-6015I1041J1083D01*
G03X135712Y-5458I-290J275D01*
G02X135739Y-3318I1068J1057D01*
G03X135755Y-2757I-277J289D01*
G02X137805I1025J956D01*
G03X137821Y-3318I293J-272D01*
G02X137868Y-5436I-1041J-1083D01*
G03X137874Y-5993I290J-275D01*
G02X137847Y-8133I-1068J-1057D01*
G37*
G36*
G01X142925Y-8339D02*
G03X142912Y-8901I278J-288D01*
G02X140864Y-8911I-1019J-963D01*
G03X140846Y-8350I-293J271D01*
G02X140787Y-6230I1034J1090D01*
G03Y-5681I-291J274D01*
G02X140850Y-3557I1093J1031D01*
G03X140871Y-2996I-274J291D01*
G02X142921Y-3017I1035J946D01*
G03X142931Y-3578I290J-275D01*
G02X142973Y-5681I-1051J-1073D01*
G03Y-6230I291J-274D01*
G02X142925Y-8339I-1093J-1030D01*
G37*
G36*
G01X100054Y84670D02*
G02X98641Y83270I86J-1500D01*
G03X98022Y83630I-399J26D01*
G02X99700Y85293I-3339J5048D01*
G03X100054Y84670I331J-224D01*
G37*
G36*
G01X96484Y77755D02*
G02X93632Y77689I-1443J696D01*
G03X92932Y77695I-352J-191D01*
G02X92945Y79243I-1396J786D01*
G03X93645Y79237I352J191D01*
G02X96472Y79171I1396J-786D01*
G03X97190Y79177I358J179D01*
G02X97202Y77761I1443J-696D01*
G03X96484Y77755I-358J-179D01*
G37*
G36*
G01X70101Y-2447D02*
G03X69547I-277J-288D01*
G02X67616Y-414I-973J1009D01*
G03X67624Y162I-274J292D01*
G02X69584Y2168I987J996D01*
G03X70138I277J288D01*
G02X72084I973J-1010D01*
G03X72638I277J288D01*
G02X74625Y2126I973J-1010D01*
G03X75210Y2133I289J276D01*
G02X77183Y146I1037J-943D01*
G03X77165Y-432I267J-298D01*
G02X75165Y-2398I-1000J-983D01*
G03X74590Y-2403I-285J-280D01*
G02X72601Y-2447I-1016J966D01*
G03X72047I-277J-288D01*
G02X70101I-973J1010D01*
G37*
G36*
G01X80729Y-12405D02*
G03X80175I-277J-288D01*
G02Y-10385I-973J1010D01*
G03X80729I277J288D01*
G02X82675I973J-1010D01*
G03X83229I277J288D01*
G02Y-12405I973J-1010D01*
G03X82675I-277J-288D01*
G02X80729I-973J1010D01*
G37*
G36*
G01X81211Y-17483D02*
G03X80589I-311J-252D01*
G02Y-15717I-1089J883D01*
G03X81211I311J252D01*
G02Y-17483I1089J-883D01*
G37*
G36*
G01X99328Y-10626D02*
G02X97720Y-11775I-226J-1384D01*
G03X97162Y-11343I-394J67D01*
G02X90822Y-10483I-2479J5521D01*
G03X90170Y-10745I-255J-308D01*
G02X88916Y-9191I-1393J159D01*
G03X89311Y-8609I40J398D01*
G02X99101Y-9958I5372J2787D01*
G03X99328Y-10626I292J-273D01*
G37*
G36*
G01X72453Y-19271D02*
G02X72429Y-17664I-1281J785D01*
G03X73105Y-17654I335J219D01*
G02X73129Y-19261I1281J-785D01*
G03X72453Y-19271I-335J-219D01*
G37*
G36*
G01X118570Y384194D02*
G02X116059Y379642I59J-3001D01*
G02X115807Y385639I-59J3001D01*
G02X118364Y384493I1256J-622D01*
G02X118570Y384194I-2364J-1849D01*
G37*
G36*
G01X124461Y379637D02*
G03X124474Y380166I-293J272D01*
G02X124492Y382120I1150J966D01*
G03Y382646I-302J263D01*
G02X126756I1132J987D01*
G03Y382120I302J-263D01*
G02X126726Y380112I-1132J-987D01*
G03X126713Y379583I293J-272D01*
G02X126837Y379411I-1153J-962D01*
G03X127182Y379421I170J106D01*
G02X127368Y377713I1318J-721D01*
G03X126750Y377696I-302J-262D01*
G02X124461Y379637I-1187J920D01*
G37*
G36*
G01X121407Y373181D02*
G03X121446Y373762I-254J309D01*
G02X123366Y373635I1027J954D01*
G03X123327Y373054I254J-309D01*
G02X121407Y373181I-1027J-954D01*
G37*
G36*
G01X127135Y345549D02*
G03X126602Y345531I-256J-307D01*
G02X124461Y347637I-1039J1085D01*
G03X124474Y348166I-293J272D01*
G02X124492Y350120I1150J966D01*
G03Y350646I-302J263D01*
G02X126756I1132J987D01*
G03Y350120I302J-263D01*
G02X126608Y347998I-1132J-987D01*
G03X126600Y347702I131J-152D01*
G02X126649Y347653I-1037J-1086D01*
G03X126947Y347663I145J138D01*
G02X127135Y345549I1153J-963D01*
G37*
G36*
G01X128750Y371148D02*
G02X128552Y372417I-1330J442D01*
G03X129255Y372527I323J236D01*
G02X129453Y371258I1330J-442D01*
G03X128750Y371148I-323J-236D01*
G37*
G36*
G01X113766Y367078D02*
G02X112134Y367622I-1166J-778D01*
G03X112334Y368222I-133J378D01*
G02X113966Y367678I1166J778D01*
G03X113766Y367078I133J-378D01*
G37*
G36*
G01X114446Y347320D02*
G03X114504Y348041I-142J374D01*
G02X115807Y353639I1496J2602D01*
G02X118364Y352493I1256J-622D01*
G02X118723Y351907I-2363J-1851D01*
G02X118627Y346054I-715J-2916D01*
G03X118333Y345527I83J-392D01*
G02X118344Y343528I-2825J-1015D01*
G03X118795Y343004I378J-131D01*
G02X118511Y340331I255J-1379D01*
G03X118253Y340231I-77J-185D01*
G02X112923Y342986I-2717J1278D01*
G02X114446Y347320I2585J1526D01*
G37*
G36*
G01X127234Y313650D02*
G03X126679Y313611I-257J-306D01*
G02X124461Y315637I-1116J1005D01*
G03X124474Y316166I-293J272D01*
G02X124492Y318120I1150J966D01*
G03Y318646I-302J263D01*
G02X126756I1132J987D01*
G03Y318120I302J-263D01*
G02X126608Y315998I-1132J-987D01*
G03X126600Y315702I131J-152D01*
G02X126661Y315641I-1031J-1092D01*
G03X126971Y315663I146J137D01*
G02X127234Y313650I1229J-863D01*
G37*
G36*
G01X122105Y308776D02*
G03X121926Y309351I-341J209D01*
G02X123689Y309901I567J1282D01*
G03X123868Y309326I341J-209D01*
G02X122105Y308776I-567J-1282D01*
G37*
G36*
G01X114446Y315320D02*
G03X114504Y316041I-142J374D01*
G02X115807Y321639I1496J2602D01*
G02X118364Y320493I1256J-622D01*
G02X118723Y319907I-2363J-1851D01*
G02X118627Y314054I-715J-2916D01*
G03X118333Y313527I83J-392D01*
G02X118121Y311034I-2825J-1015D01*
G02X112923Y310986I-2585J-1526D01*
G02X114446Y315320I2585J1526D01*
G37*
G36*
G01X127152Y281524D02*
G03X126598Y281527I-279J-287D01*
G02X124461Y283637I-1035J1089D01*
G03X124474Y284166I-293J272D01*
G02X124492Y286120I1150J966D01*
G03Y286646I-302J263D01*
G02X126756I1132J987D01*
G03Y286120I302J-263D01*
G02X126726Y284112I-1132J-987D01*
G03X126713Y283583I293J-272D01*
G02X126732Y283559I-1168J-944D01*
G03X127042Y283557I156J125D01*
G02X127152Y281524I1158J-957D01*
G37*
G36*
G01X128370Y338700D02*
G02X127731Y340196I-1370J299D01*
G03X128330Y340452I208J341D01*
G02X128969Y338956I1370J-299D01*
G03X128370Y338700I-208J-341D01*
G37*
G36*
G01X128755Y306876D02*
G02X128442Y308539I-1255J625D01*
G03X129069Y308657I269J296D01*
G02X129382Y306994I1255J-625D01*
G03X128755Y306876I-269J-296D01*
G37*
G36*
G01X114446Y283320D02*
G03X114504Y284041I-142J374D01*
G02X115807Y289639I1496J2602D01*
G02X118364Y288493I1256J-622D01*
G02X118723Y287907I-2363J-1851D01*
G02X118627Y282054I-715J-2916D01*
G03X118333Y281527I83J-392D01*
G02X118121Y279034I-2825J-1015D01*
G02X112923Y278986I-2585J-1526D01*
G02X114446Y283320I2585J1526D01*
G37*
G36*
G01X127193Y249585D02*
G03X126639Y249568I-268J-297D01*
G02X124461Y251637I-1076J1048D01*
G03X124474Y252166I-293J272D01*
G02X124492Y254120I1150J966D01*
G03Y254646I-302J263D01*
G02X126756I1132J987D01*
G03Y254120I302J-263D01*
G02X126608Y251998I-1132J-987D01*
G03X126600Y251702I131J-152D01*
G02X126696Y251602I-1034J-1089D01*
G03X127006Y251612I151J131D01*
G02X127193Y249585I1194J-912D01*
G37*
G36*
G01X123380Y245914D02*
G03X123517Y245349I336J-218D01*
G02X121643Y244894I-697J-1216D01*
G03X121506Y245459I-336J218D01*
G02X123380Y245914I697J1216D01*
G37*
G36*
G01X118576Y250043D02*
G03X118280Y249501I75J-393D01*
G02X118110Y246898I-2783J-1125D01*
G02X112912Y246850I-2585J-1526D01*
G02X114575Y251233I2585J1526D01*
G03X114634Y251970I-123J381D01*
G02X115807Y257639I1366J2673D01*
G02X118364Y256493I1256J-622D01*
G02X118723Y255907I-2363J-1851D01*
G02X118576Y250043I-715J-2916D01*
G37*
G36*
G01X123666Y277219D02*
G02X121957Y276796I-592J-1271D01*
G03X121808Y277400I-318J242D01*
G02X123517Y277823I592J1271D01*
G03X123666Y277219I318J-242D01*
G37*
G36*
G01X128755Y274876D02*
G02X128442Y276539I-1255J625D01*
G03X129069Y276657I269J296D01*
G02X129382Y274994I1255J-625D01*
G03X128755Y274876I-269J-296D01*
G37*
G36*
G01Y242876D02*
G02X128442Y244539I-1255J625D01*
G03X129069Y244657I269J296D01*
G02X129382Y242994I1255J-625D01*
G03X128755Y242876I-269J-296D01*
G37*
G36*
G01X127368Y217713D02*
G03X126750Y217696I-302J-262D01*
G02X124461Y219637I-1187J920D01*
G03X124474Y220166I-293J272D01*
G02X124492Y222120I1150J966D01*
G03Y222646I-302J263D01*
G02X126756I1132J987D01*
G03Y222120I302J-263D01*
G02X126726Y220112I-1132J-987D01*
G03X126713Y219583I293J-272D01*
G02X126837Y219411I-1153J-962D01*
G03X127182Y219421I170J106D01*
G02X127368Y217713I1318J-721D01*
G37*
G36*
G01X114889Y219449D02*
G03X115183Y219976I-83J392D01*
G02X115116Y220186I2824J1017D01*
G02X115798Y225898I1194J2754D01*
G02X118452Y225043I1282J-568D01*
G02X119202Y223745I-2142J-2103D01*
G02X118627Y218054I-1194J-2754D01*
G03X118333Y217527I83J-392D01*
G02X118121Y215034I-2825J-1015D01*
G02X112923Y214986I-2585J-1526D01*
G02X114889Y219449I2585J1526D01*
G37*
G36*
G01X129498Y213783D02*
G03X129993Y213395I400J1D01*
G02X129393Y210985I331J-1362D01*
G03X128822Y210945I-266J-299D01*
G02X126588Y211074I-1068J908D01*
G03X125954Y211114I-332J-222D01*
G02X123725Y211260I-1059J919D01*
G02X125461Y213316I-1183J2759D01*
G02X126061Y212812I-566J-1283D01*
G03X126695Y212772I332J222D01*
G02X126725Y212805I1052J-926D01*
G03X126688Y213108I-147J136D01*
G02X126510Y213495I218J335D01*
G03X126311Y215365I-3968J523D01*
G02X126647Y215898I376J135D01*
G01X127499D01*
X129498Y213899D01*
Y213783D01*
G37*
G36*
G01X109073Y405734D02*
G02X108570Y407543I-1502J557D01*
G03X109182Y407686I250J313D01*
G02X109687Y408267I1270J-594D01*
G03X109679Y408943I-218J335D01*
G02X109660Y411659I840J1364D01*
G03X109596Y412368I-214J338D01*
G02X111058Y412500I603J1484D01*
G03X111122Y411791I214J-338D01*
G02X111302Y408909I-603J-1484D01*
G03X111265Y408234I195J-349D01*
G02X109671Y405928I-813J-1142D01*
G03X109073Y405734I-223J-332D01*
G37*
G36*
G01X108874Y392919D02*
G03X108274I-300J-265D01*
G02Y394777I-1050J929D01*
G03X108874I300J265D01*
G02Y392919I1050J-929D01*
G37*
G36*
G01X108013Y214026D02*
G02X105406Y209103I-313J-2986D01*
G03X104796Y209104I-305J-258D01*
G02X104801Y212984I-2289J1943D01*
G03X105411Y212983I305J258D01*
G02X106167Y213621I2288J-1944D01*
G03X106126Y214330I-204J344D01*
G02X107753Y214687I572J1280D01*
G03X108013Y214026I301J-263D01*
G37*
G36*
G01X656071Y613089D02*
G03Y612511I277J-289D01*
G02X654129I-971J-1011D01*
G03Y613089I-277J289D01*
G02X656071I971J1011D01*
G37*
G36*
G01X648222Y592647D02*
G03X648520Y592165I389J-93D01*
G02X646718Y591047I-340J-1463D01*
G03X646420Y591529I-389J93D01*
G02X645300Y592638I340J1463D01*
G03X644825Y592934I-389J-95D01*
G02X645960Y594754I-325J1466D01*
G03X646435Y594458I389J95D01*
G02X648222Y592647I325J-1466D01*
G37*
G36*
G01X629077Y611362D02*
G02X628127Y613414I-1372J611D01*
G03X628605Y613635I113J384D01*
G02X630020Y614525I1372J-611D01*
G03X630391Y615101I12J400D01*
G02X631698Y614258I1350J658D01*
G03X631327Y613682I-12J-400D01*
G02X629555Y611583I-1350J-658D01*
G03X629077Y611362I-113J-384D01*
G37*
G36*
G01X606831Y603785D02*
G02Y605213I-1321J714D01*
G03X607535I352J191D01*
G02X610178I1321J-714D01*
G03X610881I352J190D01*
G02X613524I1321J-714D01*
G03X614228I352J191D01*
G02Y603785I1321J-714D01*
G03X613524I-352J-191D01*
G02X610881I-1321J714D01*
G03X610178I-352J-190D01*
G02X607535I-1321J714D01*
G03X606831I-352J-191D01*
G37*
G36*
G01Y592885D02*
G02Y594313I-1321J714D01*
G03X607535I352J191D01*
G02X610178I1321J-714D01*
G03X610881I352J190D01*
G02X613524I1321J-714D01*
G03X614228I352J191D01*
G02X616648Y594623I1321J-714D01*
G03X617218Y594608I292J273D01*
G02X617219Y592591I974J-1008D01*
G03X616648Y592576I-278J-288D01*
G02X614228Y592885I-1099J1023D01*
G03X613524I-352J-191D01*
G02X610881I-1321J714D01*
G03X610178I-352J-190D01*
G02X607535I-1321J714D01*
G03X606831I-352J-191D01*
G37*
G36*
G01X651229Y573317D02*
G03X650716Y573294I-243J-318D01*
G02X648604Y575427I-1015J1107D01*
G03Y575973I-292J273D01*
G02X650658Y578157I1096J1027D01*
G03X651171Y578159I255J308D01*
G02X653272Y576024I969J-1148D01*
G03Y575498I302J-263D01*
G02X651229Y573317I-1132J-987D01*
G37*
G36*
G01X646615Y562377D02*
G03X645985I-315J-246D01*
G02Y564223I-1185J923D01*
G03X646615I315J246D01*
G02X648985I1185J-923D01*
G03X649615I315J246D01*
G02X651985I1185J-923D01*
G03X652615I315J246D01*
G02Y562377I1185J-923D01*
G03X651985I-315J-246D01*
G02X649615I-1185J923D01*
G03X648985I-315J-246D01*
G02X646615I-1185J923D01*
G37*
G36*
G01X652889Y584968D02*
G02X651662Y585549I-1138J-818D01*
G03X651961Y586182I-25J399D01*
G02X653188Y585601I1138J818D01*
G03X652889Y584968I25J-399D01*
G37*
G36*
G01X576233Y606267D02*
G03X576217Y605706I277J-289D01*
G02X574167I-1025J-956D01*
G03X574151Y606267I-293J272D01*
G02X574104Y608385I1041J1083D01*
G03X574098Y608942I-290J275D01*
G02X574125Y611082I1068J1057D01*
G03X574141Y611643I-277J289D01*
G02X576191I1025J956D01*
G03X576207Y611082I293J-272D01*
G02X576254Y608964I-1041J-1083D01*
G03X576260Y608407I290J-275D01*
G02X576233Y606267I-1068J-1057D01*
G37*
G36*
G01X581311Y606061D02*
G03X581298Y605499I278J-288D01*
G02X579250Y605489I-1019J-963D01*
G03X579232Y606050I-293J271D01*
G02X579173Y608170I1034J1090D01*
G03Y608719I-291J274D01*
G02X579236Y610843I1093J1031D01*
G03X579257Y611404I-274J291D01*
G02X581307Y611383I1035J946D01*
G03X581317Y610822I290J-275D01*
G02X581359Y608719I-1051J-1073D01*
G03Y608170I291J-274D01*
G02X581311Y606061I-1093J-1030D01*
G37*
G36*
G01X544500D02*
G03X544487Y605499I278J-288D01*
G02X542439Y605489I-1019J-963D01*
G03X542421Y606050I-293J271D01*
G02X542362Y608170I1034J1090D01*
G03Y608719I-291J274D01*
G02X542425Y610843I1093J1031D01*
G03X542446Y611404I-274J291D01*
G02X544496Y611383I1035J946D01*
G03X544506Y610822I290J-275D01*
G02X544548Y608719I-1051J-1073D01*
G03Y608170I291J-274D01*
G02X544500Y606061I-1093J-1030D01*
G37*
G36*
G01X603485Y611943D02*
G02Y613371I-1322J714D01*
G03X604188I351J190D01*
G02X606831I1322J-714D01*
G03X607535I352J191D01*
G02X610178I1321J-714D01*
G03X610881I352J190D01*
G02X613524I1321J-714D01*
G03X614228I352J191D01*
G02Y611943I1321J-714D01*
G03X613524I-352J-191D01*
G02X610881I-1321J714D01*
G03X610178I-352J-190D01*
G02X607535I-1321J714D01*
G03X606831I-352J-191D01*
G02X604188I-1321J714D01*
G03X603485I-352J-190D01*
G37*
G36*
G01X596456Y590417D02*
G03X596470Y589834I281J-285D01*
G02X594470I-1000J-1120D01*
G03X594484Y590417I-267J298D01*
G02X596456I986J997D01*
G37*
G36*
G01X589763D02*
G03X589777Y589834I281J-285D01*
G02X587777I-1000J-1120D01*
G03X587791Y590417I-267J298D01*
G02X589763I986J997D01*
G37*
G36*
G01X572331D02*
G03X572345Y589834I281J-285D01*
G02X570345I-1000J-1120D01*
G03X570359Y590417I-267J298D01*
G02X572331I986J997D01*
G37*
G36*
G01X559645D02*
G03X559659Y589834I281J-285D01*
G02X557659I-1000J-1120D01*
G03X557673Y590417I-267J298D01*
G02X559645I986J997D01*
G37*
G36*
G01X552952D02*
G03X552966Y589834I281J-285D01*
G02X550966I-1000J-1120D01*
G03X550980Y590417I-267J298D01*
G02X552952I986J997D01*
G37*
G36*
G01X581206Y587343D02*
G03X581187Y586736I251J-312D01*
G02X579315Y586751I-944J-1036D01*
G03X579306Y587359I-265J300D01*
G02X579170Y589541I960J1155D01*
G03Y590087I-292J273D01*
G02X579225Y592197I1096J1027D01*
G03X579241Y592758I-277J289D01*
G02X581291I1025J956D01*
G03X581307Y592197I293J-272D01*
G02X581362Y590087I-1041J-1083D01*
G03Y589541I292J-273D01*
G02X581206Y587343I-1096J-1027D01*
G37*
G36*
G01X544395D02*
G03X544376Y586736I251J-312D01*
G02X542504Y586751I-944J-1036D01*
G03X542495Y587359I-265J300D01*
G02X542359Y589541I960J1155D01*
G03Y590087I-292J273D01*
G02X542414Y592197I1096J1027D01*
G03X542430Y592758I-277J289D01*
G02X544480I1025J956D01*
G03X544496Y592197I293J-272D01*
G02X544551Y590087I-1041J-1083D01*
G03Y589541I292J-273D01*
G02X544395Y587343I-1096J-1027D01*
G37*
G36*
G01X576206Y587216D02*
G03X576191Y586655I277J-288D01*
G02X574141I-1025J-957D01*
G03X574126Y587216I-292J273D01*
G02X574070Y589327I1040J1084D01*
G03Y589873I-292J273D01*
G02X574115Y591973I1096J1027D01*
G03X574125Y592535I-280J286D01*
G02X576176Y592553I1017J965D01*
G03X576197Y591992I295J-270D01*
G02X576262Y589873I-1031J-1092D01*
G03Y589327I292J-273D01*
G02X576206Y587216I-1096J-1027D01*
G37*
G36*
G01X576233Y568467D02*
G03X576217Y567906I277J-289D01*
G02X574167I-1025J-956D01*
G03X574151Y568467I-293J272D01*
G02X574104Y570585I1041J1083D01*
G03X574098Y571142I-290J275D01*
G02X574125Y573282I1068J1057D01*
G03X574141Y573843I-277J289D01*
G02X576191I1025J956D01*
G03X576207Y573282I293J-272D01*
G02X576254Y571164I-1041J-1083D01*
G03X576260Y570607I290J-275D01*
G02X576233Y568467I-1068J-1057D01*
G37*
G36*
G01X581311Y568261D02*
G03X581298Y567699I278J-288D01*
G02X579250Y567689I-1019J-963D01*
G03X579232Y568250I-293J271D01*
G02X579173Y570370I1034J1090D01*
G03Y570919I-291J274D01*
G02X579236Y573043I1093J1031D01*
G03X579257Y573604I-274J291D01*
G02X581307Y573583I1035J946D01*
G03X581317Y573022I290J-275D01*
G02X581359Y570919I-1051J-1073D01*
G03Y570370I291J-274D01*
G02X581311Y568261I-1093J-1030D01*
G37*
G36*
G01X544500D02*
G03X544487Y567699I278J-288D01*
G02X542439Y567689I-1019J-963D01*
G03X542421Y568250I-293J271D01*
G02X542362Y570370I1034J1090D01*
G03Y570919I-291J274D01*
G02X542425Y573043I1093J1031D01*
G03X542446Y573604I-274J291D01*
G02X544496Y573583I1035J946D01*
G03X544506Y573022I290J-275D01*
G02X544548Y570919I-1051J-1073D01*
G03Y570370I291J-274D01*
G02X544500Y568261I-1093J-1030D01*
G37*
G36*
G01X596456Y552617D02*
G03X596470Y552034I281J-285D01*
G02X594470I-1000J-1120D01*
G03X594484Y552617I-267J298D01*
G02X596456I986J997D01*
G37*
G36*
G01X589763D02*
G03X589777Y552034I281J-285D01*
G02X587777I-1000J-1120D01*
G03X587791Y552617I-267J298D01*
G02X589763I986J997D01*
G37*
G36*
G01X572331D02*
G03X572345Y552034I281J-285D01*
G02X570345I-1000J-1120D01*
G03X570359Y552617I-267J298D01*
G02X572331I986J997D01*
G37*
G36*
G01X559645D02*
G03X559659Y552034I281J-285D01*
G02X557659I-1000J-1120D01*
G03X557673Y552617I-267J298D01*
G02X559645I986J997D01*
G37*
G36*
G01X552952D02*
G03X552966Y552034I281J-285D01*
G02X550966I-1000J-1120D01*
G03X550980Y552617I-267J298D01*
G02X552952I986J997D01*
G37*
G36*
G01X581206Y549543D02*
G03X581187Y548936I251J-312D01*
G02X579315Y548951I-944J-1036D01*
G03X579306Y549559I-265J300D01*
G02X579170Y551741I960J1155D01*
G03Y552287I-292J273D01*
G02X579225Y554397I1096J1027D01*
G03X579241Y554958I-277J289D01*
G02X581291I1025J956D01*
G03X581307Y554397I293J-272D01*
G02X581362Y552287I-1041J-1083D01*
G03Y551741I292J-273D01*
G02X581206Y549543I-1096J-1027D01*
G37*
G36*
G01X544395D02*
G03X544376Y548936I251J-312D01*
G02X542504Y548951I-944J-1036D01*
G03X542495Y549559I-265J300D01*
G02X542359Y551741I960J1155D01*
G03Y552287I-292J273D01*
G02X542414Y554397I1096J1027D01*
G03X542430Y554958I-277J289D01*
G02X544480I1025J956D01*
G03X544496Y554397I293J-272D01*
G02X544551Y552287I-1041J-1083D01*
G03Y551741I292J-273D01*
G02X544395Y549543I-1096J-1027D01*
G37*
G36*
G01X576206Y549416D02*
G03X576191Y548855I277J-288D01*
G02X574141I-1025J-957D01*
G03X574126Y549416I-292J273D01*
G02X574070Y551527I1040J1084D01*
G03Y552073I-292J273D01*
G02X574115Y554173I1096J1027D01*
G03X574125Y554735I-280J286D01*
G02X576176Y554753I1017J965D01*
G03X576197Y554192I295J-270D01*
G02X576262Y552073I-1031J-1092D01*
G03Y551527I292J-273D01*
G02X576206Y549416I-1096J-1027D01*
G37*
G36*
G01X576233Y530667D02*
G03X576217Y530106I277J-289D01*
G02X574167I-1025J-956D01*
G03X574151Y530667I-293J272D01*
G02X574104Y532785I1041J1083D01*
G03X574098Y533342I-290J275D01*
G02X574125Y535482I1068J1057D01*
G03X574141Y536043I-277J289D01*
G02X576191I1025J956D01*
G03X576207Y535482I293J-272D01*
G02X576254Y533364I-1041J-1083D01*
G03X576260Y532807I290J-275D01*
G02X576233Y530667I-1068J-1057D01*
G37*
G36*
G01X581311Y530461D02*
G03X581298Y529899I278J-288D01*
G02X579250Y529889I-1019J-963D01*
G03X579232Y530450I-293J271D01*
G02X579173Y532570I1034J1090D01*
G03Y533119I-291J274D01*
G02X579236Y535243I1093J1031D01*
G03X579257Y535804I-274J291D01*
G02X581307Y535783I1035J946D01*
G03X581317Y535222I290J-275D01*
G02X581359Y533119I-1051J-1073D01*
G03Y532570I291J-274D01*
G02X581311Y530461I-1093J-1030D01*
G37*
G36*
G01X544500D02*
G03X544487Y529899I278J-288D01*
G02X542439Y529889I-1019J-963D01*
G03X542421Y530450I-293J271D01*
G02X542362Y532570I1034J1090D01*
G03Y533119I-291J274D01*
G02X542425Y535243I1093J1031D01*
G03X542446Y535804I-274J291D01*
G02X544496Y535783I1035J946D01*
G03X544506Y535222I290J-275D01*
G02X544548Y533119I-1051J-1073D01*
G03Y532570I291J-274D01*
G02X544500Y530461I-1093J-1030D01*
G37*
G36*
G01X603485Y585043D02*
G02Y586471I-1322J714D01*
G03X604188I351J190D01*
G02X606831I1322J-714D01*
G03X607535I352J191D01*
G02X610178I1321J-714D01*
G03X610881I352J190D01*
G02X613524I1321J-714D01*
G03X614228I352J191D01*
G02Y585043I1321J-714D01*
G03X613524I-352J-191D01*
G02X610881I-1321J714D01*
G03X610178I-352J-190D01*
G02X607535I-1321J714D01*
G03X606831I-352J-191D01*
G02X604188I-1321J714D01*
G03X603485I-352J-190D01*
G37*
G36*
G01X617463Y575431D02*
G02X617088Y573582I829J-1131D01*
G03X616493Y573689I-344J-204D01*
G02X614228Y574143I-944J1168D01*
G03X613524I-352J-191D01*
G02X610881I-1321J714D01*
G03X610178I-352J-190D01*
G02X607535I-1321J714D01*
G03X606831I-352J-191D01*
G02X604188I-1321J714D01*
G03X603485I-352J-190D01*
G02Y575571I-1322J714D01*
G03X604188I351J190D01*
G02X606831I1322J-714D01*
G03X607535I352J191D01*
G02X610178I1321J-714D01*
G03X610881I352J190D01*
G02X613524I1321J-714D01*
G03X614228I352J191D01*
G02X616874Y575565I1321J-714D01*
G03X617463Y575431I353J188D01*
G37*
G36*
G01X603485Y565985D02*
G02Y567413I-1322J714D01*
G03X604188I351J190D01*
G02X606831I1322J-714D01*
G03X607535I352J191D01*
G02X610178I1321J-714D01*
G03X610881I352J190D01*
G02X613524I1321J-714D01*
G03X614228I352J191D01*
G02Y565985I1321J-714D01*
G03X613524I-352J-191D01*
G02X610881I-1321J714D01*
G03X610178I-352J-190D01*
G02X607535I-1321J714D01*
G03X606831I-352J-191D01*
G02X604188I-1321J714D01*
G03X603485I-352J-190D01*
G37*
G36*
G01X596456Y514817D02*
G03X596470Y514234I281J-285D01*
G02X594470I-1000J-1120D01*
G03X594484Y514817I-267J298D01*
G02X596456I986J997D01*
G37*
G36*
G01X589763D02*
G03X589777Y514234I281J-285D01*
G02X587777I-1000J-1120D01*
G03X587791Y514817I-267J298D01*
G02X589763I986J997D01*
G37*
G36*
G01X572331D02*
G03X572345Y514234I281J-285D01*
G02X570345I-1000J-1120D01*
G03X570359Y514817I-267J298D01*
G02X572331I986J997D01*
G37*
G36*
G01X559645D02*
G03X559659Y514234I281J-285D01*
G02X557659I-1000J-1120D01*
G03X557673Y514817I-267J298D01*
G02X559645I986J997D01*
G37*
G36*
G01X552952D02*
G03X552966Y514234I281J-285D01*
G02X550966I-1000J-1120D01*
G03X550980Y514817I-267J298D01*
G02X552952I986J997D01*
G37*
G36*
G01X581206Y511743D02*
G03X581187Y511136I251J-312D01*
G02X579315Y511151I-944J-1036D01*
G03X579306Y511759I-265J300D01*
G02X579170Y513941I960J1155D01*
G03Y514487I-292J273D01*
G02X579225Y516597I1096J1027D01*
G03X579241Y517158I-277J289D01*
G02X581291I1025J956D01*
G03X581307Y516597I293J-272D01*
G02X581362Y514487I-1041J-1083D01*
G03Y513941I292J-273D01*
G02X581206Y511743I-1096J-1027D01*
G37*
G36*
G01X544395D02*
G03X544376Y511136I251J-312D01*
G02X542504Y511151I-944J-1036D01*
G03X542495Y511759I-265J300D01*
G02X542359Y513941I960J1155D01*
G03Y514487I-292J273D01*
G02X542414Y516597I1096J1027D01*
G03X542430Y517158I-277J289D01*
G02X544480I1025J956D01*
G03X544496Y516597I293J-272D01*
G02X544551Y514487I-1041J-1083D01*
G03Y513941I292J-273D01*
G02X544395Y511743I-1096J-1027D01*
G37*
G36*
G01X576206Y511616D02*
G03X576191Y511055I277J-288D01*
G02X574141I-1025J-957D01*
G03X574126Y511616I-292J273D01*
G02X574070Y513727I1040J1084D01*
G03Y514273I-292J273D01*
G02X574115Y516373I1096J1027D01*
G03X574125Y516935I-280J286D01*
G02X576176Y516953I1017J965D01*
G03X576197Y516392I295J-270D01*
G02X576262Y514273I-1031J-1092D01*
G03Y513727I292J-273D01*
G02X576206Y511616I-1096J-1027D01*
G37*
G36*
G01X539422Y606267D02*
G03X539406Y605706I277J-289D01*
G02X537356I-1025J-956D01*
G03X537340Y606267I-293J272D01*
G02X537293Y608385I1041J1083D01*
G03X537287Y608942I-290J275D01*
G02X537314Y611082I1068J1057D01*
G03X537330Y611643I-277J289D01*
G02X539380I1025J956D01*
G03X539396Y611082I293J-272D01*
G02X539443Y608964I-1041J-1083D01*
G03X539449Y608407I290J-275D01*
G02X539422Y606267I-1068J-1057D01*
G37*
G36*
G01X502611D02*
G03X502595Y605706I277J-289D01*
G02X500545I-1025J-956D01*
G03X500529Y606267I-293J272D01*
G02X500482Y608385I1041J1083D01*
G03X500476Y608942I-290J275D01*
G02X500503Y611082I1068J1057D01*
G03X500519Y611643I-277J289D01*
G02X502569I1025J956D01*
G03X502585Y611082I293J-272D01*
G02X502632Y608964I-1041J-1083D01*
G03X502638Y608407I290J-275D01*
G02X502611Y606267I-1068J-1057D01*
G37*
G36*
G01X507689Y606061D02*
G03X507676Y605499I278J-288D01*
G02X505628Y605489I-1019J-963D01*
G03X505610Y606050I-293J271D01*
G02X505551Y608170I1034J1090D01*
G03Y608719I-291J274D01*
G02X505614Y610843I1093J1031D01*
G03X505635Y611404I-274J291D01*
G02X507685Y611383I1035J946D01*
G03X507695Y610822I290J-275D01*
G02X507737Y608719I-1051J-1073D01*
G03Y608170I291J-274D01*
G02X507689Y606061I-1093J-1030D01*
G37*
G36*
G01X535520Y590417D02*
G03X535534Y589834I281J-285D01*
G02X533534I-1000J-1120D01*
G03X533548Y590417I-267J298D01*
G02X535520I986J997D01*
G37*
G36*
G01X529234Y590378D02*
G03X529261Y589817I298J-267D01*
G02X527180Y589777I-1020J-1103D01*
G03X527184Y590338I-283J283D01*
G02X529234Y590378I1006J976D01*
G37*
G36*
G01X520848Y589834D02*
G03X520862Y590417I-267J298D01*
G02X522834I986J997D01*
G03X522848Y589834I281J-285D01*
G02X520848I-1000J-1120D01*
G37*
G36*
G01X516141Y590417D02*
G03X516155Y589834I281J-285D01*
G02X514155I-1000J-1120D01*
G03X514169Y590417I-267J298D01*
G02X516141I986J997D01*
G37*
G36*
G01X498709D02*
G03X498723Y589834I281J-285D01*
G02X496723I-1000J-1120D01*
G03X496737Y590417I-267J298D01*
G02X498709I986J997D01*
G37*
G36*
G01X492423Y590378D02*
G03X492450Y589817I298J-267D01*
G02X490369Y589777I-1020J-1103D01*
G03X490373Y590338I-283J283D01*
G02X492423Y590378I1006J976D01*
G37*
G36*
G01X486710Y589695D02*
G03X486461Y589191I130J-378D01*
G02X484623Y590158I-1424J-477D01*
G03X484898Y590648I-111J384D01*
G02X486710Y589695I1352J372D01*
G37*
G36*
G01X507584Y587343D02*
G03X507565Y586736I251J-312D01*
G02X505693Y586751I-944J-1036D01*
G03X505684Y587359I-265J300D01*
G02X505548Y589541I960J1155D01*
G03Y590087I-292J273D01*
G02X505603Y592197I1096J1027D01*
G03X505619Y592758I-277J289D01*
G02X507669I1025J956D01*
G03X507685Y592197I293J-272D01*
G02X507740Y590087I-1041J-1083D01*
G03Y589541I292J-273D01*
G02X507584Y587343I-1096J-1027D01*
G37*
G36*
G01X539395Y587216D02*
G03X539380Y586655I277J-288D01*
G02X537330I-1025J-957D01*
G03X537315Y587216I-292J273D01*
G02X537259Y589327I1040J1084D01*
G03Y589873I-292J273D01*
G02X537304Y591973I1096J1027D01*
G03X537314Y592535I-280J286D01*
G02X539365Y592553I1017J965D01*
G03X539386Y591992I295J-270D01*
G02X539451Y589873I-1031J-1092D01*
G03Y589327I292J-273D01*
G02X539395Y587216I-1096J-1027D01*
G37*
G36*
G01X502584D02*
G03X502569Y586655I277J-288D01*
G02X500519I-1025J-957D01*
G03X500504Y587216I-292J273D01*
G02X500448Y589327I1040J1084D01*
G03Y589873I-292J273D01*
G02X500493Y591973I1096J1027D01*
G03X500503Y592535I-280J286D01*
G02X502554Y592553I1017J965D01*
G03X502575Y591992I295J-270D01*
G02X502640Y589873I-1031J-1092D01*
G03Y589327I292J-273D01*
G02X502584Y587216I-1096J-1027D01*
G37*
G36*
G01X539422Y568467D02*
G03X539406Y567906I277J-289D01*
G02X537356I-1025J-956D01*
G03X537340Y568467I-293J272D01*
G02X537293Y570585I1041J1083D01*
G03X537287Y571142I-290J275D01*
G02X537314Y573282I1068J1057D01*
G03X537330Y573843I-277J289D01*
G02X539380I1025J956D01*
G03X539396Y573282I293J-272D01*
G02X539443Y571164I-1041J-1083D01*
G03X539449Y570607I290J-275D01*
G02X539422Y568467I-1068J-1057D01*
G37*
G36*
G01X502611D02*
G03X502595Y567906I277J-289D01*
G02X500545I-1025J-956D01*
G03X500529Y568467I-293J272D01*
G02X500482Y570585I1041J1083D01*
G03X500476Y571142I-290J275D01*
G02X500503Y573282I1068J1057D01*
G03X500519Y573843I-277J289D01*
G02X502569I1025J956D01*
G03X502585Y573282I293J-272D01*
G02X502632Y571164I-1041J-1083D01*
G03X502638Y570607I290J-275D01*
G02X502611Y568467I-1068J-1057D01*
G37*
G36*
G01X507689Y568261D02*
G03X507676Y567699I278J-288D01*
G02X505628Y567689I-1019J-963D01*
G03X505610Y568250I-293J271D01*
G02X505551Y570370I1034J1090D01*
G03Y570919I-291J274D01*
G02X505614Y573043I1093J1031D01*
G03X505635Y573604I-274J291D01*
G02X507685Y573583I1035J946D01*
G03X507695Y573022I290J-275D01*
G02X507737Y570919I-1051J-1073D01*
G03Y570370I291J-274D01*
G02X507689Y568261I-1093J-1030D01*
G37*
G36*
G01X535520Y552617D02*
G03X535534Y552034I281J-285D01*
G02X533534I-1000J-1120D01*
G03X533548Y552617I-267J298D01*
G02X535520I986J997D01*
G37*
G36*
G01X529234Y552578D02*
G03X529261Y552017I298J-267D01*
G02X527180Y551977I-1020J-1103D01*
G03X527184Y552538I-283J283D01*
G02X529234Y552578I1006J976D01*
G37*
G36*
G01X520848Y552034D02*
G03X520862Y552617I-267J298D01*
G02X522834I986J997D01*
G03X522848Y552034I281J-285D01*
G02X520848I-1000J-1120D01*
G37*
G36*
G01X516141Y552617D02*
G03X516155Y552034I281J-285D01*
G02X514155I-1000J-1120D01*
G03X514169Y552617I-267J298D01*
G02X516141I986J997D01*
G37*
G36*
G01X498709D02*
G03X498723Y552034I281J-285D01*
G02X496723I-1000J-1120D01*
G03X496737Y552617I-267J298D01*
G02X498709I986J997D01*
G37*
G36*
G01X492423Y552578D02*
G03X492450Y552017I298J-267D01*
G02X490369Y551977I-1020J-1103D01*
G03X490373Y552538I-283J283D01*
G02X492423Y552578I1006J976D01*
G37*
G36*
G01X484037Y552034D02*
G03X484051Y552617I-267J298D01*
G02X486023I986J997D01*
G03X486037Y552034I281J-285D01*
G02X484037I-1000J-1120D01*
G37*
G36*
G01X507584Y549543D02*
G03X507565Y548936I251J-312D01*
G02X505693Y548951I-944J-1036D01*
G03X505684Y549559I-265J300D01*
G02X505548Y551741I960J1155D01*
G03Y552287I-292J273D01*
G02X505603Y554397I1096J1027D01*
G03X505619Y554958I-277J289D01*
G02X507669I1025J956D01*
G03X507685Y554397I293J-272D01*
G02X507740Y552287I-1041J-1083D01*
G03Y551741I292J-273D01*
G02X507584Y549543I-1096J-1027D01*
G37*
G36*
G01X539395Y549416D02*
G03X539380Y548855I277J-288D01*
G02X537330I-1025J-957D01*
G03X537315Y549416I-292J273D01*
G02X537259Y551527I1040J1084D01*
G03Y552073I-292J273D01*
G02X537304Y554173I1096J1027D01*
G03X537314Y554735I-280J286D01*
G02X539365Y554753I1017J965D01*
G03X539386Y554192I295J-270D01*
G02X539451Y552073I-1031J-1092D01*
G03Y551527I292J-273D01*
G02X539395Y549416I-1096J-1027D01*
G37*
G36*
G01X502584D02*
G03X502569Y548855I277J-288D01*
G02X500519I-1025J-957D01*
G03X500504Y549416I-292J273D01*
G02X500448Y551527I1040J1084D01*
G03Y552073I-292J273D01*
G02X500493Y554173I1096J1027D01*
G03X500503Y554735I-280J286D01*
G02X502554Y554753I1017J965D01*
G03X502575Y554192I295J-270D01*
G02X502640Y552073I-1031J-1092D01*
G03Y551527I292J-273D01*
G02X502584Y549416I-1096J-1027D01*
G37*
G36*
G01X539422Y530667D02*
G03X539406Y530106I277J-289D01*
G02X537356I-1025J-956D01*
G03X537340Y530667I-293J272D01*
G02X537293Y532785I1041J1083D01*
G03X537287Y533342I-290J275D01*
G02X537314Y535482I1068J1057D01*
G03X537330Y536043I-277J289D01*
G02X539380I1025J956D01*
G03X539396Y535482I293J-272D01*
G02X539443Y533364I-1041J-1083D01*
G03X539449Y532807I290J-275D01*
G02X539422Y530667I-1068J-1057D01*
G37*
G36*
G01X502611D02*
G03X502595Y530106I277J-289D01*
G02X500545I-1025J-956D01*
G03X500529Y530667I-293J272D01*
G02X500482Y532785I1041J1083D01*
G03X500476Y533342I-290J275D01*
G02X500503Y535482I1068J1057D01*
G03X500519Y536043I-277J289D01*
G02X502569I1025J956D01*
G03X502585Y535482I293J-272D01*
G02X502632Y533364I-1041J-1083D01*
G03X502638Y532807I290J-275D01*
G02X502611Y530667I-1068J-1057D01*
G37*
G36*
G01X507689Y530461D02*
G03X507676Y529899I278J-288D01*
G02X505628Y529889I-1019J-963D01*
G03X505610Y530450I-293J271D01*
G02X505551Y532570I1034J1090D01*
G03Y533119I-291J274D01*
G02X505614Y535243I1093J1031D01*
G03X505635Y535804I-274J291D01*
G02X507685Y535783I1035J946D01*
G03X507695Y535222I290J-275D01*
G02X507737Y533119I-1051J-1073D01*
G03Y532570I291J-274D01*
G02X507689Y530461I-1093J-1030D01*
G37*
G36*
G01X535520Y514817D02*
G03X535534Y514234I281J-285D01*
G02X533534I-1000J-1120D01*
G03X533548Y514817I-267J298D01*
G02X535520I986J997D01*
G37*
G36*
G01X529234Y514778D02*
G03X529261Y514217I298J-267D01*
G02X527180Y514177I-1020J-1103D01*
G03X527184Y514738I-283J283D01*
G02X529234Y514778I1006J976D01*
G37*
G36*
G01X520848Y514234D02*
G03X520862Y514817I-267J298D01*
G02X522834I986J997D01*
G03X522848Y514234I281J-285D01*
G02X520848I-1000J-1120D01*
G37*
G36*
G01X516141Y514817D02*
G03X516155Y514234I281J-285D01*
G02X514155I-1000J-1120D01*
G03X514169Y514817I-267J298D01*
G02X516141I986J997D01*
G37*
G36*
G01X498709D02*
G03X498723Y514234I281J-285D01*
G02X496723I-1000J-1120D01*
G03X496737Y514817I-267J298D01*
G02X498709I986J997D01*
G37*
G36*
G01X492423Y514778D02*
G03X492450Y514217I298J-267D01*
G02X490369Y514177I-1020J-1103D01*
G03X490373Y514738I-283J283D01*
G02X492423Y514778I1006J976D01*
G37*
G36*
G01X484037Y514234D02*
G03X484051Y514817I-267J298D01*
G02X486023I986J997D01*
G03X486037Y514234I281J-285D01*
G02X484037I-1000J-1120D01*
G37*
G36*
G01X507584Y511743D02*
G03X507565Y511136I251J-312D01*
G02X505693Y511151I-944J-1036D01*
G03X505684Y511759I-265J300D01*
G02X505548Y513941I960J1155D01*
G03Y514487I-292J273D01*
G02X505603Y516597I1096J1027D01*
G03X505619Y517158I-277J289D01*
G02X507669I1025J956D01*
G03X507685Y516597I293J-272D01*
G02X507740Y514487I-1041J-1083D01*
G03Y513941I292J-273D01*
G02X507584Y511743I-1096J-1027D01*
G37*
G36*
G01X539395Y511616D02*
G03X539380Y511055I277J-288D01*
G02X537330I-1025J-957D01*
G03X537315Y511616I-292J273D01*
G02X537259Y513727I1040J1084D01*
G03Y514273I-292J273D01*
G02X537304Y516373I1096J1027D01*
G03X537314Y516935I-280J286D01*
G02X539365Y516953I1017J965D01*
G03X539386Y516392I295J-270D01*
G02X539451Y514273I-1031J-1092D01*
G03Y513727I292J-273D01*
G02X539395Y511616I-1096J-1027D01*
G37*
G36*
G01X502554Y516953D02*
G03X502575Y516392I295J-270D01*
G02X502640Y514273I-1031J-1092D01*
G03Y513727I292J-273D01*
G02X502584Y511616I-1096J-1027D01*
G03X502569Y511055I277J-288D01*
G02X500519I-1025J-957D01*
G03X500504Y511616I-292J273D01*
G02X500448Y513727I1040J1084D01*
G03Y514273I-292J273D01*
G02X500493Y516373I1096J1027D01*
G03X500503Y516935I-280J286D01*
G02X502554Y516953I1017J965D01*
G37*
G36*
G01X465799Y606267D02*
G03X465783Y605706I277J-289D01*
G02X463733I-1025J-956D01*
G03X463717Y606267I-293J272D01*
G02X463670Y608385I1041J1083D01*
G03X463664Y608942I-290J275D01*
G02X463691Y611082I1068J1057D01*
G03X463707Y611643I-277J289D01*
G02X465757I1025J956D01*
G03X465773Y611082I293J-272D01*
G02X465820Y608964I-1041J-1083D01*
G03X465826Y608407I290J-275D01*
G02X465799Y606267I-1068J-1057D01*
G37*
G36*
G01X470877Y606060D02*
G03X470865Y605498I278J-287D01*
G02X468817Y605489I-1020J-962D01*
G03X468799Y606051I-294J272D01*
G02X468740Y608170I1034J1089D01*
G03X468739Y608718I-292J273D01*
G02X468802Y610843I1093J1031D01*
G03X468823Y611404I-274J291D01*
G02X470873Y611383I1035J946D01*
G03X470883Y610822I290J-275D01*
G02X470925Y608719I-1051J-1073D01*
G03X470926Y608171I292J-273D01*
G02X470877Y606060I-1093J-1031D01*
G37*
G36*
G01X479845Y610757D02*
G02X478979Y612061I-1501J-57D01*
G03X479548Y612425I169J363D01*
G02X480401Y611140I1402J5D01*
G03X479845Y610757I-156J-368D01*
G37*
G36*
G01X479330Y590417D02*
G03X479344Y589834I281J-285D01*
G02X477344I-1000J-1120D01*
G03X477358Y590417I-267J298D01*
G02X479330I986J997D01*
G37*
G36*
G01X461937Y590358D02*
G03X461953Y589797I293J-272D01*
G02X459871I-1041J-1083D01*
G03X459887Y590358I-277J289D01*
G02X461937I1025J956D01*
G37*
G36*
G01X455612Y590378D02*
G03X455639Y589817I298J-267D01*
G02X453558Y589777I-1020J-1103D01*
G03X453562Y590338I-283J283D01*
G02X455612Y590378I1006J976D01*
G37*
G36*
G01X447191Y589794D02*
G03X447411Y590330I-145J373D01*
G02X449266Y589621I1281J570D01*
G03X449074Y589075I164J-365D01*
G02X447191Y589794I-1339J-681D01*
G37*
G36*
G01X470772Y587343D02*
G03X470753Y586736I251J-312D01*
G02X468881Y586751I-944J-1036D01*
G03X468872Y587359I-265J300D01*
G02X468736Y589541I960J1155D01*
G03Y590087I-292J273D01*
G02X468791Y592197I1096J1027D01*
G03X468807Y592758I-277J289D01*
G02X470857I1025J956D01*
G03X470873Y592197I293J-272D01*
G02X470928Y590087I-1041J-1083D01*
G03Y589541I292J-273D01*
G02X470772Y587343I-1096J-1027D01*
G37*
G36*
G01X463707Y586655D02*
G03X463692Y587216I-292J273D01*
G02X463636Y589327I1040J1084D01*
G03Y589873I-292J273D01*
G02X463681Y591973I1096J1027D01*
G03X463691Y592535I-280J286D01*
G02X465742Y592553I1017J965D01*
G03X465763Y591992I295J-270D01*
G02X465828Y589873I-1031J-1092D01*
G03Y589327I292J-273D01*
G02X465772Y587216I-1096J-1027D01*
G03X465757Y586655I277J-288D01*
G02X463707I-1025J-957D01*
G37*
G36*
G01X465799Y568467D02*
G03X465783Y567906I277J-289D01*
G02X463733I-1025J-956D01*
G03X463717Y568467I-293J272D01*
G02X463670Y570585I1041J1083D01*
G03X463664Y571142I-290J275D01*
G02X463691Y573282I1068J1057D01*
G03X463707Y573843I-277J289D01*
G02X465757I1025J956D01*
G03X465773Y573282I293J-272D01*
G02X465820Y571164I-1041J-1083D01*
G03X465826Y570607I290J-275D01*
G02X465799Y568467I-1068J-1057D01*
G37*
G36*
G01X470877Y568261D02*
G03X470864Y567699I278J-288D01*
G02X468816Y567689I-1019J-963D01*
G03X468798Y568250I-293J271D01*
G02X468739Y570370I1034J1090D01*
G03Y570919I-291J274D01*
G02X468802Y573043I1093J1031D01*
G03X468823Y573604I-274J291D01*
G02X470873Y573583I1035J946D01*
G03X470883Y573022I290J-275D01*
G02X470925Y570919I-1051J-1073D01*
G03Y570370I291J-274D01*
G02X470877Y568261I-1093J-1030D01*
G37*
G36*
G01X479330Y552617D02*
G03X479344Y552034I281J-285D01*
G02X477344I-1000J-1120D01*
G03X477358Y552617I-267J298D01*
G02X479330I986J997D01*
G37*
G36*
G01X461937Y552558D02*
G03X461953Y551997I293J-272D01*
G02X459871I-1041J-1083D01*
G03X459887Y552558I-277J289D01*
G02X461937I1025J956D01*
G37*
G36*
G01X455612Y552578D02*
G03X455639Y552017I298J-267D01*
G02X453558Y551977I-1020J-1103D01*
G03X453562Y552538I-283J283D01*
G02X455612Y552578I1006J976D01*
G37*
G36*
G01X470772Y549543D02*
G03X470753Y548936I251J-312D01*
G02X468881Y548951I-944J-1036D01*
G03X468872Y549559I-265J300D01*
G02X468736Y551741I960J1155D01*
G03Y552287I-292J273D01*
G02X468791Y554397I1096J1027D01*
G03X468807Y554958I-277J289D01*
G02X470857I1025J956D01*
G03X470873Y554397I293J-272D01*
G02X470928Y552287I-1041J-1083D01*
G03Y551741I292J-273D01*
G02X470772Y549543I-1096J-1027D01*
G37*
G36*
G01X463707Y548855D02*
G03X463692Y549416I-292J273D01*
G02X463636Y551527I1040J1084D01*
G03Y552073I-292J273D01*
G02X463681Y554173I1096J1027D01*
G03X463691Y554735I-280J286D01*
G02X465742Y554753I1017J965D01*
G03X465763Y554192I295J-270D01*
G02X465828Y552073I-1031J-1092D01*
G03Y551527I292J-273D01*
G02X465772Y549416I-1096J-1027D01*
G03X465757Y548855I277J-288D01*
G02X463707I-1025J-957D01*
G37*
G36*
G01X465799Y530667D02*
G03X465783Y530106I277J-289D01*
G02X463733I-1025J-956D01*
G03X463717Y530667I-293J272D01*
G02X463670Y532785I1041J1083D01*
G03X463664Y533342I-290J275D01*
G02X463691Y535482I1068J1057D01*
G03X463707Y536043I-277J289D01*
G02X465757I1025J956D01*
G03X465773Y535482I293J-272D01*
G02X465820Y533364I-1041J-1083D01*
G03X465826Y532807I290J-275D01*
G02X465799Y530667I-1068J-1057D01*
G37*
G36*
G01X470877Y530461D02*
G03X470864Y529899I278J-288D01*
G02X468816Y529889I-1019J-963D01*
G03X468798Y530450I-293J271D01*
G02X468739Y532570I1034J1090D01*
G03Y533119I-291J274D01*
G02X468802Y535243I1093J1031D01*
G03X468823Y535804I-274J291D01*
G02X470873Y535783I1035J946D01*
G03X470883Y535222I290J-275D01*
G02X470925Y533119I-1051J-1073D01*
G03Y532570I291J-274D01*
G02X470877Y530461I-1093J-1030D01*
G37*
G36*
G01X449294Y532244D02*
G02X447640Y532328I-884J-1088D01*
G03X447673Y532973I-219J335D01*
G02X447566Y535052I884J1088D01*
G03X447538Y535643I-283J283D01*
G02X449594Y537507I894J1080D01*
G03X450292Y537568I332J223D01*
G02X450411Y536215I1281J-569D01*
G03X449713Y536154I-332J-223D01*
G02X449423Y535732I-1281J570D01*
G03X449451Y535141I283J-283D01*
G02X449327Y532889I-894J-1080D01*
G03X449294Y532244I219J-335D01*
G37*
G36*
G01X479330Y514817D02*
G03X479344Y514234I281J-285D01*
G02X477344I-1000J-1120D01*
G03X477358Y514817I-267J298D01*
G02X479330I986J997D01*
G37*
G36*
G01X461937Y514758D02*
G03X461953Y514197I293J-272D01*
G02X459871I-1041J-1083D01*
G03X459887Y514758I-277J289D01*
G02X461937I1025J956D01*
G37*
G36*
G01X455612Y514778D02*
G03X455639Y514217I298J-267D01*
G02X453558Y514177I-1020J-1103D01*
G03X453562Y514738I-283J283D01*
G02X455612Y514778I1006J976D01*
G37*
G36*
G01X468736Y513941D02*
G03Y514487I-292J273D01*
G02X468791Y516597I1096J1027D01*
G03X468807Y517158I-277J289D01*
G02X470857I1025J956D01*
G03X470873Y516597I293J-272D01*
G02X470928Y514487I-1041J-1083D01*
G03Y513941I292J-273D01*
G02X468736I-1096J-1027D01*
G37*
G36*
G01X449194Y513991D02*
G03X448982Y513435I144J-373D01*
G02X447233Y514103I-1247J-641D01*
G03X447445Y514659I-144J373D01*
G02X449194Y513991I1247J641D01*
G37*
G36*
G01X465742Y516953D02*
G03X465763Y516392I295J-270D01*
G02X465828Y514273I-1031J-1092D01*
G03Y513727I292J-273D01*
G02X465772Y511616I-1096J-1027D01*
G03X465757Y511055I277J-288D01*
G02X463707I-1025J-957D01*
G03X463692Y511616I-292J273D01*
G02X463636Y513727I1040J1084D01*
G03Y514273I-292J273D01*
G02X463681Y516373I1096J1027D01*
G03X463691Y516935I-280J286D01*
G02X465742Y516953I1017J965D01*
G37*
G36*
G01X362540Y611528D02*
G02Y612956I-1322J714D01*
G03X363243I352J190D01*
G02Y611528I1322J-714D01*
G03X362540I-351J-190D01*
G37*
G36*
G01X373249Y612344D02*
G02X372653Y610977I790J-1158D01*
G03X372021Y611241I-396J-59D01*
G02X372626Y612628I-887J1212D01*
G03X373249Y612344I397J46D01*
G37*
G36*
G01X362540Y603900D02*
G02Y605328I-1322J714D01*
G03X363243I352J190D01*
G02Y603900I1322J-714D01*
G03X362540I-351J-190D01*
G37*
G36*
G01X371834Y592755D02*
G02X371756Y594717I-1175J936D01*
G03X372348Y594726I292J274D01*
G02X374538Y594619I1052J-926D01*
G03X375160Y594586I324J234D01*
G02X375066Y592831I1044J-936D01*
G03X374444Y592864I-324J-234D01*
G02X372425Y592793I-1044J936D01*
G03X371834Y592755I-278J-287D01*
G37*
G36*
G01X363286Y592928D02*
G02Y594356I-1322J714D01*
G03X363989I351J190D01*
G02Y592928I1322J-714D01*
G03X363286I-351J-190D01*
G37*
G36*
G01X357780Y589938D02*
G03Y589367I280J-286D01*
G02X355816I-982J-1001D01*
G03Y589938I-280J285D01*
G02X357780I982J1001D01*
G37*
G36*
G01X363180Y584675D02*
G03X362603I-289J-277D01*
G02Y586753I-1085J1039D01*
G03X363180I289J277D01*
G02Y584675I1085J-1039D01*
G37*
G36*
G01X358734Y571001D02*
G03Y570446I288J-278D01*
G02X356714I-1010J-972D01*
G03Y571001I-288J277D01*
G02X358734I1010J972D01*
G37*
G36*
G01X358510Y552100D02*
G03Y551522I277J-289D01*
G02X356568I-971J-1011D01*
G03Y552100I-277J289D01*
G02X358510I971J1011D01*
G37*
G36*
G01X363180Y546875D02*
G03X362603I-289J-277D01*
G02Y548953I-1085J1039D01*
G03X363180I289J277D01*
G02Y546875I1085J-1039D01*
G37*
G36*
G01X375768Y544799D02*
G03X375791Y545360I-273J292D01*
G02X377840Y545331I1038J943D01*
G03X377847Y544769I288J-277D01*
G02X375768Y544799I-1055J-1069D01*
G37*
G36*
G01X358688Y533045D02*
G03Y532501I293J-272D01*
G02X356634I-1027J-955D01*
G03Y533045I-293J272D01*
G02X358688I1027J955D01*
G37*
G36*
G01X362540Y574028D02*
G02Y575456I-1322J714D01*
G03X363243I352J190D01*
G02Y574028I1322J-714D01*
G03X362540I-351J-190D01*
G37*
G36*
G01Y566100D02*
G02Y567528I-1322J714D01*
G03X363243I352J190D01*
G02Y566100I1322J-714D01*
G03X362540I-351J-190D01*
G37*
G36*
G01X362601Y555058D02*
G02Y556626I-1281J784D01*
G03X363284I341J208D01*
G02Y555058I1281J-784D01*
G03X362601I-341J-208D01*
G37*
G36*
G01X376324Y517869D02*
G03Y517343I302J-263D01*
G02X374060I-1132J-987D01*
G03Y517869I-302J263D01*
G02X376324I1132J987D01*
G37*
G36*
G01X362698Y516269D02*
G03X363249Y516258I281J284D01*
G02X363209Y514083I1016J-1107D01*
G03X362658Y514094I-281J-284D01*
G02X362698Y516269I-1016J1107D01*
G37*
G36*
G01X363180Y509075D02*
G03X362603I-289J-277D01*
G02Y511153I-1085J1039D01*
G03X363180I289J277D01*
G02Y509075I1085J-1039D01*
G37*
G36*
G01X305282Y590435D02*
G03X305307Y589853I286J-279D01*
G02X303307Y589816I-979J-1139D01*
G03X303311Y590399I-272J293D01*
G02X305282Y590435I967J1015D01*
G37*
G36*
G01X298621Y590417D02*
G03X298635Y589834I281J-285D01*
G02X296635I-1000J-1120D01*
G03X296649Y590417I-267J298D01*
G02X298621I986J997D01*
G37*
G36*
G01X308818Y589947D02*
G03X308808Y589356I264J-300D01*
G02X306922Y589387I-960J-1022D01*
G03X306932Y589978I-264J300D01*
G02X306867Y591957I960J1022D01*
G03X306819Y592547I-292J273D01*
G02X308700Y592700I856J1110D01*
G03X308748Y592110I292J-273D01*
G02X308818Y589947I-856J-1110D01*
G37*
G36*
G01X305282Y552635D02*
G03X305307Y552053I286J-279D01*
G02X303307Y552016I-979J-1139D01*
G03X303311Y552599I-272J293D01*
G02X305282Y552635I967J1015D01*
G37*
G36*
G01X298621Y552617D02*
G03X298635Y552034I281J-285D01*
G02X296635I-1000J-1120D01*
G03X296649Y552617I-267J298D01*
G02X298621I986J997D01*
G37*
G36*
G01X305282Y514835D02*
G03X305307Y514253I286J-279D01*
G02X303307Y514216I-979J-1139D01*
G03X303311Y514799I-272J293D01*
G02X305282Y514835I967J1015D01*
G37*
G36*
G01X298621Y514817D02*
G03X298635Y514234I281J-285D01*
G02X296635I-1000J-1120D01*
G03X296649Y514817I-267J298D01*
G02X298621I986J997D01*
G37*
G36*
G01X285091Y606267D02*
G03X285075Y605706I277J-289D01*
G02X283025I-1025J-956D01*
G03X283009Y606267I-293J272D01*
G02X282962Y608385I1041J1083D01*
G03X282956Y608942I-290J275D01*
G02X282983Y611082I1068J1057D01*
G03X282999Y611643I-277J289D01*
G02X285049I1025J956D01*
G03X285065Y611082I293J-272D01*
G02X285112Y608964I-1041J-1083D01*
G03X285118Y608407I290J-275D01*
G02X285091Y606267I-1068J-1057D01*
G37*
G36*
G01X248280D02*
G03X248264Y605706I277J-289D01*
G02X246214I-1025J-956D01*
G03X246198Y606267I-293J272D01*
G02X246151Y608385I1041J1083D01*
G03X246145Y608942I-290J275D01*
G02X246172Y611082I1068J1057D01*
G03X246188Y611643I-277J289D01*
G02X248238I1025J956D01*
G03X248254Y611082I293J-272D01*
G02X248301Y608964I-1041J-1083D01*
G03X248307Y608407I290J-275D01*
G02X248280Y606267I-1068J-1057D01*
G37*
G36*
G01X290169Y606061D02*
G03X290156Y605499I278J-288D01*
G02X288108Y605489I-1019J-963D01*
G03X288090Y606050I-293J271D01*
G02X288031Y608170I1034J1090D01*
G03Y608719I-291J274D01*
G02X288094Y610843I1093J1031D01*
G03X288115Y611404I-274J291D01*
G02X290165Y611383I1035J946D01*
G03X290175Y610822I290J-275D01*
G02X290217Y608719I-1051J-1073D01*
G03Y608170I291J-274D01*
G02X290169Y606061I-1093J-1030D01*
G37*
G36*
G01X253358D02*
G03X253345Y605499I278J-288D01*
G02X251297Y605489I-1019J-963D01*
G03X251279Y606050I-293J271D01*
G02X251220Y608170I1034J1090D01*
G03Y608719I-291J274D01*
G02X251283Y610843I1093J1031D01*
G03X251304Y611404I-274J291D01*
G02X253354Y611383I1035J946D01*
G03X253364Y610822I290J-275D01*
G02X253406Y608719I-1051J-1073D01*
G03Y608170I291J-274D01*
G02X253358Y606061I-1093J-1030D01*
G37*
G36*
G01X281189Y590417D02*
G03X281203Y589834I281J-285D01*
G02X279203I-1000J-1120D01*
G03X279217Y590417I-267J298D01*
G02X281189I986J997D01*
G37*
G36*
G01X274903Y590378D02*
G03X274930Y589817I298J-267D01*
G02X272849Y589777I-1020J-1103D01*
G03X272853Y590338I-283J283D01*
G02X274903Y590378I1006J976D01*
G37*
G36*
G01X266517Y589834D02*
G03X266531Y590417I-267J298D01*
G02X268503I986J997D01*
G03X268517Y589834I281J-285D01*
G02X266517I-1000J-1120D01*
G37*
G36*
G01X261810Y590417D02*
G03X261824Y589834I281J-285D01*
G02X259824I-1000J-1120D01*
G03X259838Y590417I-267J298D01*
G02X261810I986J997D01*
G37*
G36*
G01X244378D02*
G03X244392Y589834I281J-285D01*
G02X242392I-1000J-1120D01*
G03X242406Y590417I-267J298D01*
G02X244378I986J997D01*
G37*
G36*
G01X238092Y590378D02*
G03X238119Y589817I298J-267D01*
G02X236038Y589777I-1020J-1103D01*
G03X236042Y590338I-283J283D01*
G02X238092Y590378I1006J976D01*
G37*
G36*
G01X290064Y587343D02*
G03X290045Y586736I251J-312D01*
G02X288173Y586751I-944J-1036D01*
G03X288164Y587359I-265J300D01*
G02X288028Y589541I960J1155D01*
G03Y590087I-292J273D01*
G02X288083Y592197I1096J1027D01*
G03X288099Y592758I-277J289D01*
G02X290149I1025J956D01*
G03X290165Y592197I293J-272D01*
G02X290220Y590087I-1041J-1083D01*
G03Y589541I292J-273D01*
G02X290064Y587343I-1096J-1027D01*
G37*
G36*
G01X253253D02*
G03X253234Y586736I251J-312D01*
G02X251362Y586751I-944J-1036D01*
G03X251353Y587359I-265J300D01*
G02X251217Y589541I960J1155D01*
G03Y590087I-292J273D01*
G02X251272Y592197I1096J1027D01*
G03X251288Y592758I-277J289D01*
G02X253338I1025J956D01*
G03X253354Y592197I293J-272D01*
G02X253409Y590087I-1041J-1083D01*
G03Y589541I292J-273D01*
G02X253253Y587343I-1096J-1027D01*
G37*
G36*
G01X285064Y587216D02*
G03X285049Y586655I277J-288D01*
G02X282999I-1025J-957D01*
G03X282984Y587216I-292J273D01*
G02X282928Y589327I1040J1084D01*
G03Y589873I-292J273D01*
G02X282973Y591973I1096J1027D01*
G03X282983Y592535I-280J286D01*
G02X285034Y592553I1017J965D01*
G03X285055Y591992I295J-270D01*
G02X285120Y589873I-1031J-1092D01*
G03Y589327I292J-273D01*
G02X285064Y587216I-1096J-1027D01*
G37*
G36*
G01X248253D02*
G03X248238Y586655I277J-288D01*
G02X246188I-1025J-957D01*
G03X246173Y587216I-292J273D01*
G02X246117Y589327I1040J1084D01*
G03Y589873I-292J273D01*
G02X246162Y591973I1096J1027D01*
G03X246172Y592535I-280J286D01*
G02X248223Y592553I1017J965D01*
G03X248244Y591992I295J-270D01*
G02X248309Y589873I-1031J-1092D01*
G03Y589327I292J-273D01*
G02X248253Y587216I-1096J-1027D01*
G37*
G36*
G01X285091Y568467D02*
G03X285075Y567906I277J-289D01*
G02X283025I-1025J-956D01*
G03X283009Y568467I-293J272D01*
G02X282962Y570585I1041J1083D01*
G03X282956Y571142I-290J275D01*
G02X282983Y573282I1068J1057D01*
G03X282999Y573843I-277J289D01*
G02X285049I1025J956D01*
G03X285065Y573282I293J-272D01*
G02X285112Y571164I-1041J-1083D01*
G03X285118Y570607I290J-275D01*
G02X285091Y568467I-1068J-1057D01*
G37*
G36*
G01X248280D02*
G03X248264Y567906I277J-289D01*
G02X246214I-1025J-956D01*
G03X246198Y568467I-293J272D01*
G02X246151Y570585I1041J1083D01*
G03X246145Y571142I-290J275D01*
G02X246172Y573282I1068J1057D01*
G03X246188Y573843I-277J289D01*
G02X248238I1025J956D01*
G03X248254Y573282I293J-272D01*
G02X248301Y571164I-1041J-1083D01*
G03X248307Y570607I290J-275D01*
G02X248280Y568467I-1068J-1057D01*
G37*
G36*
G01X290169Y568261D02*
G03X290156Y567699I278J-288D01*
G02X288108Y567689I-1019J-963D01*
G03X288090Y568250I-293J271D01*
G02X288031Y570370I1034J1090D01*
G03Y570919I-291J274D01*
G02X288094Y573043I1093J1031D01*
G03X288115Y573604I-274J291D01*
G02X290165Y573583I1035J946D01*
G03X290175Y573022I290J-275D01*
G02X290217Y570919I-1051J-1073D01*
G03Y570370I291J-274D01*
G02X290169Y568261I-1093J-1030D01*
G37*
G36*
G01X253358D02*
G03X253345Y567699I278J-288D01*
G02X251297Y567689I-1019J-963D01*
G03X251279Y568250I-293J271D01*
G02X251220Y570370I1034J1090D01*
G03Y570919I-291J274D01*
G02X251283Y573043I1093J1031D01*
G03X251304Y573604I-274J291D01*
G02X253354Y573583I1035J946D01*
G03X253364Y573022I290J-275D01*
G02X253406Y570919I-1051J-1073D01*
G03Y570370I291J-274D01*
G02X253358Y568261I-1093J-1030D01*
G37*
G36*
G01X281189Y552617D02*
G03X281203Y552034I281J-285D01*
G02X279203I-1000J-1120D01*
G03X279217Y552617I-267J298D01*
G02X281189I986J997D01*
G37*
G36*
G01X274903Y552578D02*
G03X274930Y552017I298J-267D01*
G02X272849Y551977I-1020J-1103D01*
G03X272853Y552538I-283J283D01*
G02X274903Y552578I1006J976D01*
G37*
G36*
G01X266517Y552034D02*
G03X266531Y552617I-267J298D01*
G02X268503I986J997D01*
G03X268517Y552034I281J-285D01*
G02X266517I-1000J-1120D01*
G37*
G36*
G01X261810Y552617D02*
G03X261824Y552034I281J-285D01*
G02X259824I-1000J-1120D01*
G03X259838Y552617I-267J298D01*
G02X261810I986J997D01*
G37*
G36*
G01X244378D02*
G03X244392Y552034I281J-285D01*
G02X242392I-1000J-1120D01*
G03X242406Y552617I-267J298D01*
G02X244378I986J997D01*
G37*
G36*
G01X238092Y552578D02*
G03X238119Y552017I298J-267D01*
G02X236038Y551977I-1020J-1103D01*
G03X236042Y552538I-283J283D01*
G02X238092Y552578I1006J976D01*
G37*
G36*
G01X290064Y549543D02*
G03X290045Y548936I251J-312D01*
G02X288173Y548951I-944J-1036D01*
G03X288164Y549559I-265J300D01*
G02X288028Y551741I960J1155D01*
G03Y552287I-292J273D01*
G02X288083Y554397I1096J1027D01*
G03X288099Y554958I-277J289D01*
G02X290149I1025J956D01*
G03X290165Y554397I293J-272D01*
G02X290220Y552287I-1041J-1083D01*
G03Y551741I292J-273D01*
G02X290064Y549543I-1096J-1027D01*
G37*
G36*
G01X253253D02*
G03X253234Y548936I251J-312D01*
G02X251362Y548951I-944J-1036D01*
G03X251353Y549559I-265J300D01*
G02X251217Y551741I960J1155D01*
G03Y552287I-292J273D01*
G02X251272Y554397I1096J1027D01*
G03X251288Y554958I-277J289D01*
G02X253338I1025J956D01*
G03X253354Y554397I293J-272D01*
G02X253409Y552287I-1041J-1083D01*
G03Y551741I292J-273D01*
G02X253253Y549543I-1096J-1027D01*
G37*
G36*
G01X285064Y549416D02*
G03X285049Y548855I277J-288D01*
G02X282999I-1025J-957D01*
G03X282984Y549416I-292J273D01*
G02X282928Y551527I1040J1084D01*
G03Y552073I-292J273D01*
G02X282973Y554173I1096J1027D01*
G03X282983Y554735I-280J286D01*
G02X285034Y554753I1017J965D01*
G03X285055Y554192I295J-270D01*
G02X285120Y552073I-1031J-1092D01*
G03Y551527I292J-273D01*
G02X285064Y549416I-1096J-1027D01*
G37*
G36*
G01X248253D02*
G03X248238Y548855I277J-288D01*
G02X246188I-1025J-957D01*
G03X246173Y549416I-292J273D01*
G02X246117Y551527I1040J1084D01*
G03Y552073I-292J273D01*
G02X246162Y554173I1096J1027D01*
G03X246172Y554735I-280J286D01*
G02X248223Y554753I1017J965D01*
G03X248244Y554192I295J-270D01*
G02X248309Y552073I-1031J-1092D01*
G03Y551527I292J-273D01*
G02X248253Y549416I-1096J-1027D01*
G37*
G36*
G01X248301Y533364D02*
G03X248307Y532807I290J-275D01*
G02X246151Y532785I-1067J-1057D01*
G03X246145Y533342I-290J275D01*
G02X246172Y535482I1068J1057D01*
G03X246188Y536043I-277J289D01*
G02X248238I1025J956D01*
G03X248254Y535482I293J-272D01*
G02X248301Y533364I-1041J-1083D01*
G37*
G36*
G01X285091Y530667D02*
G03X285075Y530106I277J-289D01*
G02X283025I-1025J-956D01*
G03X283009Y530667I-293J272D01*
G02X282962Y532785I1041J1083D01*
G03X282956Y533342I-290J275D01*
G02X282983Y535482I1068J1057D01*
G03X282999Y536043I-277J289D01*
G02X285049I1025J956D01*
G03X285065Y535482I293J-272D01*
G02X285112Y533364I-1041J-1083D01*
G03X285118Y532807I290J-275D01*
G02X285091Y530667I-1068J-1057D01*
G37*
G36*
G01X290169Y530461D02*
G03X290156Y529899I278J-288D01*
G02X288108Y529889I-1019J-963D01*
G03X288090Y530450I-293J271D01*
G02X288031Y532570I1034J1090D01*
G03Y533119I-291J274D01*
G02X288094Y535243I1093J1031D01*
G03X288115Y535804I-274J291D01*
G02X290165Y535783I1035J946D01*
G03X290175Y535222I290J-275D01*
G02X290217Y533119I-1051J-1073D01*
G03Y532570I291J-274D01*
G02X290169Y530461I-1093J-1030D01*
G37*
G36*
G01X253358D02*
G03X253345Y529899I278J-288D01*
G02X251297Y529889I-1019J-963D01*
G03X251279Y530450I-293J271D01*
G02X251220Y532570I1034J1090D01*
G03Y533119I-291J274D01*
G02X251283Y535243I1093J1031D01*
G03X251304Y535804I-274J291D01*
G02X253354Y535783I1035J946D01*
G03X253364Y535222I290J-275D01*
G02X253406Y533119I-1051J-1073D01*
G03Y532570I291J-274D01*
G02X253358Y530461I-1093J-1030D01*
G37*
G36*
G01X281189Y514817D02*
G03X281203Y514234I281J-285D01*
G02X279203I-1000J-1120D01*
G03X279217Y514817I-267J298D01*
G02X281189I986J997D01*
G37*
G36*
G01X274903Y514778D02*
G03X274930Y514217I298J-267D01*
G02X272849Y514177I-1020J-1103D01*
G03X272853Y514738I-283J283D01*
G02X274903Y514778I1006J976D01*
G37*
G36*
G01X266517Y514234D02*
G03X266531Y514817I-267J298D01*
G02X268503I986J997D01*
G03X268517Y514234I281J-285D01*
G02X266517I-1000J-1120D01*
G37*
G36*
G01X261810Y514817D02*
G03X261824Y514234I281J-285D01*
G02X259824I-1000J-1120D01*
G03X259838Y514817I-267J298D01*
G02X261810I986J997D01*
G37*
G36*
G01X244378D02*
G03X244392Y514234I281J-285D01*
G02X242392I-1000J-1120D01*
G03X242406Y514817I-267J298D01*
G02X244378I986J997D01*
G37*
G36*
G01X238092Y514778D02*
G03X238119Y514217I298J-267D01*
G02X236038Y514177I-1020J-1103D01*
G03X236042Y514738I-283J283D01*
G02X238092Y514778I1006J976D01*
G37*
G36*
G01X290064Y511743D02*
G03X290045Y511136I251J-312D01*
G02X288173Y511151I-944J-1036D01*
G03X288164Y511759I-265J300D01*
G02X288028Y513941I960J1155D01*
G03Y514487I-292J273D01*
G02X288083Y516597I1096J1027D01*
G03X288099Y517158I-277J289D01*
G02X290149I1025J956D01*
G03X290165Y516597I293J-272D01*
G02X290220Y514487I-1041J-1083D01*
G03Y513941I292J-273D01*
G02X290064Y511743I-1096J-1027D01*
G37*
G36*
G01X253253D02*
G03X253234Y511136I251J-312D01*
G02X251362Y511151I-944J-1036D01*
G03X251353Y511759I-265J300D01*
G02X251217Y513941I960J1155D01*
G03Y514487I-292J273D01*
G02X251272Y516597I1096J1027D01*
G03X251288Y517158I-277J289D01*
G02X253338I1025J956D01*
G03X253354Y516597I293J-272D01*
G02X253409Y514487I-1041J-1083D01*
G03Y513941I292J-273D01*
G02X253253Y511743I-1096J-1027D01*
G37*
G36*
G01X285034Y516953D02*
G03X285055Y516392I295J-270D01*
G02X285120Y514273I-1031J-1092D01*
G03Y513727I292J-273D01*
G02X285064Y511616I-1096J-1027D01*
G03X285049Y511055I277J-288D01*
G02X282999I-1025J-957D01*
G03X282984Y511616I-292J273D01*
G02X282928Y513727I1040J1084D01*
G03Y514273I-292J273D01*
G02X282973Y516373I1096J1027D01*
G03X282983Y516935I-280J286D01*
G02X285034Y516953I1017J965D01*
G37*
G36*
G01X248253Y511616D02*
G03X248238Y511055I277J-288D01*
G02X246188I-1025J-957D01*
G03X246173Y511616I-292J273D01*
G02X246117Y513727I1040J1084D01*
G03Y514273I-292J273D01*
G02X246162Y516373I1096J1027D01*
G03X246172Y516935I-280J286D01*
G02X248223Y516953I1017J965D01*
G03X248244Y516392I295J-270D01*
G02X248309Y514273I-1031J-1092D01*
G03Y513727I292J-273D01*
G02X248253Y511616I-1096J-1027D01*
G37*
G36*
G01X211469Y606267D02*
G03X211453Y605706I277J-289D01*
G02X209403I-1025J-956D01*
G03X209387Y606267I-293J272D01*
G02X209340Y608385I1041J1083D01*
G03X209334Y608942I-290J275D01*
G02X209361Y611082I1068J1057D01*
G03X209377Y611643I-277J289D01*
G02X211427I1025J956D01*
G03X211443Y611082I293J-272D01*
G02X211490Y608964I-1041J-1083D01*
G03X211496Y608407I290J-275D01*
G02X211469Y606267I-1068J-1057D01*
G37*
G36*
G01X174658D02*
G03X174642Y605706I277J-289D01*
G02X172592I-1025J-956D01*
G03X172576Y606267I-293J272D01*
G02X172529Y608385I1041J1083D01*
G03X172523Y608942I-290J275D01*
G02X172550Y611082I1068J1057D01*
G03X172566Y611643I-277J289D01*
G02X174616I1025J956D01*
G03X174632Y611082I293J-272D01*
G02X174679Y608964I-1041J-1083D01*
G03X174685Y608407I290J-275D01*
G02X174658Y606267I-1068J-1057D01*
G37*
G36*
G01X216547Y606061D02*
G03X216534Y605499I278J-288D01*
G02X214486Y605489I-1019J-963D01*
G03X214468Y606050I-293J271D01*
G02X214409Y608170I1034J1090D01*
G03Y608719I-291J274D01*
G02X214472Y610843I1093J1031D01*
G03X214493Y611404I-274J291D01*
G02X216543Y611383I1035J946D01*
G03X216553Y610822I290J-275D01*
G02X216595Y608719I-1051J-1073D01*
G03Y608170I291J-274D01*
G02X216547Y606061I-1093J-1030D01*
G37*
G36*
G01X179736D02*
G03X179723Y605499I278J-288D01*
G02X177675Y605489I-1019J-963D01*
G03X177657Y606050I-293J271D01*
G02X177598Y608170I1034J1090D01*
G03Y608719I-291J274D01*
G02X177661Y610843I1093J1031D01*
G03X177682Y611404I-274J291D01*
G02X179732Y611383I1035J946D01*
G03X179742Y610822I290J-275D01*
G02X179784Y608719I-1051J-1073D01*
G03Y608170I291J-274D01*
G02X179736Y606061I-1093J-1030D01*
G37*
G36*
G01X229706Y589834D02*
G03X229720Y590417I-267J298D01*
G02X231692I986J997D01*
G03X231706Y589834I281J-285D01*
G02X229706I-1000J-1120D01*
G37*
G36*
G01X224999Y590417D02*
G03X225013Y589834I281J-285D01*
G02X223013I-1000J-1120D01*
G03X223027Y590417I-267J298D01*
G02X224999I986J997D01*
G37*
G36*
G01X207567D02*
G03X207581Y589834I281J-285D01*
G02X205581I-1000J-1120D01*
G03X205595Y590417I-267J298D01*
G02X207567I986J997D01*
G37*
G36*
G01X201281Y590378D02*
G03X201308Y589817I298J-267D01*
G02X199227Y589777I-1020J-1103D01*
G03X199231Y590338I-283J283D01*
G02X201281Y590378I1006J976D01*
G37*
G36*
G01X192895Y589834D02*
G03X192909Y590417I-267J298D01*
G02X194881I986J997D01*
G03X194895Y589834I281J-285D01*
G02X192895I-1000J-1120D01*
G37*
G36*
G01X188188Y590417D02*
G03X188202Y589834I281J-285D01*
G02X186202I-1000J-1120D01*
G03X186216Y590417I-267J298D01*
G02X188188I986J997D01*
G37*
G36*
G01X216442Y587343D02*
G03X216423Y586736I251J-312D01*
G02X214551Y586751I-944J-1036D01*
G03X214542Y587359I-265J300D01*
G02X214406Y589541I960J1155D01*
G03Y590087I-292J273D01*
G02X214461Y592197I1096J1027D01*
G03X214477Y592758I-277J289D01*
G02X216527I1025J956D01*
G03X216543Y592197I293J-272D01*
G02X216598Y590087I-1041J-1083D01*
G03Y589541I292J-273D01*
G02X216442Y587343I-1096J-1027D01*
G37*
G36*
G01X179631D02*
G03X179612Y586736I251J-312D01*
G02X177740Y586751I-944J-1036D01*
G03X177731Y587359I-265J300D01*
G02X177595Y589541I960J1155D01*
G03Y590087I-292J273D01*
G02X177650Y592197I1096J1027D01*
G03X177666Y592758I-277J289D01*
G02X179716I1025J956D01*
G03X179732Y592197I293J-272D01*
G02X179787Y590087I-1041J-1083D01*
G03Y589541I292J-273D01*
G02X179631Y587343I-1096J-1027D01*
G37*
G36*
G01X211442Y587216D02*
G03X211427Y586655I277J-288D01*
G02X209377I-1025J-957D01*
G03X209362Y587216I-292J273D01*
G02X209306Y589327I1040J1084D01*
G03Y589873I-292J273D01*
G02X209351Y591973I1096J1027D01*
G03X209361Y592535I-280J286D01*
G02X211412Y592553I1017J965D01*
G03X211433Y591992I295J-270D01*
G02X211498Y589873I-1031J-1092D01*
G03Y589327I292J-273D01*
G02X211442Y587216I-1096J-1027D01*
G37*
G36*
G01X174631D02*
G03X174616Y586655I277J-288D01*
G02X172566I-1025J-957D01*
G03X172551Y587216I-292J273D01*
G02X172495Y589327I1040J1084D01*
G03Y589873I-292J273D01*
G02X172540Y591973I1096J1027D01*
G03X172550Y592535I-280J286D01*
G02X174601Y592553I1017J965D01*
G03X174622Y591992I295J-270D01*
G02X174687Y589873I-1031J-1092D01*
G03Y589327I292J-273D01*
G02X174631Y587216I-1096J-1027D01*
G37*
G36*
G01X211469Y568467D02*
G03X211453Y567906I277J-289D01*
G02X209403I-1025J-956D01*
G03X209387Y568467I-293J272D01*
G02X209340Y570585I1041J1083D01*
G03X209334Y571142I-290J275D01*
G02X209361Y573282I1068J1057D01*
G03X209377Y573843I-277J289D01*
G02X211427I1025J956D01*
G03X211443Y573282I293J-272D01*
G02X211490Y571164I-1041J-1083D01*
G03X211496Y570607I290J-275D01*
G02X211469Y568467I-1068J-1057D01*
G37*
G36*
G01X174658D02*
G03X174642Y567906I277J-289D01*
G02X172592I-1025J-956D01*
G03X172576Y568467I-293J272D01*
G02X172529Y570585I1041J1083D01*
G03X172523Y571142I-290J275D01*
G02X172550Y573282I1068J1057D01*
G03X172566Y573843I-277J289D01*
G02X174616I1025J956D01*
G03X174632Y573282I293J-272D01*
G02X174679Y571164I-1041J-1083D01*
G03X174685Y570607I290J-275D01*
G02X174658Y568467I-1068J-1057D01*
G37*
G36*
G01X216547Y568261D02*
G03X216534Y567699I278J-288D01*
G02X214486Y567689I-1019J-963D01*
G03X214468Y568250I-293J271D01*
G02X214409Y570370I1034J1090D01*
G03Y570919I-291J274D01*
G02X214472Y573043I1093J1031D01*
G03X214493Y573604I-274J291D01*
G02X216543Y573583I1035J946D01*
G03X216553Y573022I290J-275D01*
G02X216595Y570919I-1051J-1073D01*
G03Y570370I291J-274D01*
G02X216547Y568261I-1093J-1030D01*
G37*
G36*
G01X179736D02*
G03X179723Y567699I278J-288D01*
G02X177675Y567689I-1019J-963D01*
G03X177657Y568250I-293J271D01*
G02X177598Y570370I1034J1090D01*
G03Y570919I-291J274D01*
G02X177661Y573043I1093J1031D01*
G03X177682Y573604I-274J291D01*
G02X179732Y573583I1035J946D01*
G03X179742Y573022I290J-275D01*
G02X179784Y570919I-1051J-1073D01*
G03Y570370I291J-274D01*
G02X179736Y568261I-1093J-1030D01*
G37*
G36*
G01X229706Y552034D02*
G03X229720Y552617I-267J298D01*
G02X231692I986J997D01*
G03X231706Y552034I281J-285D01*
G02X229706I-1000J-1120D01*
G37*
G36*
G01X224999Y552617D02*
G03X225013Y552034I281J-285D01*
G02X223013I-1000J-1120D01*
G03X223027Y552617I-267J298D01*
G02X224999I986J997D01*
G37*
G36*
G01X207567D02*
G03X207581Y552034I281J-285D01*
G02X205581I-1000J-1120D01*
G03X205595Y552617I-267J298D01*
G02X207567I986J997D01*
G37*
G36*
G01X201281Y552578D02*
G03X201308Y552017I298J-267D01*
G02X199227Y551977I-1020J-1103D01*
G03X199231Y552538I-283J283D01*
G02X201281Y552578I1006J976D01*
G37*
G36*
G01X192895Y552034D02*
G03X192909Y552617I-267J298D01*
G02X194881I986J997D01*
G03X194895Y552034I281J-285D01*
G02X192895I-1000J-1120D01*
G37*
G36*
G01X188188Y552617D02*
G03X188202Y552034I281J-285D01*
G02X186202I-1000J-1120D01*
G03X186216Y552617I-267J298D01*
G02X188188I986J997D01*
G37*
G36*
G01X216442Y549543D02*
G03X216423Y548936I251J-312D01*
G02X214551Y548951I-944J-1036D01*
G03X214542Y549559I-265J300D01*
G02X214406Y551741I960J1155D01*
G03Y552287I-292J273D01*
G02X214461Y554397I1096J1027D01*
G03X214477Y554958I-277J289D01*
G02X216527I1025J956D01*
G03X216543Y554397I293J-272D01*
G02X216598Y552287I-1041J-1083D01*
G03Y551741I292J-273D01*
G02X216442Y549543I-1096J-1027D01*
G37*
G36*
G01X179631D02*
G03X179612Y548936I251J-312D01*
G02X177740Y548951I-944J-1036D01*
G03X177731Y549559I-265J300D01*
G02X177595Y551741I960J1155D01*
G03Y552287I-292J273D01*
G02X177650Y554397I1096J1027D01*
G03X177666Y554958I-277J289D01*
G02X179716I1025J956D01*
G03X179732Y554397I293J-272D01*
G02X179787Y552287I-1041J-1083D01*
G03Y551741I292J-273D01*
G02X179631Y549543I-1096J-1027D01*
G37*
G36*
G01X211442Y549416D02*
G03X211427Y548855I277J-288D01*
G02X209377I-1025J-957D01*
G03X209362Y549416I-292J273D01*
G02X209306Y551527I1040J1084D01*
G03Y552073I-292J273D01*
G02X209351Y554173I1096J1027D01*
G03X209361Y554735I-280J286D01*
G02X211412Y554753I1017J965D01*
G03X211433Y554192I295J-270D01*
G02X211498Y552073I-1031J-1092D01*
G03Y551527I292J-273D01*
G02X211442Y549416I-1096J-1027D01*
G37*
G36*
G01X174631D02*
G03X174616Y548855I277J-288D01*
G02X172566I-1025J-957D01*
G03X172551Y549416I-292J273D01*
G02X172495Y551527I1040J1084D01*
G03Y552073I-292J273D01*
G02X172540Y554173I1096J1027D01*
G03X172550Y554735I-280J286D01*
G02X174601Y554753I1017J965D01*
G03X174622Y554192I295J-270D01*
G02X174687Y552073I-1031J-1092D01*
G03Y551527I292J-273D01*
G02X174631Y549416I-1096J-1027D01*
G37*
G36*
G01X211469Y530667D02*
G03X211453Y530106I277J-289D01*
G02X209403I-1025J-956D01*
G03X209387Y530667I-293J272D01*
G02X209340Y532785I1041J1083D01*
G03X209334Y533342I-290J275D01*
G02X209361Y535482I1068J1057D01*
G03X209377Y536043I-277J289D01*
G02X211427I1025J956D01*
G03X211443Y535482I293J-272D01*
G02X211490Y533364I-1041J-1083D01*
G03X211496Y532807I290J-275D01*
G02X211469Y530667I-1068J-1057D01*
G37*
G36*
G01X174658D02*
G03X174642Y530106I277J-289D01*
G02X172592I-1025J-956D01*
G03X172576Y530667I-293J272D01*
G02X172529Y532785I1041J1083D01*
G03X172523Y533342I-290J275D01*
G02X172550Y535482I1068J1057D01*
G03X172566Y536043I-277J289D01*
G02X174616I1025J956D01*
G03X174632Y535482I293J-272D01*
G02X174679Y533364I-1041J-1083D01*
G03X174685Y532807I290J-275D01*
G02X174658Y530667I-1068J-1057D01*
G37*
G36*
G01X216547Y530461D02*
G03X216534Y529899I278J-288D01*
G02X214486Y529889I-1019J-963D01*
G03X214468Y530450I-293J271D01*
G02X214409Y532570I1034J1090D01*
G03Y533119I-291J274D01*
G02X214472Y535243I1093J1031D01*
G03X214493Y535804I-274J291D01*
G02X216543Y535783I1035J946D01*
G03X216553Y535222I290J-275D01*
G02X216595Y533119I-1051J-1073D01*
G03Y532570I291J-274D01*
G02X216547Y530461I-1093J-1030D01*
G37*
G36*
G01X179736D02*
G03X179723Y529899I278J-288D01*
G02X177675Y529889I-1019J-963D01*
G03X177657Y530450I-293J271D01*
G02X177598Y532570I1034J1090D01*
G03Y533119I-291J274D01*
G02X177661Y535243I1093J1031D01*
G03X177682Y535804I-274J291D01*
G02X179732Y535783I1035J946D01*
G03X179742Y535222I290J-275D01*
G02X179784Y533119I-1051J-1073D01*
G03Y532570I291J-274D01*
G02X179736Y530461I-1093J-1030D01*
G37*
G36*
G01X229706Y514234D02*
G03X229720Y514817I-267J298D01*
G02X231692I986J997D01*
G03X231706Y514234I281J-285D01*
G02X229706I-1000J-1120D01*
G37*
G36*
G01X224999Y514817D02*
G03X225013Y514234I281J-285D01*
G02X223013I-1000J-1120D01*
G03X223027Y514817I-267J298D01*
G02X224999I986J997D01*
G37*
G36*
G01X207567D02*
G03X207581Y514234I281J-285D01*
G02X205581I-1000J-1120D01*
G03X205595Y514817I-267J298D01*
G02X207567I986J997D01*
G37*
G36*
G01X201281Y514778D02*
G03X201308Y514217I298J-267D01*
G02X199227Y514177I-1020J-1103D01*
G03X199231Y514738I-283J283D01*
G02X201281Y514778I1006J976D01*
G37*
G36*
G01X192895Y514234D02*
G03X192909Y514817I-267J298D01*
G02X194881I986J997D01*
G03X194895Y514234I281J-285D01*
G02X192895I-1000J-1120D01*
G37*
G36*
G01X188188Y514817D02*
G03X188202Y514234I281J-285D01*
G02X186202I-1000J-1120D01*
G03X186216Y514817I-267J298D01*
G02X188188I986J997D01*
G37*
G36*
G01X177595Y513941D02*
G03Y514487I-292J273D01*
G02X177650Y516597I1096J1027D01*
G03X177666Y517158I-277J289D01*
G02X179716I1025J956D01*
G03X179732Y516597I293J-272D01*
G02X179787Y514487I-1041J-1083D01*
G03Y513941I292J-273D01*
G02X177595I-1096J-1027D01*
G37*
G36*
G01X216442Y511743D02*
G03X216423Y511136I251J-312D01*
G02X214551Y511151I-944J-1036D01*
G03X214542Y511759I-265J300D01*
G02X214406Y513941I960J1155D01*
G03Y514487I-292J273D01*
G02X214461Y516597I1096J1027D01*
G03X214477Y517158I-277J289D01*
G02X216527I1025J956D01*
G03X216543Y516597I293J-272D01*
G02X216598Y514487I-1041J-1083D01*
G03Y513941I292J-273D01*
G02X216442Y511743I-1096J-1027D01*
G37*
G36*
G01X209377Y511055D02*
G03X209362Y511616I-292J273D01*
G02X209306Y513727I1040J1084D01*
G03Y514273I-292J273D01*
G02X209351Y516373I1096J1027D01*
G03X209361Y516935I-280J286D01*
G02X211412Y516953I1017J965D01*
G03X211433Y516392I295J-270D01*
G02X211498Y514273I-1031J-1092D01*
G03Y513727I292J-273D01*
G02X211442Y511616I-1096J-1027D01*
G03X211427Y511055I277J-288D01*
G02X209377I-1025J-957D01*
G37*
G36*
G01X174631Y511616D02*
G03X174616Y511055I277J-288D01*
G02X172566I-1025J-957D01*
G03X172551Y511616I-292J273D01*
G02X172495Y513727I1040J1084D01*
G03Y514273I-292J273D01*
G02X172540Y516373I1096J1027D01*
G03X172550Y516935I-280J286D01*
G02X174601Y516953I1017J965D01*
G03X174622Y516392I295J-270D01*
G02X174687Y514273I-1031J-1092D01*
G03Y513727I292J-273D01*
G02X174631Y511616I-1096J-1027D01*
G37*
G36*
G01X135781Y605706D02*
G03X135765Y606267I-293J272D01*
G02X135718Y608385I1041J1083D01*
G03X135712Y608942I-290J275D01*
G02X135739Y611082I1068J1057D01*
G03X135755Y611643I-277J289D01*
G02X137805I1025J956D01*
G03X137821Y611082I293J-272D01*
G02X137868Y608964I-1041J-1083D01*
G03X137874Y608407I290J-275D01*
G02X137847Y606267I-1068J-1057D01*
G03X137831Y605706I277J-289D01*
G02X135781I-1025J-956D01*
G37*
G36*
G01X142925Y606061D02*
G03X142912Y605499I278J-288D01*
G02X140864Y605489I-1019J-963D01*
G03X140846Y606050I-293J271D01*
G02X140787Y608170I1034J1090D01*
G03Y608719I-291J274D01*
G02X140850Y610843I1093J1031D01*
G03X140871Y611404I-274J291D01*
G02X142921Y611383I1035J946D01*
G03X142931Y610822I290J-275D01*
G02X142973Y608719I-1051J-1073D01*
G03Y608170I291J-274D01*
G02X142925Y606061I-1093J-1030D01*
G37*
G36*
G01X116026Y591716D02*
G03X115998Y592320I-276J290D01*
G02X117910Y592364I929J1180D01*
G03Y591760I262J-302D01*
G02X116026Y591716I-918J-1060D01*
G37*
G36*
G01X170776Y590387D02*
G03X170791Y589816I287J-278D01*
G02X168749I-1021J-1102D01*
G03X168764Y590387I-272J293D01*
G02X170776I1006J977D01*
G37*
G36*
G01X164470Y590378D02*
G03X164497Y589817I298J-267D01*
G02X162416Y589777I-1020J-1103D01*
G03X162420Y590338I-283J283D01*
G02X164470Y590378I1006J976D01*
G37*
G36*
G01X156084Y589834D02*
G03X156098Y590417I-267J298D01*
G02X158070I986J997D01*
G03X158084Y589834I281J-285D01*
G02X156084I-1000J-1120D01*
G37*
G36*
G01X151377Y590417D02*
G03X151391Y589834I281J-285D01*
G02X149391I-1000J-1120D01*
G03X149405Y590417I-267J298D01*
G02X151377I986J997D01*
G37*
G36*
G01X133945D02*
G03X133959Y589834I281J-285D01*
G02X131959I-1000J-1120D01*
G03X131973Y590417I-267J298D01*
G02X133945I986J997D01*
G37*
G36*
G01X127659Y590378D02*
G03X127686Y589817I298J-267D01*
G02X125605Y589777I-1020J-1103D01*
G03X125609Y590338I-283J283D01*
G02X127659Y590378I1006J976D01*
G37*
G36*
G01X142820Y587343D02*
G03X142801Y586736I251J-312D01*
G02X140929Y586751I-944J-1036D01*
G03X140920Y587359I-265J300D01*
G02X140784Y589541I960J1155D01*
G03Y590087I-292J273D01*
G02X140839Y592197I1096J1027D01*
G03X140855Y592758I-277J289D01*
G02X142905I1025J956D01*
G03X142921Y592197I293J-272D01*
G02X142976Y590087I-1041J-1083D01*
G03Y589541I292J-273D01*
G02X142820Y587343I-1096J-1027D01*
G37*
G36*
G01X135755Y586655D02*
G03X135740Y587216I-292J273D01*
G02X135684Y589327I1040J1084D01*
G03Y589873I-292J273D01*
G02X135729Y591973I1096J1027D01*
G03X135739Y592535I-280J286D01*
G02X137790Y592553I1017J965D01*
G03X137811Y591992I295J-270D01*
G02X137876Y589873I-1031J-1092D01*
G03Y589327I292J-273D01*
G02X137820Y587216I-1096J-1027D01*
G03X137805Y586655I277J-288D01*
G02X135755I-1025J-957D01*
G37*
G36*
G01X135781Y567906D02*
G03X135765Y568467I-293J272D01*
G02X135718Y570585I1041J1083D01*
G03X135712Y571142I-290J275D01*
G02X135739Y573282I1068J1057D01*
G03X135755Y573843I-277J289D01*
G02X137805I1025J956D01*
G03X137821Y573282I293J-272D01*
G02X137868Y571164I-1041J-1083D01*
G03X137874Y570607I290J-275D01*
G02X137847Y568467I-1068J-1057D01*
G03X137831Y567906I277J-289D01*
G02X135781I-1025J-956D01*
G37*
G36*
G01X142925Y568261D02*
G03X142912Y567699I278J-288D01*
G02X140864Y567689I-1019J-963D01*
G03X140846Y568250I-293J271D01*
G02X140787Y570370I1034J1090D01*
G03Y570919I-291J274D01*
G02X140850Y573043I1093J1031D01*
G03X140871Y573604I-274J291D01*
G02X142921Y573583I1035J946D01*
G03X142931Y573022I290J-275D01*
G02X142973Y570919I-1051J-1073D01*
G03Y570370I291J-274D01*
G02X142925Y568261I-1093J-1030D01*
G37*
G36*
G01X170776Y552587D02*
G03X170791Y552016I287J-278D01*
G02X168749I-1021J-1102D01*
G03X168764Y552587I-272J293D01*
G02X170776I1006J977D01*
G37*
G36*
G01X164470Y552578D02*
G03X164497Y552017I298J-267D01*
G02X162416Y551977I-1020J-1103D01*
G03X162420Y552538I-283J283D01*
G02X164470Y552578I1006J976D01*
G37*
G36*
G01X156084Y552034D02*
G03X156098Y552617I-267J298D01*
G02X158070I986J997D01*
G03X158084Y552034I281J-285D01*
G02X156084I-1000J-1120D01*
G37*
G36*
G01X151377Y552617D02*
G03X151391Y552034I281J-285D01*
G02X149391I-1000J-1120D01*
G03X149405Y552617I-267J298D01*
G02X151377I986J997D01*
G37*
G36*
G01X133945D02*
G03X133959Y552034I281J-285D01*
G02X131959I-1000J-1120D01*
G03X131973Y552617I-267J298D01*
G02X133945I986J997D01*
G37*
G36*
G01X125605Y551977D02*
G03X125609Y552538I-283J283D01*
G02X127659Y552578I1006J976D01*
G03X127686Y552017I298J-267D01*
G02X125605Y551977I-1020J-1103D01*
G37*
G36*
G01X142820Y549543D02*
G03X142801Y548936I251J-312D01*
G02X140929Y548951I-944J-1036D01*
G03X140920Y549559I-265J300D01*
G02X140784Y551741I960J1155D01*
G03Y552287I-292J273D01*
G02X140839Y554397I1096J1027D01*
G03X140855Y554958I-277J289D01*
G02X142905I1025J956D01*
G03X142921Y554397I293J-272D01*
G02X142976Y552287I-1041J-1083D01*
G03Y551741I292J-273D01*
G02X142820Y549543I-1096J-1027D01*
G37*
G36*
G01X135755Y548855D02*
G03X135740Y549416I-292J273D01*
G02X135684Y551527I1040J1084D01*
G03Y552073I-292J273D01*
G02X135729Y554173I1096J1027D01*
G03X135739Y554735I-280J286D01*
G02X137790Y554753I1017J965D01*
G03X137811Y554192I295J-270D01*
G02X137876Y552073I-1031J-1092D01*
G03Y551527I292J-273D01*
G02X137820Y549416I-1096J-1027D01*
G03X137805Y548855I277J-288D01*
G02X135755I-1025J-957D01*
G37*
G36*
G01X135781Y530106D02*
G03X135765Y530667I-293J272D01*
G02X135718Y532785I1041J1083D01*
G03X135712Y533342I-290J275D01*
G02X135739Y535482I1068J1057D01*
G03X135755Y536043I-277J289D01*
G02X137805I1025J956D01*
G03X137821Y535482I293J-272D01*
G02X137868Y533364I-1041J-1083D01*
G03X137874Y532807I290J-275D01*
G02X137847Y530667I-1068J-1057D01*
G03X137831Y530106I277J-289D01*
G02X135781I-1025J-956D01*
G37*
G36*
G01X142925Y530461D02*
G03X142912Y529899I278J-288D01*
G02X140864Y529889I-1019J-963D01*
G03X140846Y530450I-293J271D01*
G02X140787Y532570I1034J1090D01*
G03Y533119I-291J274D01*
G02X140850Y535243I1093J1031D01*
G03X140871Y535804I-274J291D01*
G02X142921Y535783I1035J946D01*
G03X142931Y535222I290J-275D01*
G02X142973Y533119I-1051J-1073D01*
G03Y532570I291J-274D01*
G02X142925Y530461I-1093J-1030D01*
G37*
G36*
G01X170776Y514787D02*
G03X170791Y514216I287J-278D01*
G02X168749I-1021J-1102D01*
G03X168764Y514787I-272J293D01*
G02X170776I1006J977D01*
G37*
G36*
G01X164470Y514778D02*
G03X164497Y514217I298J-267D01*
G02X162416Y514177I-1020J-1103D01*
G03X162420Y514738I-283J283D01*
G02X164470Y514778I1006J976D01*
G37*
G36*
G01X156084Y514234D02*
G03X156098Y514817I-267J298D01*
G02X158070I986J997D01*
G03X158084Y514234I281J-285D01*
G02X156084I-1000J-1120D01*
G37*
G36*
G01X151377Y514817D02*
G03X151391Y514234I281J-285D01*
G02X149391I-1000J-1120D01*
G03X149405Y514817I-267J298D01*
G02X151377I986J997D01*
G37*
G36*
G01X133945D02*
G03X133959Y514234I281J-285D01*
G02X131959I-1000J-1120D01*
G03X131973Y514817I-267J298D01*
G02X133945I986J997D01*
G37*
G36*
G01X125605Y514177D02*
G03X125609Y514738I-283J283D01*
G02X127659Y514778I1006J976D01*
G03X127686Y514217I298J-267D01*
G02X125605Y514177I-1020J-1103D01*
G37*
G36*
G01X142820Y511743D02*
G03X142801Y511136I251J-312D01*
G02X140929Y511151I-944J-1036D01*
G03X140920Y511759I-265J300D01*
G02X140784Y513941I960J1155D01*
G03Y514487I-292J273D01*
G02X140839Y516597I1096J1027D01*
G03X140855Y517158I-277J289D01*
G02X142905I1025J956D01*
G03X142921Y516597I293J-272D01*
G02X142976Y514487I-1041J-1083D01*
G03Y513941I292J-273D01*
G02X142820Y511743I-1096J-1027D01*
G37*
G36*
G01X135755Y511055D02*
G03X135740Y511616I-292J273D01*
G02X135684Y513727I1040J1084D01*
G03Y514273I-292J273D01*
G02X135729Y516373I1096J1027D01*
G03X135739Y516935I-280J286D01*
G02X137790Y516953I1017J965D01*
G03X137811Y516392I295J-270D01*
G02X137876Y514273I-1031J-1092D01*
G03Y513727I292J-273D01*
G02X137820Y511616I-1096J-1027D01*
G03X137805Y511055I277J-288D01*
G02X135755I-1025J-957D01*
G37*
G36*
G01X92680Y619112D02*
G02X92697Y617091I1120J-1001D01*
G03X92140Y617120I-293J-272D01*
G02X89653Y618377I-990J1130D01*
G03X89277Y618810I-398J34D01*
G02X88140Y619433I83J1500D01*
G03X87482Y619421I-325J-233D01*
G02X87450Y621127I-1252J830D01*
G03X88108Y621139I325J233D01*
G02X90211Y621548I1252J-829D01*
G03X90774Y621660I227J329D01*
G02X92371Y619562I1178J-760D01*
G03X92280Y619239I59J-191D01*
G02X92369Y619128I-1126J-994D01*
G03X92680Y619112I162J117D01*
G37*
G36*
G01X100596Y609843D02*
G02X99822Y611752I-5914J-1286D01*
G03X100547Y611857I339J211D01*
G02X101047Y612597I1351J-374D01*
G03X101105Y613178I-243J318D01*
G02X103253Y615272I1130J989D01*
G03X103852Y615337I271J294D01*
G02X104100Y613458I1148J-804D01*
G03X103506Y613365I-256J-307D01*
G02X103086Y612929I-1269J803D01*
G03X102999Y612351I227J-330D01*
G02X101189Y610273I-1101J-868D01*
G03X100596Y609843I-202J-345D01*
G37*
G36*
G01X90087Y523218D02*
G03X90675Y523142I328J229D01*
G02X90418Y521141I975J-1142D01*
G03X89830Y521217I-328J-229D01*
G02X90087Y523218I-975J1142D01*
G37*
G36*
G01X193499Y359219D02*
G03X192922Y359213I-286J-280D01*
G02X192901Y361154I-1022J960D01*
G03X193478Y361160I286J280D01*
G02X195472Y361211I1022J-960D01*
G03X196057Y361244I277J288D01*
G02X196165Y359339I1080J-894D01*
G03X195580Y359306I-277J-288D01*
G02X193499Y359219I-1080J894D01*
G37*
G36*
G01X417627Y339572D02*
G03X418248Y339563I314J248D01*
G02X418221Y337669I1152J-964D01*
G03X417600Y337678I-314J-248D01*
G02X415461Y337509I-1152J963D01*
G03X414935I-263J-302D01*
G02X412763Y337718I-987J1132D01*
G03X412133I-315J-246D01*
G02Y339564I-1185J923D01*
G03X412763I315J246D01*
G02X414935Y339773I1185J-923D01*
G03X415461I263J302D01*
G02X417627Y339572I987J-1132D01*
G37*
G36*
G01X399963Y337418D02*
G03X399333I-315J-246D01*
G02Y339264I-1185J923D01*
G03X399963I315J246D01*
G02X402135Y339473I1185J-923D01*
G03X402661I263J302D01*
G02Y337209I987J-1132D01*
G03X402135I-263J-302D01*
G02X399963Y337418I-987J1132D01*
G37*
G36*
G01X193564Y331470D02*
G03X193010I-277J-288D01*
G02Y333490I-973J1010D01*
G03X193564I277J288D01*
G02X195510I973J-1010D01*
G03X196064I277J288D01*
G02Y331470I973J-1010D01*
G03X195510I-277J-288D01*
G02X193564I-973J1010D01*
G37*
G36*
G01X434694Y323112D02*
G03X434094I-300J-265D01*
G02Y325234I-1200J1061D01*
G03X434694I300J265D01*
G02Y323112I1200J-1061D01*
G37*
G36*
G01X427494D02*
G03X426894I-300J-265D01*
G02Y325234I-1200J1061D01*
G03X427494I300J265D01*
G02Y323112I1200J-1061D01*
G37*
G36*
G01X367579Y311230D02*
G03X367069Y311072I-167J-363D01*
G02X366528Y313260I-1376J821D01*
G03X367053Y313358I208J342D01*
G02X369157Y313494I1112J-854D01*
G03X369709Y313480I283J283D01*
G02X371644Y313430I941J-1039D01*
G03X372201Y313421I283J282D01*
G02X374123I961J-1021D01*
G03X374680Y313430I274J291D01*
G02X376640Y313458I994J-989D01*
G03X377190I275J290D01*
G02Y311424I966J-1017D01*
G03X376640I-275J-290D01*
G02X374713Y311420I-966J1017D01*
G03X374156Y311411I-274J-291D01*
G02X372168I-994J989D01*
G03X371611Y311420I-283J-282D01*
G02X369658Y311451I-961J1021D01*
G03X369106Y311465I-283J-283D01*
G02X367579Y311230I-941J1039D01*
G37*
G36*
G01X193564Y298740D02*
G03X193010I-277J-288D01*
G02Y300760I-973J1010D01*
G03X193564I277J288D01*
G02X195510I973J-1010D01*
G03X196064I277J288D01*
G02Y298740I973J-1010D01*
G03X195510I-277J-288D01*
G02X193564I-973J1010D01*
G37*
G36*
G01X398694Y294843D02*
G03X398094I-300J-265D01*
G02Y296965I-1200J1061D01*
G03X398694I300J265D01*
G02Y294843I1200J-1061D01*
G37*
G36*
G01X391494D02*
G03X390894I-300J-265D01*
G02Y296965I-1200J1061D01*
G03X391494I300J265D01*
G02Y294843I1200J-1061D01*
G37*
G36*
G01X384294D02*
G03X383694I-300J-265D01*
G02Y296965I-1200J1061D01*
G03X384294I300J265D01*
G02Y294843I1200J-1061D01*
G37*
G36*
G01X377094D02*
G03X376494I-300J-265D01*
G02Y296965I-1200J1061D01*
G03X377094I300J265D01*
G02Y294843I1200J-1061D01*
G37*
G36*
G01X369894D02*
G03X369294I-300J-265D01*
G02Y296965I-1200J1061D01*
G03X369894I300J265D01*
G02Y294843I1200J-1061D01*
G37*
G36*
G01X391494Y277843D02*
G03X390894I-300J-265D01*
G02Y279965I-1200J1061D01*
G03X391494I300J265D01*
G02Y277843I1200J-1061D01*
G37*
G36*
G01X377094D02*
G03X376494I-300J-265D01*
G02Y279965I-1200J1061D01*
G03X377094I300J265D01*
G02Y277843I1200J-1061D01*
G37*
G36*
G01X369894D02*
G03X369294I-300J-265D01*
G02Y279965I-1200J1061D01*
G03X369894I300J265D01*
G02Y277843I1200J-1061D01*
G37*
G36*
G01X193564Y269740D02*
G03X193010I-277J-288D01*
G02Y271760I-973J1010D01*
G03X193564I277J288D01*
G02X195510I973J-1010D01*
G03X196064I277J288D01*
G02Y269740I973J-1010D01*
G03X195510I-277J-288D01*
G02X193564I-973J1010D01*
G37*
G36*
G01X381946Y272676D02*
G03Y272076I265J-300D01*
G02X379824I-1061J-1200D01*
G03Y272676I-265J300D01*
G02X381946I1061J1200D01*
G37*
G36*
G01X399209Y263976D02*
G03X398579I-315J-246D01*
G02Y265822I-1185J923D01*
G03X399209I315J246D01*
G02Y263976I1185J-923D01*
G37*
G36*
G01X392709D02*
G03X392079I-315J-246D01*
G02Y265822I-1185J923D01*
G03X392709I315J246D01*
G02Y263976I1185J-923D01*
G37*
G36*
G01X198627Y239616D02*
G03Y239062I288J-277D01*
G02X196607I-1010J-973D01*
G03Y239616I-288J277D01*
G02Y241562I1010J973D01*
G03Y242116I-288J277D01*
G02X198627I1010J973D01*
G03Y241562I288J-277D01*
G02Y239616I-1010J-973D01*
G37*
G36*
G01X192547Y239516D02*
G03Y238962I288J-277D01*
G02X190527I-1010J-973D01*
G03Y239516I-288J277D01*
G02Y241462I1010J973D01*
G03Y242016I-288J277D01*
G02X192547I1010J973D01*
G03Y241462I288J-277D01*
G02Y239516I-1010J-973D01*
G37*
G36*
G01X386654Y323068D02*
G02Y325278I-1160J1105D01*
G03X387234I290J275D01*
G02X389494Y325337I1160J-1105D01*
G03X390044I275J291D01*
G02X392244I1100J-1164D01*
G03X392794I275J291D01*
G02X395094Y325234I1100J-1164D01*
G03X395694I300J265D01*
G02X398094I1200J-1061D01*
G03X398694I300J265D01*
G02X401094I1200J-1061D01*
G03X401694I300J265D01*
G02X404094I1200J-1061D01*
G03X404694I300J265D01*
G02X407094I1200J-1061D01*
G03X407694I300J265D01*
G02X410094I1200J-1061D01*
G03X410694I300J265D01*
G02X413094I1200J-1061D01*
G03X413694I300J265D01*
G02X416334Y324874I1200J-1061D01*
G03X417054I360J175D01*
G02X419694Y325234I1440J-701D01*
G03X420294I300J265D01*
G02Y323112I1200J-1061D01*
G03X419694I-300J-265D01*
G02X417054Y323472I-1200J1061D01*
G03X416334I-360J-175D01*
G02X413694Y323112I-1440J701D01*
G03X413094I-300J-265D01*
G02X410694I-1200J1061D01*
G03X410094I-300J-265D01*
G02X407694I-1200J1061D01*
G03X407094I-300J-265D01*
G02X404694I-1200J1061D01*
G03X404094I-300J-265D01*
G02X401694I-1200J1061D01*
G03X401094I-300J-265D01*
G02X398694I-1200J1061D01*
G03X398094I-300J-265D01*
G02X395694I-1200J1061D01*
G03X395094I-300J-265D01*
G02X392794Y323009I-1200J1061D01*
G03X392244I-275J-291D01*
G02X390044I-1100J1164D01*
G03X389494I-275J-291D01*
G02X387234Y323068I-1100J1164D01*
G03X386654I-290J-275D01*
G37*
G36*
G01X384661Y279438D02*
G02X384467Y277861I1284J-958D01*
G03X383778Y277946I-369J-154D01*
G02X383972Y279523I-1284J958D01*
G03X384661Y279438I369J154D01*
G37*
G36*
G01X175831Y403321D02*
G02X175784Y404774I-1222J688D01*
G03X176467Y404797I335J219D01*
G02X178913Y404794I1222J-688D01*
G03X179603Y404780I349J195D01*
G02X179575Y403364I1196J-732D01*
G03X178885Y403378I-349J-195D01*
G02X176514Y403344I-1196J731D01*
G03X175831Y403321I-335J-219D01*
G37*
G36*
G01X196210Y379327D02*
G03Y378773I288J-277D01*
G02X194190I-1010J-973D01*
G03Y379327I-288J277D01*
G02X196210I1010J973D01*
G37*
G36*
G01X412516Y364647D02*
G03X412494Y364092I277J-289D01*
G02X410478Y364173I-1047J-932D01*
G03X410500Y364728I-277J289D01*
G02X410576Y366671I1047J932D01*
G03Y367249I-277J289D01*
G02X412518I971J1011D01*
G03Y366671I277J-289D01*
G02X412516Y364647I-971J-1011D01*
G37*
G36*
G01X445956Y262596D02*
G02X443997Y262340I-833J-1250D01*
G03X443919Y262938I-300J265D01*
G02X443771Y265325I833J1250D01*
G03X443699Y265981I-261J303D01*
G02X445389Y266168I709J1324D01*
G03X445461Y265512I261J-303D01*
G02X445878Y263194I-709J-1324D01*
G03X445956Y262596I300J-265D01*
G37*
G36*
G01X449580Y264344D02*
G02X448046Y264728I-1077J-1047D01*
G03X448211Y265388I-121J381D01*
G02X448391Y267640I1077J1047D01*
G03X448318Y268324I-239J320D01*
G02X449773Y268503I582J1276D01*
G03X449867Y267821I249J-313D01*
G02X450726Y266868I-579J-1386D01*
G03X451272Y266618I383J115D01*
G02X450445Y264813I611J-1372D01*
G03X449899Y265063I-383J-115D01*
G02X449745Y265004I-614J1371D01*
G03X449580Y264344I121J-381D01*
G37*
G36*
G01X451827Y274504D02*
G02X449761Y276685I-1027J1096D01*
G03X449561Y277367I-276J289D01*
G02X448782Y277783I287J1474D01*
G03X448214I-284J-282D01*
G02Y279899I-1066J1058D01*
G03X448782I284J282D01*
G02X450887Y277756I1066J-1058D01*
G03X451087Y277074I276J-289D01*
G02X451827Y276696I-287J-1474D01*
G03X452373I273J292D01*
G02Y274504I1027J-1096D01*
G03X451827I-273J-292D01*
G37*
G36*
G01X437620Y263877D02*
G03X437658Y263359I322J-237D01*
G02X435228Y263181I-1139J-1127D01*
G03X435190Y263699I-322J237D01*
G02X437620Y263877I1139J1127D01*
G37*
G36*
G01X441151Y265147D02*
G03X440996Y264558I174J-361D01*
G02X439113Y265052I-1232J-859D01*
G03X439268Y265641I-174J361D01*
G02X441151Y265147I1232J859D01*
G37*
G36*
G01X430961Y265722D02*
G03X431548Y265678I314J248D01*
G02X431339Y263577I1095J-1170D01*
G03X430755Y263649I-325J-233D01*
G02X430961Y265722I-974J1144D01*
G37*
G36*
G01X459399Y277949D02*
G03X459398Y277385I283J-283D01*
G02X457409Y277391I-997J-985D01*
G03X457410Y277955I-283J283D01*
G02X459399Y277949I997J985D01*
G37*
G36*
G01X441894Y277843D02*
G03X441294I-300J-265D01*
G02Y279965I-1200J1061D01*
G03X441894I300J265D01*
G02Y277843I1200J-1061D01*
G37*
G36*
G01X420335Y277870D02*
G03X419735Y277863I-297J-268D01*
G02X419711Y279984I-1212J1047D01*
G03X420311Y279991I297J268D01*
G02X420335Y277870I1212J-1047D01*
G37*
G36*
G01X427494Y277849D02*
G03X426894I-300J-265D01*
G02Y279971I-1200J1061D01*
G03X427494I300J265D01*
G02Y277849I1200J-1061D01*
G37*
G36*
G01X434704Y277866D02*
G03X434104Y277860I-297J-268D01*
G02X434084Y279982I-1210J1050D01*
G03X434684Y279988I297J268D01*
G02X434704Y277866I1210J-1050D01*
G37*
G36*
G01X468864Y287326D02*
G02X468576Y285975I1049J-930D01*
G03X467887Y286111I-382J-120D01*
G02X468179Y287482I-1153J962D01*
G03X468864Y287326I385J109D01*
G37*
G36*
G01X455287Y293287D02*
G02X453794Y290967I-61J-1601D01*
G03X453085Y290978I-357J-179D01*
G02X450200Y291115I-1410J761D01*
G03X449695Y291335I-368J-156D01*
G02X447972Y291753I-547J1506D01*
G03X447385Y291754I-294J-271D01*
G02X445221Y294103I-1176J1088D01*
G03X445256Y294702I-246J315D01*
G02X445050Y294953I1129J1137D01*
G03X444392Y294966I-334J-221D01*
G02X441894Y294843I-1298J938D01*
G03X441294I-300J-265D01*
G02Y296965I-1200J1061D01*
G03X441894I300J265D01*
G02X444427Y296792I1200J-1061D01*
G03X445085Y296779I334J221D01*
G02X447371Y294580I1299J-938D01*
G03X447336Y293981I246J-315D01*
G02X447385Y293930I-1131J-1135D01*
G03X447972Y293929I294J271D01*
G02X450623Y293465I1176J-1088D01*
G03X451128Y293245I368J156D01*
G02X451534Y293335I547J-1506D01*
G03X451898Y293723I-36J398D01*
G02X451910Y293875I1502J-42D01*
G03X451574Y294320I-397J50D01*
G02X453079Y296889I242J1584D01*
G03X453700Y296877I315J246D01*
G02X455219Y294267I1222J-1036D01*
G03X454895Y293834I74J-393D01*
G02X454902Y293686I-1495J-145D01*
G03X455287Y293287I400J1D01*
G37*
G36*
G01X465497Y294379D02*
G03X465932Y293948I399J-33D01*
G02X464569Y292573I134J-1496D01*
G03X464134Y293004I-399J33D01*
G02X465497Y294379I-134J1496D01*
G37*
G36*
G01X420294Y294843D02*
G03X419694I-300J-265D01*
G02Y296965I-1200J1061D01*
G03X420294I300J265D01*
G02Y294843I1200J-1061D01*
G37*
G36*
G01X427494D02*
G03X426894I-300J-265D01*
G02Y296965I-1200J1061D01*
G03X427494I300J265D01*
G02Y294843I1200J-1061D01*
G37*
G36*
G01X434694D02*
G03X434094I-300J-265D01*
G02Y296965I-1200J1061D01*
G03X434694I300J265D01*
G02Y294843I1200J-1061D01*
G37*
G36*
G01X510564Y259018D02*
G03X510207Y258602I43J-398D01*
G02X508544Y260025I-1500J-70D01*
G03X508901Y260441I-43J398D01*
G02X510564Y259018I1500J70D01*
G37*
G36*
G01X578866Y203940D02*
G03X579312Y203494I397J-49D01*
G02X578006Y202188I185J-1491D01*
G03X577560Y202634I-397J49D01*
G02X578866Y203940I-185J1491D01*
G37*
G36*
G01X562230Y207440D02*
G03X562676Y206994I397J-49D01*
G02X561370Y205688I185J-1491D01*
G03X560924Y206134I-397J49D01*
G02X562230Y207440I-185J1491D01*
G37*
G36*
G01X565401Y213453D02*
G03X565854Y213044I400J-12D01*
G02X564550Y211602I197J-1489D01*
G03X564097Y212011I-400J12D01*
G02X565401Y213453I-197J1489D01*
G37*
G36*
G01X580917Y218515D02*
G03X580471Y218069I-49J-397D01*
G02X579165Y219375I-1491J-185D01*
G03X579611Y219821I49J397D01*
G02X580917Y218515I1491J185D01*
G37*
G36*
G01X571697Y229557D02*
G03X572258Y229360I369J154D01*
G02X571637Y227588I672J-1230D01*
G03X571076Y227785I-369J-154D01*
G02X569455Y230047I-672J1230D01*
G03X569483Y230608I-270J295D01*
G02X571043Y232847I1045J935D01*
G03X571576Y233115I147J372D01*
G02X572415Y231446I1354J-365D01*
G03X571882Y231178I-147J-372D01*
G02X571477Y230511I-1354J365D01*
G03X571449Y229950I270J-295D01*
G02X571697Y229557I-1045J-934D01*
G37*
G36*
G01X579182Y231552D02*
G03X579740Y231317I381J124D01*
G02X579027Y229627I620J-1257D01*
G03X578469Y229862I-381J-124D01*
G02X576876Y232128I-619J1257D01*
G03X576872Y232707I-278J288D01*
G02X578512Y234955I960J1022D01*
G03X579073Y235146I194J350D01*
G02X579680Y233364I1287J-556D01*
G03X579119Y233173I-194J-350D01*
G02X578805Y232720I-1287J557D01*
G03X578809Y232141I278J-288D01*
G02X579182Y231552I-961J-1021D01*
G37*
G36*
G01X568789Y244539D02*
G03X569335Y244559I262J302D01*
G02X569350Y242426I1065J-1059D01*
G03X568804Y242438I-279J-286D01*
G02X566796Y242579I-936J1044D01*
G03X566187Y242582I-306J-258D01*
G02X564139Y242499I-1063J914D01*
G03X563576I-282J-285D01*
G02Y244493I-985J997D01*
G03X564139I282J285D01*
G02X566196Y244399I985J-997D01*
G03X566805Y244396I306J258D01*
G02X568789Y244539I1063J-914D01*
G37*
G36*
G01X574890Y258091D02*
G03X574335Y257936I-203J-345D01*
G02X573810Y259809I-1235J664D01*
G03X574365Y259964I203J345D01*
G02X574590Y260273I1235J-663D01*
G03Y260827I-288J277D01*
G02X574351Y261164I1012J971D01*
G03X573818Y261341I-356J-182D01*
G02X574449Y263236I-618J1258D01*
G03X574982Y263059I356J182D01*
G02X576610Y260827I619J-1258D01*
G03Y260273I288J-277D01*
G02X574890Y258091I-1009J-973D01*
G37*
G36*
G01X566278Y264312D02*
G03X565739Y264144I-185J-355D01*
G02X565148Y266043I-1239J656D01*
G03X565687Y266211I185J355D01*
G02X565916Y266528I1240J-655D01*
G03Y267082I-288J277D01*
G02X565690Y267393I1011J972D01*
G03X565152Y267559I-353J-189D01*
G02X565736Y269462I-652J1241D01*
G03X566274Y269296I353J189D01*
G02X567936Y267082I652J-1241D01*
G03Y266528I288J-277D01*
G02X566278Y264312I-1010J-973D01*
G37*
G36*
G01X557887Y284909D02*
G03X557651Y285415I-377J132D01*
G02X559319Y287494I494J1312D01*
G03X559927Y287420I335J218D01*
G02X560979Y284997I957J-1024D01*
G03X560608Y284565I28J-399D01*
G02X557887Y284909I-1397J-118D01*
G37*
G36*
G01X692363Y204304D02*
G02X690790Y205817I-1502J13D01*
G03X691171Y206213I-19J400D01*
G01Y206214D01*
G03X690790Y206617I-400J3D01*
G02X690655Y209605I71J1500D01*
G03X691000Y210022I-54J396D01*
G02X690999Y210047I1500J73D01*
G03X690654Y210429I-400J-14D01*
G02X690664Y213406I207J1488D01*
G03X691011Y213802I-53J396D01*
G01Y213825D01*
G03X690664Y214228I-400J7D01*
G02X690628Y217201I197J1489D01*
G03X690952Y217702I-62J395D01*
G02X691046Y218750I1448J398D01*
G03X690722Y219321I-361J173D01*
G02X689729Y221804I139J1496D01*
G03Y222330I-302J263D01*
G02X691993I1132J987D01*
G03Y221804I302J-263D01*
G02X692215Y220167I-1132J-987D01*
G03X692539Y219596I361J-173D01*
G02X692598Y219589I-147J-1495D01*
G03X693010Y220160I52J396D01*
G02X693229Y221804I1351J657D01*
G03Y222330I-302J263D01*
G02X695493I1132J987D01*
G03Y221804I302J-263D01*
G02X694163Y219328I-1132J-987D01*
G03X693751Y218757I-52J-396D01*
G02X692633Y216616I-1351J-657D01*
G03X692309Y216115I62J-395D01*
G02X692363Y215692I-1448J-400D01*
G03X692710Y215289I400J-7D01*
G02Y212311I-197J-1489D01*
G03X692363Y211915I53J-396D01*
G02X692360Y211814I-1502J-6D01*
G03X692553Y211601I200J-13D01*
G02X692706Y208612I-53J-1501D01*
G03X692361Y208195I54J-396D01*
G02X692363Y208103I-1500J-79D01*
G03X692744Y207700I400J-3D01*
G02Y204700I-71J-1500D01*
G03X692363Y204304I19J-400D01*
G37*
G36*
G01X725999Y189785D02*
G03X726623Y189773I317J244D01*
G02X726547Y187947I1153J-963D01*
G03X725925Y187986I-327J-230D01*
G02X725999Y189785I-1037J944D01*
G37*
G36*
G01X688060Y195614D02*
G03X687506I-277J-288D01*
G02Y197634I-973J1010D01*
G03X688060I277J288D01*
G02X690025Y197615I973J-1010D01*
G03X690591I283J282D01*
G02Y195633I992J-991D01*
G03X690025I-283J-282D01*
G02X688060Y195614I-992J991D01*
G37*
G36*
G01X711953Y200102D02*
G02X710601Y198645I-2753J1198D01*
G02X707899Y198176I-1401J54D01*
G03X707419Y198412I-371J-149D01*
G02X703957Y202723I-819J2888D01*
G02X704122Y205967I2604J1494D01*
G02X704135Y209649I2378J1833D01*
G02X705055Y214014I2426J1768D01*
G03X705136Y214271I-100J173D01*
G02X705368Y215887I1364J629D01*
G03Y216413I-302J263D01*
G02X705398Y218421I1132J987D01*
G03X705411Y218950I-293J272D01*
G02X707663Y218896I1150J967D01*
G03X707650Y218367I293J-272D01*
G02X707632Y216413I-1150J-966D01*
G03Y215887I302J-263D01*
G02X707885Y214319I-1132J-987D01*
G01X707855Y214247D01*
X707907Y214101D01*
X707975Y214065D01*
G02X708926Y209568I-1414J-2648D01*
G02X709467Y207342I-2426J-1768D01*
G03X709782Y206889I395J-61D01*
G02X711313Y206062I-600J-2941D01*
G02X711953Y200102I488J-2962D01*
G37*
G36*
G01X688060Y199114D02*
G03X687506I-277J-288D01*
G02Y201134I-973J1010D01*
G03X688060I277J288D01*
G02X690025Y201115I973J-1010D01*
G03X690591I283J282D01*
G02Y199133I992J-991D01*
G03X690025I-283J-282D01*
G02X688060Y199114I-992J991D01*
G37*
G36*
G01X715737Y215142D02*
G03X715886Y214624I358J-177D01*
G02X713754Y214011I-786J-1280D01*
G03X713605Y214529I-358J177D01*
G02X714024Y217266I786J1280D01*
G03X714305Y217782I-97J388D01*
G02X716094Y216810I1422J485D01*
G03X715813Y216294I97J-388D01*
G02X715737Y215142I-1422J-485D01*
G37*
G36*
G01X714855Y222613D02*
G02X712666Y222529I-1055J-1069D01*
G03X712645Y223075I-302J262D01*
G02X712348Y223490I1055J1069D01*
G03X711675Y223565I-360J-174D01*
G02X711852Y225154I-1175J935D01*
G03X712525Y225079I360J174D01*
G02X714834Y223159I1175J-935D01*
G03X714855Y222613I302J-262D01*
G37*
G36*
G01X670949Y223070D02*
G02X670874Y225008I-1049J930D01*
G03X671451Y225030I278J288D01*
G02X673550Y225029I1049J-930D01*
G03X674150I300J265D01*
G02X676445Y224745I1050J-929D01*
G03X677155I355J184D01*
G02Y223455I1245J-645D01*
G03X676445I-355J-184D01*
G02X674150Y223171I-1245J645D01*
G03X673550I-300J-265D01*
G02X671526Y223092I-1050J929D01*
G03X670949Y223070I-278J-288D01*
G37*
G36*
G01X706508Y227156D02*
G02X706395Y225728I1145J-809D01*
G03X705703Y225771I-358J-177D01*
G02X703364Y225562I-1253J829D01*
G03X702786I-289J-276D01*
G02Y227638I-1086J1038D01*
G03X703364I289J276D01*
G02X705817Y227222I1086J-1038D01*
G03X706508Y227156I364J165D01*
G37*
G36*
G01X669267Y231423D02*
G02Y232977I-1167J777D01*
G03X669933I333J222D01*
G02X672345Y232845I1167J-777D01*
G03X673055I355J184D01*
G02X675483Y232953I1245J-645D01*
G03X676171Y232975I337J214D01*
G02X676217Y231547I1229J-675D01*
G03X675529Y231525I-337J-214D01*
G02X673055Y231555I-1229J675D01*
G03X672345I-355J-184D01*
G02X669933Y231423I-1245J645D01*
G03X669267I-333J-222D01*
G37*
G36*
G01X729017Y237701D02*
G02X726943Y237725I-1048J-931D01*
G03X726949Y238264I-293J273D01*
G02X726661Y239620I1048J931D01*
G03X726163Y240123I-381J121D01*
G02X727143Y241065I-438J1437D01*
G03X727626Y240547I378J-132D01*
G02X729023Y238240I371J-1352D01*
G03X729017Y237701I293J-273D01*
G37*
G36*
G01X720388Y240551D02*
G03X720378Y240018I293J-272D01*
G02X718287Y240057I-1063J-914D01*
G03X718297Y240590I-293J272D01*
G02X720388Y240551I1063J914D01*
G37*
G36*
G01X751253Y204027D02*
G03X750699I-277J-288D01*
G02X748716Y206010I-973J1010D01*
G03Y206564I-288J277D01*
G02X750699Y208547I1010J973D01*
G03X751253I277J288D01*
G02X753199I973J-1010D01*
G03X753753I277J288D01*
G02X755736Y206564I973J-1010D01*
G03Y206010I288J-277D01*
G02X753753Y204027I-1010J-973D01*
G03X753199I-277J-288D01*
G02X751253I-973J1010D01*
G37*
G36*
G01X637881Y287185D02*
G03X637839Y286610I255J-308D01*
G02X636064Y286864I-1040J-940D01*
G03X636087Y287187I-105J170D01*
G02X635967Y287300I900J1076D01*
G03X635645Y287257I-146J-137D01*
G02X635280Y289012I-1238J658D01*
G03X635852Y289090I249J313D01*
G02X637881Y287185I1133J-827D01*
G37*
G36*
G01X629922Y287956D02*
G02X629175Y289074I-1397J-125D01*
G03X629758Y289475I186J354D01*
G02X630516Y288340I1492J176D01*
G03X629922Y287956I-196J-349D01*
G37*
G36*
G01X621974Y254930D02*
G03X621904Y254340I231J-327D01*
G02X620041Y254561I-1054J-924D01*
G03X620111Y255151I-231J327D01*
G02X621974Y254930I1054J924D01*
G37*
G36*
G01X631752Y247132D02*
G03X631199Y247116I-268J-297D01*
G02X631140Y249140I-999J984D01*
G03X631693Y249156I268J297D01*
G02X631752Y247132I999J-984D01*
G37*
G36*
G01X643772Y262245D02*
G02X641828I-972J-1145D01*
G03Y262855I-259J305D01*
G02X642264Y265403I972J1145D01*
G03X642430Y266030I-143J373D01*
G02X642310Y267768I1161J953D01*
G03X642156Y268331I-341J209D01*
G02X642144Y270983I699J1329D01*
G03X642298Y271541I-189J352D01*
G02X642477Y273220I1202J721D01*
G03X642461Y273783I-292J273D01*
G02X644539I1039J1085D01*
G03X644523Y273220I276J-290D01*
G02X644226Y271063I-1023J-958D01*
G03X644102Y270498I208J-342D01*
G02X644136Y268875I-1247J-838D01*
G03X644290Y268312I341J-209D01*
G02X644127Y265580I-699J-1329D01*
G03X643961Y264953I143J-373D01*
G02X643772Y262855I-1161J-953D01*
G03Y262245I259J-305D01*
G37*
G36*
G01X463914Y314235D02*
G03X463891Y313677I275J-291D01*
G02X461882Y313757I-1043J-936D01*
G03X461905Y314315I-275J291D01*
G02X463914Y314235I1043J936D01*
G37*
G36*
G01X678779Y364798D02*
G03X679038Y364209I347J-199D01*
G02X677514Y363539I-308J-1368D01*
G03X677255Y364128I-347J199D01*
G02X678779Y364798I308J1368D01*
G37*
G36*
G01X696398Y353462D02*
G03X696449Y352760I215J-337D01*
G02X695006Y352697I-659J-1460D01*
G03X694996Y353401I-195J349D01*
G02X694719Y355697I648J1243D01*
G03X694731Y356287I-264J300D01*
G02X696625Y356247I969J1013D01*
G03X696613Y355657I264J-300D01*
G02X696398Y353462I-969J-1013D01*
G37*
G36*
G01X700087Y339969D02*
G02X700168Y337953I1013J-969D01*
G03X699613Y337931I-266J-299D01*
G02X699532Y339947I-1013J969D01*
G03X700087Y339969I266J299D01*
G37*
G36*
G01X686276Y318995D02*
G02X688320Y318775I1124J838D01*
G03X688262Y318235I263J-301D01*
G02X686218Y318455I-1124J-838D01*
G03X686276Y318995I-263J301D01*
G37*
G36*
G01X712960Y309887D02*
G02X714980I1010J973D01*
G03Y309333I288J-277D01*
G02X712960I-1010J-973D01*
G03Y309887I-288J277D01*
G37*
G36*
G01X688137Y327007D02*
G03X688114Y326341I210J-341D01*
G02X686563Y326393I-815J-1141D01*
G03X686586Y327059I-210J341D01*
G02X688137Y327007I815J1141D01*
G37*
G36*
G01X672085Y298960D02*
G03X672778Y298889I367J160D01*
G02X672637Y297518I1144J-810D01*
G03X671944Y297589I-367J-160D01*
G02X669711Y297517I-1144J811D01*
G03X669089I-311J-252D01*
G02Y299283I-1089J883D01*
G03X669711I311J252D01*
G02X672085Y298960I1089J-883D01*
G37*
G36*
G01X685340Y281390D02*
G03X684678Y281366I-323J-236D01*
G02X684620Y282940I-1188J744D01*
G03X685282Y282964I323J236D01*
G02X685340Y281390I1188J-744D01*
G37*
G36*
G01X690825Y282886D02*
G03Y282220I222J-333D01*
G02X689271I-777J-1167D01*
G03Y282886I-222J333D01*
G02X690825I777J1167D01*
G37*
G36*
G01X710645Y274464D02*
G03X710700Y273831I269J-295D01*
G02X709004Y273683I-751J-1184D01*
G03X708949Y274316I-269J295D01*
G02X708692Y276474I751J1184D01*
G03X708670Y277051I-288J278D01*
G02X708511Y277217I930J1049D01*
G03X707889I-311J-252D01*
G02Y278983I-1089J883D01*
G03X708511I311J252D01*
G02X710608Y277126I1090J-882D01*
G03X710630Y276549I288J-278D01*
G02X710645Y274464I-930J-1049D01*
G37*
G36*
G01X719279Y249179D02*
G03X718606Y249173I-335J-219D01*
G02X718591Y250691I-1186J747D01*
G03X719264Y250697I335J219D01*
G02X721584Y250774I1186J-747D01*
G03X722239Y250786I323J236D01*
G02X724545Y250809I1161J-786D01*
G03X725195Y250805I326J231D01*
G02X725183Y249170I1133J-826D01*
G03X724533Y249174I-326J-231D01*
G02X722266Y249176I-1133J826D01*
G03X721611Y249164I-323J-236D01*
G02X719279Y249179I-1161J786D01*
G37*
G36*
G01X647483Y327324D02*
G02X645706Y326977I-683J-1224D01*
G03X645589Y327576I-312J250D01*
G02X647366Y327923I683J1224D01*
G03X647483Y327324I312J-250D01*
G37*
G36*
G01X646017Y319011D02*
G02X647783I883J1089D01*
G03Y318389I252J-311D01*
G02X646017I-883J-1089D01*
G03Y319011I-252J311D01*
G37*
G36*
G01X659377Y295606D02*
G02X657627Y294985I-524J-1301D01*
G03X657426Y295549I-350J193D01*
G02X659176Y296170I524J1301D01*
G03X659377Y295606I350J-193D01*
G37*
G36*
G01X663911Y285683D02*
G02Y283917I1089J-883D01*
G03X663289I-311J-252D01*
G02X660957Y285448I-1089J883D01*
G03X660742Y286007I-355J184D01*
G02X662475Y286673I490J1314D01*
G03X662690Y286114I355J-184D01*
G02X663289Y285683I-491J-1314D01*
G03X663911I311J252D01*
G37*
G36*
G01X637286Y329053D02*
G03X637524Y328453I339J-213D01*
G02X635905Y327850I-381J-1453D01*
G03X635691Y328459I-330J226D01*
G02X636069Y331202I409J1341D01*
G03X636420Y331777I-8J400D01*
G02X637712Y330988I1261J613D01*
G03X637361Y330413I8J-400D01*
G02X637286Y329053I-1261J-613D01*
G37*
G36*
G01X656353Y286072D02*
G03X656121Y285442I88J-390D01*
G02X654689Y285967I-1121J-842D01*
G03X654921Y286597I-88J390D01*
G02X656353Y286072I1121J842D01*
G37*
G36*
G01X660966Y278455D02*
G02X662303Y279878I-65J1401D01*
G03X662721Y279485I400J6D01*
G02X661384Y278062I65J-1401D01*
G03X660966Y278455I-400J-6D01*
G37*
G36*
G01X689350Y410810D02*
G03X688784Y410617I-197J-348D01*
G02X688201Y412470I-1384J583D01*
G03X688776Y412636I214J338D01*
G02X689350Y410810I1264J-606D01*
G37*
G36*
G01X705251Y415224D02*
G02X704037Y416342I-1375J-275D01*
G03X704475Y416818I46J397D01*
G02X706140Y418465I1375J275D01*
G03X706620Y418905I83J391D01*
G02X708660Y420321I1391J173D01*
G03X709234Y420585I185J355D01*
G02X711673Y421169I1366J-318D01*
G03X712315Y421210I306J258D01*
G02X714245Y419266I1178J-761D01*
G03X714131Y418700I215J-338D01*
G02X712163Y416760I-1151J-800D01*
G03X711596Y416655I-233J-325D01*
G02X710199Y416039I-1173J768D01*
G03X709738Y415692I-64J-395D01*
G02X706981Y415541I-1392J167D01*
G03X706426Y415815I-390J-91D01*
G02X705689Y415700I-577J1278D01*
G03X705251Y415224I-46J-397D01*
G37*
G36*
G01X1297959Y50236D02*
G03X1297942Y49668I273J-292D01*
G02X1295919Y49673I-1014J-968D01*
G03X1295905Y50242I-288J278D01*
G02X1297959Y50236I1030J1093D01*
G37*
G36*
G01X1302167Y61223D02*
G02Y62777I-1167J777D01*
G03X1302833I333J222D01*
G02Y61223I1167J-777D01*
G03X1302167I-333J-222D01*
G37*
G36*
G01X1319118Y61167D02*
G02X1317564I-777J-1167D01*
G03Y61833I-222J333D01*
G02X1319118I777J1167D01*
G03Y61167I222J-333D01*
G37*
G36*
G01X1300447Y-16726D02*
G03X1300497Y-17327I287J-279D01*
G02X1298451Y-17453I-947J-1292D01*
G03X1298427Y-16850I-274J291D01*
G02X1300447Y-16726I942J1170D01*
G37*
G36*
G01X1246064Y89417D02*
G03X1246078Y88834I281J-285D01*
G02X1244078I-1000J-1120D01*
G03X1244092Y89417I-267J298D01*
G02X1246064I986J997D01*
G37*
G36*
G01X1239371D02*
G03X1239385Y88834I281J-285D01*
G02X1237385I-1000J-1120D01*
G03X1237399Y89417I-267J298D01*
G02X1239371I986J997D01*
G37*
G36*
G01X1221939D02*
G03X1221953Y88834I281J-285D01*
G02X1219953I-1000J-1120D01*
G03X1219967Y89417I-267J298D01*
G02X1221939I986J997D01*
G37*
G36*
G01X1225841Y67467D02*
G03X1225825Y66906I277J-289D01*
G02X1223775I-1025J-956D01*
G03X1223759Y67467I-293J272D01*
G02X1223712Y69585I1041J1083D01*
G03X1223706Y70142I-290J275D01*
G02X1223733Y72282I1068J1057D01*
G03X1223749Y72843I-277J289D01*
G02X1225799I1025J956D01*
G03X1225815Y72282I293J-272D01*
G02X1225862Y70164I-1041J-1083D01*
G03X1225868Y69607I290J-275D01*
G02X1225841Y67467I-1068J-1057D01*
G37*
G36*
G01X1230919Y67261D02*
G03X1230906Y66699I278J-288D01*
G02X1228858Y66689I-1019J-963D01*
G03X1228840Y67250I-293J271D01*
G02X1228781Y69370I1034J1090D01*
G03Y69919I-291J274D01*
G02X1228844Y72043I1093J1031D01*
G03X1228865Y72604I-274J291D01*
G02X1230915Y72583I1035J946D01*
G03X1230925Y72022I290J-275D01*
G02X1230967Y69919I-1051J-1073D01*
G03Y69370I291J-274D01*
G02X1230919Y67261I-1093J-1030D01*
G37*
G36*
G01X1246064Y51617D02*
G03X1246078Y51034I281J-285D01*
G02X1244078I-1000J-1120D01*
G03X1244092Y51617I-267J298D01*
G02X1246064I986J997D01*
G37*
G36*
G01X1239371D02*
G03X1239385Y51034I281J-285D01*
G02X1237385I-1000J-1120D01*
G03X1237399Y51617I-267J298D01*
G02X1239371I986J997D01*
G37*
G36*
G01X1221939D02*
G03X1221953Y51034I281J-285D01*
G02X1219953I-1000J-1120D01*
G03X1219967Y51617I-267J298D01*
G02X1221939I986J997D01*
G37*
G36*
G01X1230970Y51287D02*
G03Y50741I292J-273D01*
G02X1228778I-1096J-1027D01*
G03Y51287I-292J273D01*
G02X1228833Y53397I1096J1027D01*
G03X1228849Y53958I-277J289D01*
G02X1230899I1025J956D01*
G03X1230915Y53397I293J-272D01*
G02X1230970Y51287I-1041J-1083D01*
G37*
G36*
G01X1225814Y48416D02*
G03X1225799Y47855I277J-288D01*
G02X1223749I-1025J-957D01*
G03X1223734Y48416I-292J273D01*
G02X1223678Y50527I1040J1084D01*
G03Y51073I-292J273D01*
G02X1225870I1096J1027D01*
G03Y50527I292J-273D01*
G02X1225814Y48416I-1096J-1027D01*
G37*
G36*
G01X1253093Y84043D02*
G02Y85471I-1322J714D01*
G03X1253796I352J190D01*
G02X1256439I1321J-714D01*
G03X1257143I352J191D01*
G02X1259786I1321J-714D01*
G03X1260489I352J190D01*
G02X1263132I1322J-714D01*
G03X1263836I352J191D01*
G02Y84043I1321J-714D01*
G03X1263132I-352J-191D01*
G02X1260489I-1322J714D01*
G03X1259786I-351J-190D01*
G02X1257143I-1322J714D01*
G03X1256439I-352J-191D01*
G02X1253796I-1322J714D01*
G03X1253093I-352J-190D01*
G37*
G36*
G01X1266990Y74673D02*
G02X1266871Y72814I986J-996D01*
G03X1266261Y72839I-316J-246D01*
G02X1263836Y73143I-1104J1018D01*
G03X1263132I-352J-191D01*
G02X1260489I-1322J714D01*
G03X1259786I-351J-190D01*
G02X1257143I-1322J714D01*
G03X1256439I-352J-191D01*
G02X1253796I-1322J714D01*
G03X1253093I-352J-190D01*
G02Y74571I-1322J714D01*
G03X1253796I352J190D01*
G02X1256439I1321J-714D01*
G03X1257143I352J191D01*
G02X1259786I1321J-714D01*
G03X1260489I352J190D01*
G02X1263132I1322J-714D01*
G03X1263836I352J191D01*
G02X1266382Y74726I1321J-714D01*
G03X1266990Y74673I326J231D01*
G37*
G36*
G01X1256439Y64985D02*
G02Y66413I-1321J714D01*
G03X1257143I352J191D01*
G02X1259786I1321J-714D01*
G03X1260489I352J190D01*
G02X1263132I1322J-714D01*
G03X1263836I352J191D01*
G02Y64985I1321J-714D01*
G03X1263132I-352J-191D01*
G02X1260489I-1322J714D01*
G03X1259786I-351J-190D01*
G02X1257143I-1322J714D01*
G03X1256439I-352J-191D01*
G37*
G36*
G01X1267068Y55471D02*
G02X1266846Y53680I954J-1028D01*
G03X1266226Y53744I-336J-218D01*
G02X1263836Y54085I-1069J1055D01*
G03X1263132I-352J-191D01*
G02X1260489I-1322J714D01*
G03X1259786I-351J-190D01*
G02X1257143I-1322J714D01*
G03X1256439I-352J-191D01*
G02X1253796I-1322J714D01*
G03X1253093I-352J-190D01*
G02X1250437Y54108I-1322J714D01*
G03X1249734Y54120I-355J-184D01*
G02X1249759Y55548I-1309J737D01*
G03X1250462Y55536I355J184D01*
G02X1253093Y55513I1309J-737D01*
G03X1253796I352J190D01*
G02X1256439I1321J-714D01*
G03X1257143I352J191D01*
G02X1259786I1321J-714D01*
G03X1260489I352J190D01*
G02X1263132I1322J-714D01*
G03X1263836I352J191D01*
G02X1266451Y55561I1321J-714D01*
G03X1267068Y55471I345J203D01*
G37*
G36*
G01X1253093Y46243D02*
G02Y47671I-1322J714D01*
G03X1253796I352J190D01*
G02X1256439I1321J-714D01*
G03X1257143I352J191D01*
G02X1259786I1321J-714D01*
G03X1260489I352J190D01*
G02X1263132I1322J-714D01*
G03X1263836I352J191D01*
G02X1266218Y48020I1321J-714D01*
G03X1266824Y48068I282J283D01*
G02X1267015Y46208I1135J-823D01*
G03X1266412Y46132I-269J-296D01*
G02X1263836Y46243I-1255J825D01*
G03X1263132I-352J-191D01*
G02X1260489I-1322J714D01*
G03X1259786I-351J-190D01*
G02X1257143I-1322J714D01*
G03X1256439I-352J-191D01*
G02X1253796I-1322J714D01*
G03X1253093I-352J-190D01*
G37*
G36*
G01Y35343D02*
G02Y36771I-1322J714D01*
G03X1253796I352J190D01*
G02X1256439I1321J-714D01*
G03X1257143I352J191D01*
G02X1259786I1321J-714D01*
G03X1260489I352J190D01*
G02X1263132I1322J-714D01*
G03X1263836I352J191D01*
G02Y35343I1321J-714D01*
G03X1263132I-352J-191D01*
G02X1260489I-1322J714D01*
G03X1259786I-351J-190D01*
G02X1257143I-1322J714D01*
G03X1256439I-352J-191D01*
G02X1253796I-1322J714D01*
G03X1253093I-352J-190D01*
G37*
G36*
G01X1225821Y29648D02*
G03X1225806Y29077I272J-293D01*
G02X1223794I-1006J-977D01*
G03X1223779Y29648I-287J278D01*
G02X1223712Y31785I1021J1102D01*
G03X1223706Y32342I-290J275D01*
G02X1223733Y34482I1068J1057D01*
G03X1223749Y35043I-277J289D01*
G02X1225799I1025J956D01*
G03X1225815Y34482I293J-272D01*
G02X1225862Y32364I-1041J-1083D01*
G03X1225868Y31807I290J-275D01*
G02X1225821Y29648I-1068J-1057D01*
G37*
G36*
G01X1230919Y29461D02*
G03X1230906Y28899I278J-288D01*
G02X1228858Y28889I-1019J-963D01*
G03X1228840Y29450I-293J271D01*
G02X1228781Y31570I1034J1090D01*
G03Y32119I-291J274D01*
G02X1228804Y34203I1093J1030D01*
G03X1228803Y34764I-286J280D01*
G02X1230851Y34823I996J986D01*
G03X1230883Y34262I300J-264D01*
G02X1230967Y32119I-1009J-1113D01*
G03Y31570I291J-275D01*
G02X1230919Y29461I-1093J-1030D01*
G37*
G36*
G01X1246064Y13817D02*
G03X1246078Y13234I281J-285D01*
G02X1244078I-1000J-1120D01*
G03X1244092Y13817I-267J298D01*
G02X1246064I986J997D01*
G37*
G36*
G01X1239371D02*
G03X1239385Y13234I281J-285D01*
G02X1237385I-1000J-1120D01*
G03X1237399Y13817I-267J298D01*
G02X1239371I986J997D01*
G37*
G36*
G01X1221939D02*
G03X1221953Y13234I281J-285D01*
G02X1219953I-1000J-1120D01*
G03X1219967Y13817I-267J298D01*
G02X1221939I986J997D01*
G37*
G36*
G01X1230878Y10797D02*
G03X1230847Y10233I267J-298D01*
G02X1228808Y10291I-1047J-933D01*
G03X1228809Y10855I-283J283D01*
G02X1228778Y12941I1065J1059D01*
G03Y13487I-292J273D01*
G02X1228833Y15597I1096J1027D01*
G03X1228849Y16158I-277J289D01*
G02X1230899I1025J956D01*
G03X1230915Y15597I293J-272D01*
G02X1230970Y13487I-1041J-1083D01*
G03Y12941I292J-273D01*
G02X1230878Y10797I-1096J-1027D01*
G37*
G36*
G01X1225814Y10616D02*
G03X1225799Y10055I277J-288D01*
G02X1223749I-1025J-957D01*
G03X1223734Y10616I-292J273D01*
G02X1223678Y12727I1040J1084D01*
G03Y13273I-292J273D01*
G02X1223740Y15389I1096J1027D01*
G03X1223759Y15950I-275J290D01*
G02X1225810Y15938I1031J950D01*
G03X1225821Y15376I290J-275D01*
G02X1225870Y13273I-1047J-1076D01*
G03Y12727I292J-273D01*
G02X1225814Y10616I-1096J-1027D01*
G37*
G36*
G01X1225830Y-8143D02*
G03X1225820Y-8715I274J-291D01*
G02X1223808Y-8732I-998J-985D01*
G03X1223788Y-8160I-289J276D01*
G02X1223712Y-6015I1012J1110D01*
G03X1223706Y-5458I-290J275D01*
G02X1223733Y-3318I1068J1057D01*
G03X1223749Y-2757I-277J289D01*
G02X1225799I1025J956D01*
G03X1225815Y-3318I293J-272D01*
G02X1225862Y-5436I-1041J-1083D01*
G03X1225868Y-5993I290J-275D01*
G02X1225830Y-8143I-1068J-1056D01*
G37*
G36*
G01X1230919Y-8339D02*
G03X1230906Y-8901I278J-288D01*
G02X1228858Y-8911I-1019J-963D01*
G03X1228840Y-8350I-293J271D01*
G02X1228781Y-6230I1034J1090D01*
G03Y-5681I-291J274D01*
G02X1228874Y-3531I1093J1030D01*
G03X1228899Y-2959I-267J298D01*
G02X1230910Y-2995I1023J959D01*
G03X1230914Y-3568I281J-285D01*
G02X1230967Y-5681I-1040J-1083D01*
G03Y-6230I291J-274D01*
G02X1230919Y-8339I-1093J-1030D01*
G37*
G36*
G01X1253093Y27185D02*
G02Y28613I-1322J714D01*
G03X1253796I352J190D01*
G02X1256439I1321J-714D01*
G03X1257143I352J191D01*
G02X1259786I1321J-714D01*
G03X1260489I352J190D01*
G02X1263132I1322J-714D01*
G03X1263836I352J191D01*
G02X1266121Y29051I1321J-714D01*
G03X1266729Y29166I257J306D01*
G02X1267108Y27380I1231J-672D01*
G03X1266506Y27239I-243J-317D01*
G02X1263836Y27185I-1349J660D01*
G03X1263132I-352J-191D01*
G02X1260489I-1322J714D01*
G03X1259786I-351J-190D01*
G02X1257143I-1322J714D01*
G03X1256439I-352J-191D01*
G02X1253796I-1322J714D01*
G03X1253093I-352J-190D01*
G37*
G36*
G01X1256439Y16285D02*
G02Y17713I-1321J714D01*
G03X1257143I352J191D01*
G02X1259786I1321J-714D01*
G03X1260489I352J190D01*
G02X1263132I1322J-714D01*
G03X1263836I352J191D01*
G02Y16285I1321J-714D01*
G03X1263132I-352J-191D01*
G02X1260489I-1322J714D01*
G03X1259786I-351J-190D01*
G02X1257143I-1322J714D01*
G03X1256439I-352J-191D01*
G37*
G36*
G01X1260024Y10242D02*
G02X1259973Y8004I976J-1142D01*
G03X1259440Y8015I-273J-293D01*
G02X1257143Y8443I-976J1142D01*
G03X1256439I-352J-191D01*
G02X1253796I-1322J714D01*
G03X1253093I-352J-190D01*
G02Y9871I-1322J714D01*
G03X1253796I352J190D01*
G02X1256439I1321J-714D01*
G03X1257143I352J191D01*
G02X1259491Y10253I1321J-714D01*
G03X1260024Y10242I273J293D01*
G37*
G36*
G01X1253093Y-2457D02*
G02Y-1029I-1322J714D01*
G03X1253796I352J190D01*
G02X1256439I1321J-714D01*
G03X1257143I352J191D01*
G02X1259786I1321J-714D01*
G03X1260489I352J190D01*
G02X1263132I1322J-714D01*
G03X1263836I352J191D01*
G02Y-2457I1321J-714D01*
G03X1263132I-352J-191D01*
G02X1260489I-1322J714D01*
G03X1259786I-351J-190D01*
G02X1257143I-1322J714D01*
G03X1256439I-352J-191D01*
G02X1253796I-1322J714D01*
G03X1253093I-352J-190D01*
G37*
G36*
G01X1256439Y-10615D02*
G02Y-9187I-1321J714D01*
G03X1257143I352J191D01*
G02X1259786I1321J-714D01*
G03X1260489I352J190D01*
G02X1263132I1322J-714D01*
G03X1263836I352J191D01*
G02Y-10615I1321J-714D01*
G03X1263132I-352J-191D01*
G02X1260489I-1322J714D01*
G03X1259786I-351J-190D01*
G02X1257143I-1322J714D01*
G03X1256439I-352J-191D01*
G37*
G36*
G01X1280343Y-15495D02*
G02X1280321Y-14060I-1443J696D01*
G03X1281025Y-14068I354J186D01*
G02X1283184Y-13700I1227J-679D01*
G03X1283763Y-13650I266J299D01*
G02X1283927Y-15571I1096J-874D01*
G03X1283348Y-15621I-266J-299D01*
G02X1281047Y-15464I-1096J874D01*
G03X1280343Y-15495I-344J-205D01*
G37*
G36*
G01X1209253Y89417D02*
G03X1209267Y88834I281J-285D01*
G02X1207267I-1000J-1120D01*
G03X1207281Y89417I-267J298D01*
G02X1209253I986J997D01*
G37*
G36*
G01X1202560D02*
G03X1202574Y88834I281J-285D01*
G02X1200574I-1000J-1120D01*
G03X1200588Y89417I-267J298D01*
G02X1202560I986J997D01*
G37*
G36*
G01X1185128D02*
G03X1185142Y88834I281J-285D01*
G02X1183142I-1000J-1120D01*
G03X1183156Y89417I-267J298D01*
G02X1185128I986J997D01*
G37*
G36*
G01X1178842Y89378D02*
G03X1178869Y88817I298J-267D01*
G02X1176788Y88777I-1020J-1103D01*
G03X1176792Y89338I-283J283D01*
G02X1178842Y89378I1006J976D01*
G37*
G36*
G01X1172442Y89417D02*
G03X1172456Y88834I281J-285D01*
G02X1170456I-1000J-1120D01*
G03X1170470Y89417I-267J298D01*
G02X1172442I986J997D01*
G37*
G36*
G01X1165749D02*
G03X1165763Y88834I281J-285D01*
G02X1163763I-1000J-1120D01*
G03X1163777Y89417I-267J298D01*
G02X1165749I986J997D01*
G37*
G36*
G01X1189030Y67467D02*
G03X1189014Y66906I277J-289D01*
G02X1186964I-1025J-956D01*
G03X1186948Y67467I-293J272D01*
G02X1186901Y69585I1041J1083D01*
G03X1186895Y70142I-290J275D01*
G02X1186922Y72282I1068J1057D01*
G03X1186938Y72843I-277J289D01*
G02X1188988I1025J956D01*
G03X1189004Y72282I293J-272D01*
G02X1189051Y70164I-1041J-1083D01*
G03X1189057Y69607I290J-275D01*
G02X1189030Y67467I-1068J-1057D01*
G37*
G36*
G01X1194108Y67261D02*
G03X1194095Y66699I278J-288D01*
G02X1192047Y66689I-1019J-963D01*
G03X1192029Y67250I-293J271D01*
G02X1191970Y69370I1034J1090D01*
G03Y69919I-291J274D01*
G02X1192033Y72043I1093J1031D01*
G03X1192054Y72604I-274J291D01*
G02X1194104Y72583I1035J946D01*
G03X1194114Y72022I290J-275D01*
G02X1194156Y69919I-1051J-1073D01*
G03Y69370I291J-274D01*
G02X1194108Y67261I-1093J-1030D01*
G37*
G36*
G01X1209253Y51617D02*
G03X1209267Y51034I281J-285D01*
G02X1207267I-1000J-1120D01*
G03X1207281Y51617I-267J298D01*
G02X1209253I986J997D01*
G37*
G36*
G01X1202560D02*
G03X1202574Y51034I281J-285D01*
G02X1200574I-1000J-1120D01*
G03X1200588Y51617I-267J298D01*
G02X1202560I986J997D01*
G37*
G36*
G01X1185128D02*
G03X1185142Y51034I281J-285D01*
G02X1183142I-1000J-1120D01*
G03X1183156Y51617I-267J298D01*
G02X1185128I986J997D01*
G37*
G36*
G01X1172442D02*
G03X1172456Y51034I281J-285D01*
G02X1170456I-1000J-1120D01*
G03X1170470Y51617I-267J298D01*
G02X1172442I986J997D01*
G37*
G36*
G01X1165749D02*
G03X1165763Y51034I281J-285D01*
G02X1163763I-1000J-1120D01*
G03X1163777Y51617I-267J298D01*
G02X1165749I986J997D01*
G37*
G36*
G01X1194036Y48570D02*
G03X1194010Y47984I259J-305D01*
G02X1192051Y48021I-998J-984D01*
G03X1192048Y48607I-274J292D01*
G02X1191967Y50741I1015J1107D01*
G03Y51287I-292J273D01*
G02X1192022Y53397I1096J1027D01*
G03X1192038Y53958I-277J289D01*
G02X1194088I1025J956D01*
G03X1194104Y53397I293J-272D01*
G02X1194159Y51287I-1041J-1083D01*
G03Y50741I292J-273D01*
G02X1194036Y48570I-1096J-1027D01*
G37*
G36*
G01X1189003Y48416D02*
G03X1188988Y47855I277J-288D01*
G02X1186938I-1025J-957D01*
G03X1186923Y48416I-292J273D01*
G02X1186867Y50527I1040J1084D01*
G03Y51073I-292J273D01*
G02X1186901Y53162I1096J1027D01*
G03X1186906Y53724I-282J284D01*
G02X1188956Y53764I1006J976D01*
G03X1188982Y53203I298J-267D01*
G02X1189059Y51073I-1019J-1103D01*
G03Y50527I292J-273D01*
G02X1189003Y48416I-1096J-1027D01*
G37*
G36*
G01X1215655Y51039D02*
G02X1213912Y51217I-995J-1125D01*
G03X1213990Y51852I-199J347D01*
G02X1215707Y51677I971J1012D01*
G03X1215655Y51039I213J-338D01*
G37*
G36*
G01X1189024Y29662D02*
G03X1189016Y29089I275J-290D01*
G02X1187005Y29064I-993J-989D01*
G03X1186982Y29635I-291J274D01*
G02X1186901Y31785I1007J1114D01*
G03X1186895Y32342I-290J275D01*
G02X1186922Y34482I1068J1057D01*
G03X1186938Y35043I-277J289D01*
G02X1188988I1025J956D01*
G03X1189004Y34482I293J-272D01*
G02X1189051Y32364I-1041J-1083D01*
G03X1189057Y31807I290J-275D01*
G02X1189024Y29662I-1068J-1056D01*
G37*
G36*
G01X1194108Y29461D02*
G03X1194095Y28899I278J-288D01*
G02X1192047Y28889I-1019J-963D01*
G03X1192029Y29450I-293J271D01*
G02X1191970Y31570I1034J1090D01*
G03Y32119I-291J274D01*
G02X1192026Y34236I1093J1030D01*
G03X1192032Y34808I-276J289D01*
G02X1194043Y34838I991J992D01*
G03X1194067Y34266I291J-274D01*
G02X1194156Y32119I-1004J-1117D01*
G03Y31570I291J-275D01*
G02X1194108Y29461I-1093J-1030D01*
G37*
G36*
G01X1215647Y13782D02*
G03X1215675Y13221I299J-266D01*
G02X1213595Y13173I-1015J-1107D01*
G03X1213597Y13734I-284J282D01*
G02X1215647Y13782I1003J980D01*
G37*
G36*
G01X1209253Y13817D02*
G03X1209267Y13234I281J-285D01*
G02X1207267I-1000J-1120D01*
G03X1207281Y13817I-267J298D01*
G02X1209253I986J997D01*
G37*
G36*
G01X1202560D02*
G03X1202574Y13234I281J-285D01*
G02X1200574I-1000J-1120D01*
G03X1200588Y13817I-267J298D01*
G02X1202560I986J997D01*
G37*
G36*
G01X1185128D02*
G03X1185142Y13234I281J-285D01*
G02X1183142I-1000J-1120D01*
G03X1183156Y13817I-267J298D01*
G02X1185128I986J997D01*
G37*
G36*
G01X1178842Y13778D02*
G03X1178869Y13217I298J-267D01*
G02X1176788Y13177I-1020J-1103D01*
G03X1176792Y13738I-283J283D01*
G02X1178842Y13778I1006J976D01*
G37*
G36*
G01X1172442Y13817D02*
G03X1172456Y13234I281J-285D01*
G02X1170456I-1000J-1120D01*
G03X1170470Y13817I-267J298D01*
G02X1172442I986J997D01*
G37*
G36*
G01X1165749D02*
G03X1165763Y13234I281J-285D01*
G02X1163763I-1000J-1120D01*
G03X1163777Y13817I-267J298D01*
G02X1165749I986J997D01*
G37*
G36*
G01X1194082Y10810D02*
G03X1194058Y10246I271J-294D01*
G02X1192018Y10277I-1035J-946D01*
G03X1192011Y10842I-287J279D01*
G02X1191967Y12941I1052J1072D01*
G03Y13487I-292J273D01*
G02X1192022Y15597I1096J1027D01*
G03X1192038Y16158I-277J289D01*
G02X1194088I1025J956D01*
G03X1194104Y15597I293J-272D01*
G02X1194159Y13487I-1041J-1083D01*
G03Y12941I292J-273D01*
G02X1194082Y10810I-1096J-1027D01*
G37*
G36*
G01X1189003Y10616D02*
G03X1188988Y10055I277J-288D01*
G02X1186938I-1025J-957D01*
G03X1186923Y10616I-292J273D01*
G02X1186867Y12727I1040J1084D01*
G03Y13273I-292J273D01*
G02X1186906Y15367I1096J1027D01*
G03X1186912Y15928I-282J284D01*
G02X1188963Y15960I1011J972D01*
G03X1188987Y15399I297J-268D01*
G02X1189059Y13273I-1024J-1099D01*
G03Y12727I292J-273D01*
G02X1189003Y10616I-1096J-1027D01*
G37*
G36*
G01X1189019Y-8143D02*
G03X1189009Y-8715I274J-291D01*
G02X1186997Y-8732I-998J-985D01*
G03X1186977Y-8160I-289J276D01*
G02X1186901Y-6015I1012J1110D01*
G03X1186895Y-5458I-290J275D01*
G02X1186922Y-3318I1068J1057D01*
G03X1186938Y-2757I-277J289D01*
G02X1188988I1025J956D01*
G03X1189004Y-3318I293J-272D01*
G02X1189051Y-5436I-1041J-1083D01*
G03X1189057Y-5993I290J-275D01*
G02X1189019Y-8143I-1068J-1056D01*
G37*
G36*
G01X1194108Y-8339D02*
G03X1194095Y-8901I278J-288D01*
G02X1192047Y-8911I-1019J-963D01*
G03X1192029Y-8350I-293J271D01*
G02X1191970Y-6230I1034J1090D01*
G03Y-5681I-291J274D01*
G02X1192063Y-3531I1093J1030D01*
G03X1192088Y-2959I-267J298D01*
G02X1194099Y-2995I1023J959D01*
G03X1194103Y-3568I281J-285D01*
G02X1194156Y-5681I-1040J-1083D01*
G03Y-6230I291J-274D01*
G02X1194108Y-8339I-1093J-1030D01*
G37*
G36*
G01X1148317Y89417D02*
G03X1148331Y88834I281J-285D01*
G02X1146331I-1000J-1120D01*
G03X1146345Y89417I-267J298D01*
G02X1148317I986J997D01*
G37*
G36*
G01X1142031Y89378D02*
G03X1142058Y88817I298J-267D01*
G02X1139977Y88777I-1020J-1103D01*
G03X1139981Y89338I-283J283D01*
G02X1142031Y89378I1006J976D01*
G37*
G36*
G01X1135631Y89417D02*
G03X1135645Y88834I281J-285D01*
G02X1133645I-1000J-1120D01*
G03X1133659Y89417I-267J298D01*
G02X1135631I986J997D01*
G37*
G36*
G01X1128938D02*
G03X1128952Y88834I281J-285D01*
G02X1126952I-1000J-1120D01*
G03X1126966Y89417I-267J298D01*
G02X1128938I986J997D01*
G37*
G36*
G01X1111545Y89358D02*
G03X1111561Y88797I293J-272D01*
G02X1109479I-1041J-1083D01*
G03X1109495Y89358I-277J289D01*
G02X1111545I1025J956D01*
G37*
G36*
G01X1105220Y89378D02*
G03X1105247Y88817I298J-267D01*
G02X1103166Y88777I-1020J-1103D01*
G03X1103170Y89338I-283J283D01*
G02X1105220Y89378I1006J976D01*
G37*
G36*
G01X1152219Y67467D02*
G03X1152203Y66906I277J-289D01*
G02X1150153I-1025J-956D01*
G03X1150137Y67467I-293J272D01*
G02X1150090Y69585I1041J1083D01*
G03X1150084Y70142I-290J275D01*
G02X1150111Y72282I1068J1057D01*
G03X1150127Y72843I-277J289D01*
G02X1152177I1025J956D01*
G03X1152193Y72282I293J-272D01*
G02X1152240Y70164I-1041J-1083D01*
G03X1152246Y69607I290J-275D01*
G02X1152219Y67467I-1068J-1057D01*
G37*
G36*
G01X1115407D02*
G03X1115391Y66906I277J-289D01*
G02X1113341I-1025J-956D01*
G03X1113325Y67467I-293J272D01*
G02X1113278Y69585I1041J1083D01*
G03X1113272Y70142I-290J275D01*
G02X1113299Y72282I1068J1057D01*
G03X1113315Y72843I-277J289D01*
G02X1115365I1025J956D01*
G03X1115381Y72282I293J-272D01*
G02X1115428Y70164I-1041J-1083D01*
G03X1115434Y69607I290J-275D01*
G02X1115407Y67467I-1068J-1057D01*
G37*
G36*
G01X1157297Y67261D02*
G03X1157284Y66699I278J-288D01*
G02X1155236Y66689I-1019J-963D01*
G03X1155218Y67250I-293J271D01*
G02X1155159Y69370I1034J1090D01*
G03Y69919I-291J274D01*
G02X1155222Y72043I1093J1031D01*
G03X1155243Y72604I-274J291D01*
G02X1157293Y72583I1035J946D01*
G03X1157303Y72022I290J-275D01*
G02X1157345Y69919I-1051J-1073D01*
G03Y69370I291J-274D01*
G02X1157297Y67261I-1093J-1030D01*
G37*
G36*
G01X1120485D02*
G03X1120472Y66699I278J-288D01*
G02X1118424Y66689I-1019J-963D01*
G03X1118406Y67250I-293J271D01*
G02X1118347Y69370I1034J1090D01*
G03Y69919I-291J274D01*
G02X1118410Y72043I1093J1031D01*
G03X1118431Y72604I-274J291D01*
G02X1120481Y72583I1035J946D01*
G03X1120491Y72022I290J-275D01*
G02X1120533Y69919I-1051J-1073D01*
G03Y69370I291J-274D01*
G02X1120485Y67261I-1093J-1030D01*
G37*
G36*
G01X1099508Y55935D02*
G03X1100069Y55966I265J300D01*
G02X1100128Y53886I1112J-1009D01*
G03X1099566I-281J-285D01*
G02X1099508Y55935I-985J997D01*
G37*
G36*
G01X1148317Y51617D02*
G03X1148331Y51034I281J-285D01*
G02X1146331I-1000J-1120D01*
G03X1146345Y51617I-267J298D01*
G02X1148317I986J997D01*
G37*
G36*
G01X1135631D02*
G03X1135645Y51034I281J-285D01*
G02X1133645I-1000J-1120D01*
G03X1133659Y51617I-267J298D01*
G02X1135631I986J997D01*
G37*
G36*
G01X1128938D02*
G03X1128952Y51034I281J-285D01*
G02X1126952I-1000J-1120D01*
G03X1126966Y51617I-267J298D01*
G02X1128938I986J997D01*
G37*
G36*
G01X1111506D02*
G03X1111520Y51034I281J-285D01*
G02X1109520I-1000J-1120D01*
G03X1109534Y51617I-267J298D01*
G02X1111506I986J997D01*
G37*
G36*
G01X1120459Y48610D02*
G03X1120435Y48046I271J-294D01*
G02X1118395Y48077I-1035J-946D01*
G03X1118388Y48642I-287J279D01*
G02X1118344Y50741I1052J1072D01*
G03Y51287I-292J273D01*
G02X1118399Y53397I1096J1027D01*
G03X1118415Y53958I-277J289D01*
G02X1120465I1025J956D01*
G03X1120481Y53397I293J-272D01*
G02X1120536Y51287I-1041J-1083D01*
G03Y50741I292J-273D01*
G02X1120459Y48610I-1096J-1027D01*
G37*
G36*
G01X1157224Y48570D02*
G03X1157198Y47984I259J-305D01*
G02X1155239Y48021I-998J-984D01*
G03X1155236Y48607I-274J292D01*
G02X1155155Y50741I1015J1107D01*
G03Y51287I-292J273D01*
G02X1155211Y53397I1096J1027D01*
G03X1155226Y53958I-277J288D01*
G02X1157277I1025J956D01*
G03X1157292Y53396I292J-273D01*
G02X1157347Y51287I-1041J-1082D01*
G03Y50741I292J-273D01*
G02X1157224Y48570I-1096J-1027D01*
G37*
G36*
G01X1152192Y48417D02*
G03X1152176Y47855I277J-289D01*
G02X1150127Y47854I-1024J-957D01*
G03X1150111Y48416I-292J273D01*
G02X1150055Y50527I1040J1084D01*
G03Y51073I-292J273D01*
G02X1150089Y53162I1096J1027D01*
G03X1150094Y53724I-282J284D01*
G02X1152144Y53764I1006J976D01*
G03X1152170Y53203I298J-267D01*
G02X1152247Y51073I-1019J-1103D01*
G03Y50527I292J-273D01*
G02X1152192Y48417I-1096J-1027D01*
G37*
G36*
G01X1115380Y48416D02*
G03X1115365Y47855I277J-288D01*
G02X1113315I-1025J-957D01*
G03X1113300Y48416I-292J273D01*
G02X1113244Y50527I1040J1084D01*
G03Y51073I-292J273D01*
G02X1113283Y53167I1096J1027D01*
G03X1113289Y53728I-282J284D01*
G02X1115340Y53760I1011J972D01*
G03X1115364Y53199I297J-268D01*
G02X1115436Y51073I-1024J-1099D01*
G03Y50527I292J-273D01*
G02X1115380Y48416I-1096J-1027D01*
G37*
G36*
G01X1100176Y85691D02*
G02X1099881Y84189I1005J-977D01*
G03X1099223Y84319I-371J-149D01*
G02X1099518Y85821I-1005J977D01*
G03X1100176Y85691I371J149D01*
G37*
G36*
G01X1099124Y69174D02*
G02X1097365Y69189I-889J-1084D01*
G03X1097370Y69812I-249J314D01*
G02X1097307Y71926I889J1084D01*
G03X1097296Y72523I-271J294D01*
G02X1099308Y74456I910J1066D01*
G03X1099969Y74503I315J248D01*
G02X1100080Y72932I1212J-704D01*
G03X1099419Y72885I-315J-248D01*
G02X1099159Y72559I-1214J702D01*
G03X1099170Y71962I271J-294D01*
G02X1099129Y69797I-911J-1066D01*
G03X1099124Y69174I249J-314D01*
G37*
G36*
G01X1105090Y50793D02*
G02X1103323Y50763I-863J-1229D01*
G03X1103325Y51400I-241J319D01*
G02X1105066Y51430I852J1114D01*
G03X1105090Y50793I254J-309D01*
G37*
G36*
G01X1100010Y47672D02*
G02X1099974Y46187I1171J-771D01*
G03X1099296Y46203I-344J-204D01*
G02X1099332Y47688I-1171J771D01*
G03X1100010Y47672I344J204D01*
G37*
G36*
G01X1099301Y35187D02*
G02X1099201Y36520I-1279J574D01*
G03X1099902Y36573I336J217D01*
G02X1100002Y35240I1279J-574D01*
G03X1099301Y35187I-336J-217D01*
G37*
G36*
G01X1152212Y29662D02*
G03X1152204Y29089I275J-290D01*
G02X1150193Y29064I-993J-989D01*
G03X1150170Y29635I-291J274D01*
G02X1150089Y31785I1007J1114D01*
G03X1150083Y32342I-290J275D01*
G02X1150111Y34482I1068J1056D01*
G03X1150126Y35043I-277J288D01*
G02X1152177I1025J956D01*
G03X1152192Y34481I292J-273D01*
G02X1152239Y32364I-1041J-1082D01*
G03X1152245Y31807I290J-275D01*
G02X1152212Y29662I-1068J-1056D01*
G37*
G36*
G01X1115401D02*
G03X1115393Y29089I275J-290D01*
G02X1113382Y29064I-993J-989D01*
G03X1113359Y29635I-291J274D01*
G02X1113278Y31785I1007J1114D01*
G03X1113272Y32342I-290J275D01*
G02X1113299Y34482I1068J1057D01*
G03X1113315Y35043I-277J289D01*
G02X1115365I1025J956D01*
G03X1115381Y34482I293J-272D01*
G02X1115428Y32364I-1041J-1083D01*
G03X1115434Y31807I290J-275D01*
G02X1115401Y29662I-1068J-1056D01*
G37*
G36*
G01X1157296Y29461D02*
G03X1157284Y28899I278J-287D01*
G02X1155236Y28888I-1019J-963D01*
G03X1155218Y29450I-294J272D01*
G02X1155158Y31570I1033J1090D01*
G03Y32119I-291J274D01*
G02X1155214Y34236I1093J1030D01*
G03X1155220Y34808I-276J289D01*
G02X1157231Y34838I991J992D01*
G03X1157255Y34266I291J-274D01*
G02X1157344Y32119I-1004J-1117D01*
G03Y31570I291J-275D01*
G02X1157296Y29461I-1093J-1030D01*
G37*
G36*
G01X1120485D02*
G03X1120472Y28899I278J-288D01*
G02X1118424Y28889I-1019J-963D01*
G03X1118406Y29450I-293J271D01*
G02X1118347Y31570I1034J1090D01*
G03Y32119I-291J274D01*
G02X1118403Y34236I1093J1030D01*
G03X1118409Y34808I-276J289D01*
G02X1120420Y34838I991J992D01*
G03X1120444Y34266I291J-274D01*
G02X1120533Y32119I-1004J-1117D01*
G03Y31570I291J-275D01*
G02X1120485Y29461I-1093J-1030D01*
G37*
G36*
G01X1100127Y16087D02*
G03X1099547Y16068I-281J-285D01*
G02X1099431Y18048I-1047J932D01*
G03X1100009Y18097I266J299D01*
G02X1100127Y16087I1172J-940D01*
G37*
G36*
G01X1148317Y13817D02*
G03X1148331Y13234I281J-285D01*
G02X1146331I-1000J-1120D01*
G03X1146345Y13817I-267J298D01*
G02X1148317I986J997D01*
G37*
G36*
G01X1142031Y13778D02*
G03X1142058Y13217I298J-267D01*
G02X1139977Y13177I-1020J-1103D01*
G03X1139981Y13738I-283J283D01*
G02X1142031Y13778I1006J976D01*
G37*
G36*
G01X1135631Y13817D02*
G03X1135645Y13234I281J-285D01*
G02X1133645I-1000J-1120D01*
G03X1133659Y13817I-267J298D01*
G02X1135631I986J997D01*
G37*
G36*
G01X1128938D02*
G03X1128952Y13234I281J-285D01*
G02X1126952I-1000J-1120D01*
G03X1126966Y13817I-267J298D01*
G02X1128938I986J997D01*
G37*
G36*
G01X1111506D02*
G03X1111520Y13234I281J-285D01*
G02X1109520I-1000J-1120D01*
G03X1109534Y13817I-267J298D01*
G02X1111506I986J997D01*
G37*
G36*
G01X1105220Y13778D02*
G03X1105247Y13217I298J-267D01*
G02X1103166Y13177I-1020J-1103D01*
G03X1103170Y13738I-283J283D01*
G02X1105220Y13778I1006J976D01*
G37*
G36*
G01X1098901Y12718D02*
G03X1098902Y12156I285J-280D01*
G02X1096821Y12209I-1068J-1056D01*
G03X1096851Y12770I-269J296D01*
G02X1098901Y12718I1049J930D01*
G37*
G36*
G01X1157271Y10810D02*
G03X1157247Y10246I271J-294D01*
G02X1155207Y10277I-1035J-946D01*
G03X1155200Y10842I-287J279D01*
G02X1155156Y12941I1052J1072D01*
G03Y13487I-292J273D01*
G02X1155211Y15597I1096J1027D01*
G03X1155227Y16158I-277J289D01*
G02X1157277I1025J956D01*
G03X1157293Y15597I293J-272D01*
G02X1157348Y13487I-1041J-1083D01*
G03Y12941I292J-273D01*
G02X1157271Y10810I-1096J-1027D01*
G37*
G36*
G01X1120459D02*
G03X1120435Y10246I271J-294D01*
G02X1118395Y10277I-1035J-946D01*
G03X1118388Y10842I-287J279D01*
G02X1118344Y12941I1052J1072D01*
G03Y13487I-292J273D01*
G02X1118399Y15597I1096J1027D01*
G03X1118415Y16158I-277J289D01*
G02X1120465I1025J956D01*
G03X1120481Y15597I293J-272D01*
G02X1120536Y13487I-1041J-1083D01*
G03Y12941I292J-273D01*
G02X1120459Y10810I-1096J-1027D01*
G37*
G36*
G01X1152192Y10616D02*
G03X1152177Y10055I277J-288D01*
G02X1150127I-1025J-957D01*
G03X1150112Y10616I-292J273D01*
G02X1150056Y12727I1040J1084D01*
G03Y13273I-292J273D01*
G02X1150095Y15367I1096J1027D01*
G03X1150101Y15928I-282J284D01*
G02X1152152Y15960I1011J972D01*
G03X1152176Y15399I297J-268D01*
G02X1152248Y13273I-1024J-1099D01*
G03Y12727I292J-273D01*
G02X1152192Y10616I-1096J-1027D01*
G37*
G36*
G01X1115380D02*
G03X1115365Y10055I277J-288D01*
G02X1113315I-1025J-957D01*
G03X1113300Y10616I-292J273D01*
G02X1113244Y12727I1040J1084D01*
G03Y13273I-292J273D01*
G02X1113283Y15367I1096J1027D01*
G03X1113289Y15928I-282J284D01*
G02X1115340Y15960I1011J972D01*
G03X1115364Y15399I297J-268D01*
G02X1115436Y13273I-1024J-1099D01*
G03Y12727I292J-273D01*
G02X1115380Y10616I-1096J-1027D01*
G37*
G36*
G01X1115428Y-5436D02*
G03X1115434Y-5993I290J-275D01*
G02X1113278Y-6015I-1067J-1057D01*
G03X1113272Y-5458I-290J275D01*
G02X1113299Y-3318I1068J1057D01*
G03X1113315Y-2757I-277J289D01*
G02X1115365I1025J956D01*
G03X1115381Y-3318I293J-272D01*
G02X1115428Y-5436I-1041J-1083D01*
G37*
G36*
G01X1152208Y-8143D02*
G03X1152198Y-8715I274J-291D01*
G02X1150186Y-8732I-998J-985D01*
G03X1150166Y-8160I-289J276D01*
G02X1150090Y-6015I1012J1110D01*
G03X1150084Y-5458I-290J275D01*
G02X1150111Y-3318I1068J1057D01*
G03X1150127Y-2757I-277J289D01*
G02X1152177I1025J956D01*
G03X1152193Y-3318I293J-272D01*
G02X1152240Y-5436I-1041J-1083D01*
G03X1152246Y-5993I290J-275D01*
G02X1152208Y-8143I-1068J-1056D01*
G37*
G36*
G01X1157297Y-8339D02*
G03X1157284Y-8901I278J-288D01*
G02X1155236Y-8911I-1019J-963D01*
G03X1155218Y-8350I-293J271D01*
G02X1155159Y-6230I1034J1090D01*
G03Y-5681I-291J274D01*
G02X1155252Y-3531I1093J1030D01*
G03X1155277Y-2959I-267J298D01*
G02X1157288Y-2995I1023J959D01*
G03X1157292Y-3568I281J-285D01*
G02X1157345Y-5681I-1040J-1083D01*
G03Y-6230I291J-274D01*
G02X1157297Y-8339I-1093J-1030D01*
G37*
G36*
G01X1120485D02*
G03X1120472Y-8901I278J-288D01*
G02X1118424Y-8911I-1019J-963D01*
G03X1118406Y-8350I-293J271D01*
G02X1118347Y-6230I1034J1090D01*
G03Y-5681I-291J274D01*
G02X1120533I1093J1030D01*
G03Y-6230I291J-274D01*
G02X1120485Y-8339I-1093J-1030D01*
G37*
G36*
G01X1047471Y15650D02*
G03X1047025Y15275I-47J-397D01*
G02X1045778Y16838I-1500J82D01*
G03X1046243Y17190I67J394D01*
G02X1047471Y15650I1394J-148D01*
G37*
G36*
G01X1031015Y60198D02*
X1026485D01*
X1020498Y66185D01*
Y87815D01*
X1021785Y89102D01*
X1028115D01*
X1032902Y84315D01*
Y62085D01*
X1031015Y60198D01*
G37*
G36*
G01X1014103Y91490D02*
G03X1013512I-296J-269D01*
G02Y93510I-1112J1010D01*
G03X1014103I296J269D01*
G02Y91490I1112J-1010D01*
G37*
G36*
G01X1013737Y86483D02*
G03X1013148I-295J-271D01*
G02Y88517I-1105J1017D01*
G03X1013737I295J271D01*
G02Y86483I1105J-1017D01*
G37*
G36*
G01X1008351Y69924D02*
G03Y69346I277J-289D01*
G02X1006409I-971J-1011D01*
G03Y69924I-277J289D01*
G02X1008351I971J1011D01*
G37*
G36*
G01X1008310Y51293D02*
G03Y50699I268J-297D01*
G02X1006430I-940J-1040D01*
G03Y51293I-268J297D01*
G02X1008310I940J1040D01*
G37*
G36*
G01X1012788Y45875D02*
G03X1012211I-288J-277D01*
G02Y47953I-1085J1039D01*
G03X1012788I288J277D01*
G02Y45875I1085J-1039D01*
G37*
G36*
G01X1012148Y54128D02*
G02Y55556I-1322J714D01*
G03X1012851I352J190D01*
G02Y54128I1322J-714D01*
G03X1012148I-352J-190D01*
G37*
G36*
G01Y35228D02*
G02Y36656I-1322J714D01*
G03X1012851I352J190D01*
G02Y35228I1322J-714D01*
G03X1012148I-352J-190D01*
G37*
G36*
G01X1009185Y32318D02*
G03X1009179Y31740I273J-292D01*
G02X1007242Y31760I-979J-1004D01*
G03X1007248Y32338I-273J292D01*
G02X1009185Y32318I979J1004D01*
G37*
G36*
G01X1013884Y15953D02*
G03X1013327Y15947I-275J-290D01*
G02X1013305Y18103I-1057J1067D01*
G03X1013862Y18109I275J290D01*
G02X1013884Y15953I1057J-1067D01*
G37*
G36*
G01X1008071Y13303D02*
G03Y12725I277J-289D01*
G02X1006129I-971J-1011D01*
G03Y13303I-277J289D01*
G02X1008071I971J1011D01*
G37*
G36*
G01X1026852Y7567D02*
G03X1027440Y7522I315J247D01*
G02X1027341Y5581I960J-1022D01*
G03X1026751Y5597I-302J-262D01*
G02X1026852Y7567I-1081J1043D01*
G37*
G36*
G01X1012148Y27300D02*
G02Y28728I-1322J714D01*
G03X1012851I352J190D01*
G02Y27300I1322J-714D01*
G03X1012148I-352J-190D01*
G37*
G36*
G01X1031207Y24330D02*
G02X1029654Y24304I-757J-1180D01*
G03X1029643Y24970I-227J329D01*
G02X1031196Y24996I757J1180D01*
G03X1031207Y24330I227J-329D01*
G37*
G36*
G01X1025138Y18699D02*
G02X1023567Y19642I-1398J-549D01*
G03X1023893Y20185I-47J397D01*
G02X1025464Y19242I1398J549D01*
G03X1025138Y18699I47J-397D01*
G37*
G36*
G01X1012148Y8400D02*
G02Y9828I-1322J714D01*
G03X1012851I352J190D01*
G02Y8400I1322J-714D01*
G03X1012148I-352J-190D01*
G37*
G36*
G01Y-2572D02*
G02Y-1144I-1322J714D01*
G03X1012851I352J190D01*
G02Y-2572I1322J-714D01*
G03X1012148I-352J-190D01*
G37*
G36*
G01X1030454Y-7537D02*
G02X1029044Y-8610I-47J-1401D01*
G03X1028652Y-8117I-389J93D01*
G02X1030083Y-7027I-13J1502D01*
G03X1030454Y-7537I385J-110D01*
G37*
G36*
G01X1012148Y-10500D02*
G02Y-9072I-1322J714D01*
G03X1012851I352J190D01*
G02Y-10500I1322J-714D01*
G03X1012148I-352J-190D01*
G37*
G36*
G01X954890Y89435D02*
G03X954915Y88853I286J-279D01*
G02X952915Y88816I-979J-1139D01*
G03X952919Y89399I-272J293D01*
G02X954890Y89435I967J1015D01*
G37*
G36*
G01X948229Y89417D02*
G03X948243Y88834I281J-285D01*
G02X946243I-1000J-1120D01*
G03X946257Y89417I-267J298D01*
G02X948229I986J997D01*
G37*
G36*
G01X930797D02*
G03X930811Y88834I281J-285D01*
G02X928811I-1000J-1120D01*
G03X928825Y89417I-267J298D01*
G02X930797I986J997D01*
G37*
G36*
G01X924511Y89378D02*
G03X924538Y88817I298J-267D01*
G02X922457Y88777I-1020J-1103D01*
G03X922461Y89338I-283J283D01*
G02X924511Y89378I1006J976D01*
G37*
G36*
G01X918111Y89417D02*
G03X918125Y88834I281J-285D01*
G02X916125I-1000J-1120D01*
G03X916139Y89417I-267J298D01*
G02X918111I986J997D01*
G37*
G36*
G01X958546Y69365D02*
G03X958532Y68789I270J-295D01*
G02X956590Y68837I-996J-987D01*
G03X956604Y69413I-270J295D01*
G02X958546Y69365I996J987D01*
G37*
G36*
G01X934699Y67467D02*
G03X934683Y66906I277J-289D01*
G02X932633I-1025J-956D01*
G03X932617Y67467I-293J272D01*
G02X932570Y69585I1041J1083D01*
G03X932564Y70142I-290J275D01*
G02X932591Y72282I1068J1057D01*
G03X932607Y72843I-277J289D01*
G02X934657I1025J956D01*
G03X934673Y72282I293J-272D01*
G02X934720Y70164I-1041J-1083D01*
G03X934726Y69607I290J-275D01*
G02X934699Y67467I-1068J-1057D01*
G37*
G36*
G01X939777Y67261D02*
G03X939764Y66699I278J-288D01*
G02X937716Y66689I-1019J-963D01*
G03X937698Y67250I-293J271D01*
G02X937639Y69370I1034J1090D01*
G03Y69919I-291J274D01*
G02X937702Y72043I1093J1031D01*
G03X937723Y72604I-274J291D01*
G02X939773Y72583I1035J946D01*
G03X939783Y72022I290J-275D01*
G02X939825Y69919I-1051J-1073D01*
G03Y69370I291J-274D01*
G02X939777Y67261I-1093J-1030D01*
G37*
G36*
G01X954922Y51617D02*
G03X954936Y51034I281J-285D01*
G02X952936I-1000J-1120D01*
G03X952950Y51617I-267J298D01*
G02X954922I986J997D01*
G37*
G36*
G01X948229D02*
G03X948243Y51034I281J-285D01*
G02X946243I-1000J-1120D01*
G03X946257Y51617I-267J298D01*
G02X948229I986J997D01*
G37*
G36*
G01X930797D02*
G03X930811Y51034I281J-285D01*
G02X928811I-1000J-1120D01*
G03X928825Y51617I-267J298D01*
G02X930797I986J997D01*
G37*
G36*
G01X918111D02*
G03X918125Y51034I281J-285D01*
G02X916125I-1000J-1120D01*
G03X916139Y51617I-267J298D01*
G02X918111I986J997D01*
G37*
G36*
G01X939672Y48543D02*
G03X939653Y47936I251J-312D01*
G02X937781Y47951I-944J-1036D01*
G03X937772Y48559I-265J300D01*
G02X937636Y50741I960J1155D01*
G03Y51287I-292J273D01*
G02X937691Y53397I1096J1027D01*
G03X937707Y53958I-277J289D01*
G02X939757I1025J956D01*
G03X939773Y53397I293J-272D01*
G02X939828Y51287I-1041J-1083D01*
G03Y50741I292J-273D01*
G02X939672Y48543I-1096J-1027D01*
G37*
G36*
G01X934672Y48416D02*
G03X934657Y47855I277J-288D01*
G02X932607I-1025J-957D01*
G03X932592Y48416I-292J273D01*
G02X932536Y50527I1040J1084D01*
G03Y51073I-292J273D01*
G02X932581Y53173I1096J1027D01*
G03X932591Y53735I-280J286D01*
G02X934642Y53753I1017J965D01*
G03X934663Y53192I295J-270D01*
G02X934728Y51073I-1031J-1092D01*
G03Y50527I292J-273D01*
G02X934672Y48416I-1096J-1027D01*
G37*
G36*
G01X934699Y29667D02*
G03X934683Y29106I277J-289D01*
G02X932633I-1025J-956D01*
G03X932617Y29667I-293J272D01*
G02X932570Y31785I1041J1083D01*
G03X932564Y32342I-290J275D01*
G02X932591Y34482I1068J1057D01*
G03X932607Y35043I-277J289D01*
G02X934657I1025J956D01*
G03X934673Y34482I293J-272D01*
G02X934720Y32364I-1041J-1083D01*
G03X934726Y31807I290J-275D01*
G02X934699Y29667I-1068J-1057D01*
G37*
G36*
G01X939777Y29461D02*
G03X939764Y28899I278J-288D01*
G02X937716Y28889I-1019J-963D01*
G03X937698Y29450I-293J271D01*
G02X937639Y31570I1034J1090D01*
G03Y32119I-291J274D01*
G02X937702Y34243I1093J1031D01*
G03X937723Y34804I-274J291D01*
G02X939773Y34783I1035J946D01*
G03X939783Y34222I290J-275D01*
G02X939825Y32119I-1051J-1073D01*
G03Y31570I291J-275D01*
G02X939777Y29461I-1093J-1030D01*
G37*
G36*
G01X954922Y13817D02*
G03X954936Y13234I281J-285D01*
G02X952936I-1000J-1120D01*
G03X952950Y13817I-267J298D01*
G02X954922I986J997D01*
G37*
G36*
G01X948229D02*
G03X948243Y13234I281J-285D01*
G02X946243I-1000J-1120D01*
G03X946257Y13817I-267J298D01*
G02X948229I986J997D01*
G37*
G36*
G01X930797D02*
G03X930811Y13234I281J-285D01*
G02X928811I-1000J-1120D01*
G03X928825Y13817I-267J298D01*
G02X930797I986J997D01*
G37*
G36*
G01X924511Y13778D02*
G03X924538Y13217I298J-267D01*
G02X922457Y13177I-1020J-1103D01*
G03X922461Y13738I-283J283D01*
G02X924511Y13778I1006J976D01*
G37*
G36*
G01X918111Y13817D02*
G03X918125Y13234I281J-285D01*
G02X916125I-1000J-1120D01*
G03X916139Y13817I-267J298D01*
G02X918111I986J997D01*
G37*
G36*
G01X939672Y10743D02*
G03X939653Y10136I251J-312D01*
G02X937781Y10151I-944J-1036D01*
G03X937772Y10759I-265J300D01*
G02X937636Y12941I960J1155D01*
G03Y13487I-292J273D01*
G02X937691Y15597I1096J1027D01*
G03X937707Y16158I-277J289D01*
G02X939757I1025J956D01*
G03X939773Y15597I293J-272D01*
G02X939828Y13487I-1041J-1083D01*
G03Y12941I292J-273D01*
G02X939672Y10743I-1096J-1027D01*
G37*
G36*
G01X934672Y10616D02*
G03X934657Y10055I277J-288D01*
G02X932607I-1025J-957D01*
G03X932592Y10616I-292J273D01*
G02X932536Y12727I1040J1084D01*
G03Y13273I-292J273D01*
G02X932581Y15373I1096J1027D01*
G03X932591Y15935I-280J286D01*
G02X934642Y15953I1017J965D01*
G03X934663Y15392I295J-270D01*
G02X934728Y13273I-1031J-1092D01*
G03Y12727I292J-273D01*
G02X934672Y10616I-1096J-1027D01*
G37*
G36*
G01X934699Y-8133D02*
G03X934683Y-8694I277J-289D01*
G02X932633I-1025J-956D01*
G03X932617Y-8133I-293J272D01*
G02X932570Y-6015I1041J1083D01*
G03X932564Y-5458I-290J275D01*
G02X932591Y-3318I1068J1057D01*
G03X932607Y-2757I-277J289D01*
G02X934657I1025J956D01*
G03X934673Y-3318I293J-272D01*
G02X934720Y-5436I-1041J-1083D01*
G03X934726Y-5993I290J-275D01*
G02X934699Y-8133I-1068J-1057D01*
G37*
G36*
G01X939777Y-8339D02*
G03X939764Y-8901I278J-288D01*
G02X937716Y-8911I-1019J-963D01*
G03X937698Y-8350I-293J271D01*
G02X937639Y-6230I1034J1090D01*
G03Y-5681I-291J274D01*
G02X937702Y-3557I1093J1031D01*
G03X937723Y-2996I-274J291D01*
G02X939773Y-3017I1035J946D01*
G03X939783Y-3578I290J-275D01*
G02X939825Y-5681I-1051J-1073D01*
G03Y-6230I291J-274D01*
G02X939777Y-8339I-1093J-1030D01*
G37*
G36*
G01X911418Y89417D02*
G03X911432Y88834I281J-285D01*
G02X909432I-1000J-1120D01*
G03X909446Y89417I-267J298D01*
G02X911418I986J997D01*
G37*
G36*
G01X893986D02*
G03X894000Y88834I281J-285D01*
G02X892000I-1000J-1120D01*
G03X892014Y89417I-267J298D01*
G02X893986I986J997D01*
G37*
G36*
G01X887700Y89378D02*
G03X887727Y88817I298J-267D01*
G02X885646Y88777I-1020J-1103D01*
G03X885650Y89338I-283J283D01*
G02X887700Y89378I1006J976D01*
G37*
G36*
G01X881300Y89417D02*
G03X881314Y88834I281J-285D01*
G02X879314I-1000J-1120D01*
G03X879328Y89417I-267J298D01*
G02X881300I986J997D01*
G37*
G36*
G01X874607D02*
G03X874621Y88834I281J-285D01*
G02X872621I-1000J-1120D01*
G03X872635Y89417I-267J298D01*
G02X874607I986J997D01*
G37*
G36*
G01X857175D02*
G03X857189Y88834I281J-285D01*
G02X855189I-1000J-1120D01*
G03X855203Y89417I-267J298D01*
G02X857175I986J997D01*
G37*
G36*
G01X850889Y89378D02*
G03X850916Y88817I298J-267D01*
G02X848835Y88777I-1020J-1103D01*
G03X848839Y89338I-283J283D01*
G02X850889Y89378I1006J976D01*
G37*
G36*
G01X897888Y67467D02*
G03X897872Y66906I277J-289D01*
G02X895822I-1025J-956D01*
G03X895806Y67467I-293J272D01*
G02X895759Y69585I1041J1083D01*
G03X895753Y70142I-290J275D01*
G02X895780Y72282I1068J1057D01*
G03X895796Y72843I-277J289D01*
G02X897846I1025J956D01*
G03X897862Y72282I293J-272D01*
G02X897909Y70164I-1041J-1083D01*
G03X897915Y69607I290J-275D01*
G02X897888Y67467I-1068J-1057D01*
G37*
G36*
G01X861077D02*
G03X861061Y66906I277J-289D01*
G02X859011I-1025J-956D01*
G03X858995Y67467I-293J272D01*
G02X858948Y69585I1041J1083D01*
G03X858942Y70142I-290J275D01*
G02X858969Y72282I1068J1057D01*
G03X858985Y72843I-277J289D01*
G02X861035I1025J956D01*
G03X861051Y72282I293J-272D01*
G02X861098Y70164I-1041J-1083D01*
G03X861104Y69607I290J-275D01*
G02X861077Y67467I-1068J-1057D01*
G37*
G36*
G01X902966Y67261D02*
G03X902953Y66699I278J-288D01*
G02X900905Y66689I-1019J-963D01*
G03X900887Y67250I-293J271D01*
G02X900828Y69370I1034J1090D01*
G03Y69919I-291J274D01*
G02X900891Y72043I1093J1031D01*
G03X900912Y72604I-274J291D01*
G02X902962Y72583I1035J946D01*
G03X902972Y72022I290J-275D01*
G02X903014Y69919I-1051J-1073D01*
G03Y69370I291J-274D01*
G02X902966Y67261I-1093J-1030D01*
G37*
G36*
G01X866155D02*
G03X866142Y66699I278J-288D01*
G02X864094Y66689I-1019J-963D01*
G03X864076Y67250I-293J271D01*
G02X864017Y69370I1034J1090D01*
G03Y69919I-291J274D01*
G02X864080Y72043I1093J1031D01*
G03X864101Y72604I-274J291D01*
G02X866151Y72583I1035J946D01*
G03X866161Y72022I290J-275D01*
G02X866203Y69919I-1051J-1073D01*
G03Y69370I291J-274D01*
G02X866155Y67261I-1093J-1030D01*
G37*
G36*
G01X911418Y51617D02*
G03X911432Y51034I281J-285D01*
G02X909432I-1000J-1120D01*
G03X909446Y51617I-267J298D01*
G02X911418I986J997D01*
G37*
G36*
G01X893986D02*
G03X894000Y51034I281J-285D01*
G02X892000I-1000J-1120D01*
G03X892014Y51617I-267J298D01*
G02X893986I986J997D01*
G37*
G36*
G01X887700Y51578D02*
G03X887727Y51017I298J-267D01*
G02X885646Y50977I-1020J-1103D01*
G03X885650Y51538I-283J283D01*
G02X887700Y51578I1006J976D01*
G37*
G36*
G01X881300Y51617D02*
G03X881314Y51034I281J-285D01*
G02X879314I-1000J-1120D01*
G03X879328Y51617I-267J298D01*
G02X881300I986J997D01*
G37*
G36*
G01X874607D02*
G03X874621Y51034I281J-285D01*
G02X872621I-1000J-1120D01*
G03X872635Y51617I-267J298D01*
G02X874607I986J997D01*
G37*
G36*
G01X857175D02*
G03X857189Y51034I281J-285D01*
G02X855189I-1000J-1120D01*
G03X855203Y51617I-267J298D01*
G02X857175I986J997D01*
G37*
G36*
G01X850889Y51578D02*
G03X850916Y51017I298J-267D01*
G02X848835Y50977I-1020J-1103D01*
G03X848839Y51538I-283J283D01*
G02X850889Y51578I1006J976D01*
G37*
G36*
G01X902861Y48543D02*
G03X902842Y47936I251J-312D01*
G02X900970Y47951I-944J-1036D01*
G03X900961Y48559I-265J300D01*
G02X900825Y50741I960J1155D01*
G03Y51287I-292J273D01*
G02X900880Y53397I1096J1027D01*
G03X900896Y53958I-277J289D01*
G02X902946I1025J956D01*
G03X902962Y53397I293J-272D01*
G02X903017Y51287I-1041J-1083D01*
G03Y50741I292J-273D01*
G02X902861Y48543I-1096J-1027D01*
G37*
G36*
G01X866050D02*
G03X866031Y47936I251J-312D01*
G02X864159Y47951I-944J-1036D01*
G03X864150Y48559I-265J300D01*
G02X864014Y50741I960J1155D01*
G03Y51287I-292J273D01*
G02X864069Y53397I1096J1027D01*
G03X864085Y53958I-277J289D01*
G02X866135I1025J956D01*
G03X866151Y53397I293J-272D01*
G02X866206Y51287I-1041J-1083D01*
G03Y50741I292J-273D01*
G02X866050Y48543I-1096J-1027D01*
G37*
G36*
G01X897861Y48416D02*
G03X897846Y47855I277J-288D01*
G02X895796I-1025J-957D01*
G03X895781Y48416I-292J273D01*
G02X895725Y50527I1040J1084D01*
G03Y51073I-292J273D01*
G02X895770Y53173I1096J1027D01*
G03X895780Y53735I-280J286D01*
G02X897831Y53753I1017J965D01*
G03X897852Y53192I295J-270D01*
G02X897917Y51073I-1031J-1092D01*
G03Y50527I292J-273D01*
G02X897861Y48416I-1096J-1027D01*
G37*
G36*
G01X861050D02*
G03X861035Y47855I277J-288D01*
G02X858985I-1025J-957D01*
G03X858970Y48416I-292J273D01*
G02X858914Y50527I1040J1084D01*
G03Y51073I-292J273D01*
G02X858959Y53173I1096J1027D01*
G03X858969Y53735I-280J286D01*
G02X861020Y53753I1017J965D01*
G03X861041Y53192I295J-270D01*
G02X861106Y51073I-1031J-1092D01*
G03Y50527I292J-273D01*
G02X861050Y48416I-1096J-1027D01*
G37*
G36*
G01X897888Y29667D02*
G03X897872Y29106I277J-289D01*
G02X895822I-1025J-956D01*
G03X895806Y29667I-293J272D01*
G02X895759Y31785I1041J1083D01*
G03X895753Y32342I-290J275D01*
G02X895780Y34482I1068J1057D01*
G03X895796Y35043I-277J289D01*
G02X897846I1025J956D01*
G03X897862Y34482I293J-272D01*
G02X897909Y32364I-1041J-1083D01*
G03X897915Y31807I290J-275D01*
G02X897888Y29667I-1068J-1057D01*
G37*
G36*
G01X861077D02*
G03X861061Y29106I277J-289D01*
G02X859011I-1025J-956D01*
G03X858995Y29667I-293J272D01*
G02X858948Y31785I1041J1083D01*
G03X858942Y32342I-290J275D01*
G02X858969Y34482I1068J1057D01*
G03X858985Y35043I-277J289D01*
G02X861035I1025J956D01*
G03X861051Y34482I293J-272D01*
G02X861098Y32364I-1041J-1083D01*
G03X861104Y31807I290J-275D01*
G02X861077Y29667I-1068J-1057D01*
G37*
G36*
G01X902966Y29461D02*
G03X902953Y28899I278J-288D01*
G02X900905Y28889I-1019J-963D01*
G03X900887Y29450I-293J271D01*
G02X900828Y31570I1034J1090D01*
G03Y32119I-291J274D01*
G02X900891Y34243I1093J1031D01*
G03X900912Y34804I-274J291D01*
G02X902962Y34783I1035J946D01*
G03X902972Y34222I290J-275D01*
G02X903014Y32119I-1051J-1073D01*
G03Y31570I291J-275D01*
G02X902966Y29461I-1093J-1030D01*
G37*
G36*
G01X866155D02*
G03X866142Y28899I278J-288D01*
G02X864094Y28889I-1019J-963D01*
G03X864076Y29450I-293J271D01*
G02X864017Y31570I1034J1090D01*
G03Y32119I-291J274D01*
G02X864080Y34243I1093J1031D01*
G03X864101Y34804I-274J291D01*
G02X866151Y34783I1035J946D01*
G03X866161Y34222I290J-275D01*
G02X866203Y32119I-1051J-1073D01*
G03Y31570I291J-275D01*
G02X866155Y29461I-1093J-1030D01*
G37*
G36*
G01X911418Y13817D02*
G03X911432Y13234I281J-285D01*
G02X909432I-1000J-1120D01*
G03X909446Y13817I-267J298D01*
G02X911418I986J997D01*
G37*
G36*
G01X893986D02*
G03X894000Y13234I281J-285D01*
G02X892000I-1000J-1120D01*
G03X892014Y13817I-267J298D01*
G02X893986I986J997D01*
G37*
G36*
G01X887700Y13778D02*
G03X887727Y13217I298J-267D01*
G02X885646Y13177I-1020J-1103D01*
G03X885650Y13738I-283J283D01*
G02X887700Y13778I1006J976D01*
G37*
G36*
G01X881300Y13817D02*
G03X881314Y13234I281J-285D01*
G02X879314I-1000J-1120D01*
G03X879328Y13817I-267J298D01*
G02X881300I986J997D01*
G37*
G36*
G01X874607D02*
G03X874621Y13234I281J-285D01*
G02X872621I-1000J-1120D01*
G03X872635Y13817I-267J298D01*
G02X874607I986J997D01*
G37*
G36*
G01X857175D02*
G03X857189Y13234I281J-285D01*
G02X855189I-1000J-1120D01*
G03X855203Y13817I-267J298D01*
G02X857175I986J997D01*
G37*
G36*
G01X850889Y13778D02*
G03X850916Y13217I298J-267D01*
G02X848835Y13177I-1020J-1103D01*
G03X848839Y13738I-283J283D01*
G02X850889Y13778I1006J976D01*
G37*
G36*
G01X902861Y10743D02*
G03X902842Y10136I251J-312D01*
G02X900970Y10151I-944J-1036D01*
G03X900961Y10759I-265J300D01*
G02X900825Y12941I960J1155D01*
G03Y13487I-292J273D01*
G02X900880Y15597I1096J1027D01*
G03X900896Y16158I-277J289D01*
G02X902946I1025J956D01*
G03X902962Y15597I293J-272D01*
G02X903017Y13487I-1041J-1083D01*
G03Y12941I292J-273D01*
G02X902861Y10743I-1096J-1027D01*
G37*
G36*
G01X866050D02*
G03X866031Y10136I251J-312D01*
G02X864159Y10151I-944J-1036D01*
G03X864150Y10759I-265J300D01*
G02X864014Y12941I960J1155D01*
G03Y13487I-292J273D01*
G02X864069Y15597I1096J1027D01*
G03X864085Y16158I-277J289D01*
G02X866135I1025J956D01*
G03X866151Y15597I293J-272D01*
G02X866206Y13487I-1041J-1083D01*
G03Y12941I292J-273D01*
G02X866050Y10743I-1096J-1027D01*
G37*
G36*
G01X897861Y10616D02*
G03X897846Y10055I277J-288D01*
G02X895796I-1025J-957D01*
G03X895781Y10616I-292J273D01*
G02X895725Y12727I1040J1084D01*
G03Y13273I-292J273D01*
G02X895770Y15373I1096J1027D01*
G03X895780Y15935I-280J286D01*
G02X897831Y15953I1017J965D01*
G03X897852Y15392I295J-270D01*
G02X897917Y13273I-1031J-1092D01*
G03Y12727I292J-273D01*
G02X897861Y10616I-1096J-1027D01*
G37*
G36*
G01X861050D02*
G03X861035Y10055I277J-288D01*
G02X858985I-1025J-957D01*
G03X858970Y10616I-292J273D01*
G02X858914Y12727I1040J1084D01*
G03Y13273I-292J273D01*
G02X858959Y15373I1096J1027D01*
G03X858969Y15935I-280J286D01*
G02X861020Y15953I1017J965D01*
G03X861041Y15392I295J-270D01*
G02X861106Y13273I-1031J-1092D01*
G03Y12727I292J-273D01*
G02X861050Y10616I-1096J-1027D01*
G37*
G36*
G01X897888Y-8133D02*
G03X897872Y-8694I277J-289D01*
G02X895822I-1025J-956D01*
G03X895806Y-8133I-293J272D01*
G02X895759Y-6015I1041J1083D01*
G03X895753Y-5458I-290J275D01*
G02X895780Y-3318I1068J1057D01*
G03X895796Y-2757I-277J289D01*
G02X897846I1025J956D01*
G03X897862Y-3318I293J-272D01*
G02X897909Y-5436I-1041J-1083D01*
G03X897915Y-5993I290J-275D01*
G02X897888Y-8133I-1068J-1057D01*
G37*
G36*
G01X861077D02*
G03X861061Y-8694I277J-289D01*
G02X859011I-1025J-956D01*
G03X858995Y-8133I-293J272D01*
G02X858948Y-6015I1041J1083D01*
G03X858942Y-5458I-290J275D01*
G02X858969Y-3318I1068J1057D01*
G03X858985Y-2757I-277J289D01*
G02X861035I1025J956D01*
G03X861051Y-3318I293J-272D01*
G02X861098Y-5436I-1041J-1083D01*
G03X861104Y-5993I290J-275D01*
G02X861077Y-8133I-1068J-1057D01*
G37*
G36*
G01X902966Y-8339D02*
G03X902953Y-8901I278J-288D01*
G02X900905Y-8911I-1019J-963D01*
G03X900887Y-8350I-293J271D01*
G02X900828Y-6230I1034J1090D01*
G03Y-5681I-291J274D01*
G02X900891Y-3557I1093J1031D01*
G03X900912Y-2996I-274J291D01*
G02X902962Y-3017I1035J946D01*
G03X902972Y-3578I290J-275D01*
G02X903014Y-5681I-1051J-1073D01*
G03Y-6230I291J-274D01*
G02X902966Y-8339I-1093J-1030D01*
G37*
G36*
G01X866155D02*
G03X866142Y-8901I278J-288D01*
G02X864094Y-8911I-1019J-963D01*
G03X864076Y-8350I-293J271D01*
G02X864017Y-6230I1034J1090D01*
G03Y-5681I-291J274D01*
G02X864080Y-3557I1093J1031D01*
G03X864101Y-2996I-274J291D01*
G02X866151Y-3017I1035J946D01*
G03X866161Y-3578I290J-275D01*
G02X866203Y-5681I-1051J-1073D01*
G03Y-6230I291J-274D01*
G02X866155Y-8339I-1093J-1030D01*
G37*
G36*
G01X844489Y89417D02*
G03X844503Y88834I281J-285D01*
G02X842503I-1000J-1120D01*
G03X842517Y89417I-267J298D01*
G02X844489I986J997D01*
G37*
G36*
G01X837796D02*
G03X837810Y88834I281J-285D01*
G02X835810I-1000J-1120D01*
G03X835824Y89417I-267J298D01*
G02X837796I986J997D01*
G37*
G36*
G01X820384Y89387D02*
G03X820399Y88816I287J-278D01*
G02X818357I-1021J-1102D01*
G03X818372Y89387I-272J293D01*
G02X820384I1006J977D01*
G37*
G36*
G01X814078Y89378D02*
G03X814105Y88817I298J-267D01*
G02X812024Y88777I-1020J-1103D01*
G03X812028Y89338I-283J283D01*
G02X814078Y89378I1006J976D01*
G37*
G36*
G01X807678Y89417D02*
G03X807692Y88834I281J-285D01*
G02X805692I-1000J-1120D01*
G03X805706Y89417I-267J298D01*
G02X807678I986J997D01*
G37*
G36*
G01X800985D02*
G03X800999Y88834I281J-285D01*
G02X798999I-1000J-1120D01*
G03X799013Y89417I-267J298D01*
G02X800985I986J997D01*
G37*
G36*
G01X824266Y67467D02*
G03X824250Y66906I277J-289D01*
G02X822200I-1025J-956D01*
G03X822184Y67467I-293J272D01*
G02X822137Y69585I1041J1083D01*
G03X822131Y70142I-290J275D01*
G02X822158Y72282I1068J1057D01*
G03X822174Y72843I-277J289D01*
G02X824224I1025J956D01*
G03X824240Y72282I293J-272D01*
G02X824287Y70164I-1041J-1083D01*
G03X824293Y69607I290J-275D01*
G02X824266Y67467I-1068J-1057D01*
G37*
G36*
G01X829344Y67261D02*
G03X829331Y66699I278J-288D01*
G02X827283Y66689I-1019J-963D01*
G03X827265Y67250I-293J271D01*
G02X827206Y69370I1034J1090D01*
G03Y69919I-291J274D01*
G02X827269Y72043I1093J1031D01*
G03X827290Y72604I-274J291D01*
G02X829340Y72583I1035J946D01*
G03X829350Y72022I290J-275D01*
G02X829392Y69919I-1051J-1073D01*
G03Y69370I291J-274D01*
G02X829344Y67261I-1093J-1030D01*
G37*
G36*
G01X792533D02*
G03X792520Y66699I278J-288D01*
G02X790472Y66689I-1019J-963D01*
G03X790454Y67250I-293J271D01*
G02X790395Y69370I1034J1090D01*
G03Y69919I-291J274D01*
G02X790458Y72043I1093J1031D01*
G03X790479Y72604I-274J291D01*
G02X792529Y72583I1035J946D01*
G03X792539Y72022I290J-275D01*
G02X792581Y69919I-1051J-1073D01*
G03Y69370I291J-274D01*
G02X792533Y67261I-1093J-1030D01*
G37*
G36*
G01X844489Y51617D02*
G03X844503Y51034I281J-285D01*
G02X842503I-1000J-1120D01*
G03X842517Y51617I-267J298D01*
G02X844489I986J997D01*
G37*
G36*
G01X837796D02*
G03X837810Y51034I281J-285D01*
G02X835810I-1000J-1120D01*
G03X835824Y51617I-267J298D01*
G02X837796I986J997D01*
G37*
G36*
G01X820364D02*
G03X820378Y51034I281J-285D01*
G02X818378I-1000J-1120D01*
G03X818392Y51617I-267J298D01*
G02X820364I986J997D01*
G37*
G36*
G01X814078Y51578D02*
G03X814105Y51017I298J-267D01*
G02X812024Y50977I-1020J-1103D01*
G03X812028Y51538I-283J283D01*
G02X814078Y51578I1006J976D01*
G37*
G36*
G01X807678Y51617D02*
G03X807692Y51034I281J-285D01*
G02X805692I-1000J-1120D01*
G03X805706Y51617I-267J298D01*
G02X807678I986J997D01*
G37*
G36*
G01X800985D02*
G03X800999Y51034I281J-285D01*
G02X798999I-1000J-1120D01*
G03X799013Y51617I-267J298D01*
G02X800985I986J997D01*
G37*
G36*
G01X829239Y48543D02*
G03X829220Y47936I251J-312D01*
G02X827348Y47951I-944J-1036D01*
G03X827339Y48559I-265J300D01*
G02X827203Y50741I960J1155D01*
G03Y51287I-292J273D01*
G02X827258Y53397I1096J1027D01*
G03X827274Y53958I-277J289D01*
G02X829324I1025J956D01*
G03X829340Y53397I293J-272D01*
G02X829395Y51287I-1041J-1083D01*
G03Y50741I292J-273D01*
G02X829239Y48543I-1096J-1027D01*
G37*
G36*
G01X792428D02*
G03X792409Y47936I251J-312D01*
G02X790537Y47951I-944J-1036D01*
G03X790528Y48559I-265J300D01*
G02X790392Y50741I960J1155D01*
G03Y51287I-292J273D01*
G02X790447Y53397I1096J1027D01*
G03X790463Y53958I-277J289D01*
G02X792513I1025J956D01*
G03X792529Y53397I293J-272D01*
G02X792584Y51287I-1041J-1083D01*
G03Y50741I292J-273D01*
G02X792428Y48543I-1096J-1027D01*
G37*
G36*
G01X824239Y48416D02*
G03X824224Y47855I277J-288D01*
G02X822174I-1025J-957D01*
G03X822159Y48416I-292J273D01*
G02X822103Y50527I1040J1084D01*
G03Y51073I-292J273D01*
G02X822148Y53173I1096J1027D01*
G03X822158Y53735I-280J286D01*
G02X824209Y53753I1017J965D01*
G03X824230Y53192I295J-270D01*
G02X824295Y51073I-1031J-1092D01*
G03Y50527I292J-273D01*
G02X824239Y48416I-1096J-1027D01*
G37*
G36*
G01X824266Y29667D02*
G03X824250Y29106I277J-289D01*
G02X822200I-1025J-956D01*
G03X822184Y29667I-293J272D01*
G02X822137Y31785I1041J1083D01*
G03X822131Y32342I-290J275D01*
G02X822158Y34482I1068J1057D01*
G03X822174Y35043I-277J289D01*
G02X824224I1025J956D01*
G03X824240Y34482I293J-272D01*
G02X824287Y32364I-1041J-1083D01*
G03X824293Y31807I290J-275D01*
G02X824266Y29667I-1068J-1057D01*
G37*
G36*
G01X829344Y29461D02*
G03X829331Y28899I278J-288D01*
G02X827283Y28889I-1019J-963D01*
G03X827265Y29450I-293J271D01*
G02X827206Y31570I1034J1090D01*
G03Y32119I-291J274D01*
G02X827269Y34243I1093J1031D01*
G03X827290Y34804I-274J291D01*
G02X829340Y34783I1035J946D01*
G03X829350Y34222I290J-275D01*
G02X829392Y32119I-1051J-1073D01*
G03Y31570I291J-275D01*
G02X829344Y29461I-1093J-1030D01*
G37*
G36*
G01X792533D02*
G03X792520Y28899I278J-288D01*
G02X790472Y28889I-1019J-963D01*
G03X790454Y29450I-293J271D01*
G02X790395Y31570I1034J1090D01*
G03Y32119I-291J274D01*
G02X790458Y34243I1093J1031D01*
G03X790479Y34804I-274J291D01*
G02X792529Y34783I1035J946D01*
G03X792539Y34222I290J-275D01*
G02X792581Y32119I-1051J-1073D01*
G03Y31570I291J-275D01*
G02X792533Y29461I-1093J-1030D01*
G37*
G36*
G01X844489Y13817D02*
G03X844503Y13234I281J-285D01*
G02X842503I-1000J-1120D01*
G03X842517Y13817I-267J298D01*
G02X844489I986J997D01*
G37*
G36*
G01X837796D02*
G03X837810Y13234I281J-285D01*
G02X835810I-1000J-1120D01*
G03X835824Y13817I-267J298D01*
G02X837796I986J997D01*
G37*
G36*
G01X820364D02*
G03X820378Y13234I281J-285D01*
G02X818378I-1000J-1120D01*
G03X818392Y13817I-267J298D01*
G02X820364I986J997D01*
G37*
G36*
G01X814078Y13778D02*
G03X814105Y13217I298J-267D01*
G02X812024Y13177I-1020J-1103D01*
G03X812028Y13738I-283J283D01*
G02X814078Y13778I1006J976D01*
G37*
G36*
G01X807678Y13817D02*
G03X807692Y13234I281J-285D01*
G02X805692I-1000J-1120D01*
G03X805706Y13817I-267J298D01*
G02X807678I986J997D01*
G37*
G36*
G01X800985D02*
G03X800999Y13234I281J-285D01*
G02X798999I-1000J-1120D01*
G03X799013Y13817I-267J298D01*
G02X800985I986J997D01*
G37*
G36*
G01X829239Y10743D02*
G03X829220Y10136I251J-312D01*
G02X827348Y10151I-944J-1036D01*
G03X827339Y10759I-265J300D01*
G02X827203Y12941I960J1155D01*
G03Y13487I-292J273D01*
G02X827258Y15597I1096J1027D01*
G03X827274Y16158I-277J289D01*
G02X829324I1025J956D01*
G03X829340Y15597I293J-272D01*
G02X829395Y13487I-1041J-1083D01*
G03Y12941I292J-273D01*
G02X829239Y10743I-1096J-1027D01*
G37*
G36*
G01X792428D02*
G03X792409Y10136I251J-312D01*
G02X790537Y10151I-944J-1036D01*
G03X790528Y10759I-265J300D01*
G02X790392Y12941I960J1155D01*
G03Y13487I-292J273D01*
G02X790447Y15597I1096J1027D01*
G03X790463Y16158I-277J289D01*
G02X792513I1025J956D01*
G03X792529Y15597I293J-272D01*
G02X792584Y13487I-1041J-1083D01*
G03Y12941I292J-273D01*
G02X792428Y10743I-1096J-1027D01*
G37*
G36*
G01X824239Y10616D02*
G03X824224Y10055I277J-288D01*
G02X822174I-1025J-957D01*
G03X822159Y10616I-292J273D01*
G02X822103Y12727I1040J1084D01*
G03Y13273I-292J273D01*
G02X822148Y15373I1096J1027D01*
G03X822158Y15935I-280J286D01*
G02X824209Y15953I1017J965D01*
G03X824230Y15392I295J-270D01*
G02X824295Y13273I-1031J-1092D01*
G03Y12727I292J-273D01*
G02X824239Y10616I-1096J-1027D01*
G37*
G36*
G01X824266Y-8133D02*
G03X824250Y-8694I277J-289D01*
G02X822200I-1025J-956D01*
G03X822184Y-8133I-293J272D01*
G02X822137Y-6015I1041J1083D01*
G03X822131Y-5458I-290J275D01*
G02X822158Y-3318I1068J1057D01*
G03X822174Y-2757I-277J289D01*
G02X824224I1025J956D01*
G03X824240Y-3318I293J-272D01*
G02X824287Y-5436I-1041J-1083D01*
G03X824293Y-5993I290J-275D01*
G02X824266Y-8133I-1068J-1057D01*
G37*
G36*
G01X829344Y-8339D02*
G03X829331Y-8901I278J-288D01*
G02X827283Y-8911I-1019J-963D01*
G03X827265Y-8350I-293J271D01*
G02X827206Y-6230I1034J1090D01*
G03Y-5681I-291J274D01*
G02X827269Y-3557I1093J1031D01*
G03X827290Y-2996I-274J291D01*
G02X829340Y-3017I1035J946D01*
G03X829350Y-3578I290J-275D01*
G02X829392Y-5681I-1051J-1073D01*
G03Y-6230I291J-274D01*
G02X829344Y-8339I-1093J-1030D01*
G37*
G36*
G01X792533D02*
G03X792520Y-8901I278J-288D01*
G02X790472Y-8911I-1019J-963D01*
G03X790454Y-8350I-293J271D01*
G02X790395Y-6230I1034J1090D01*
G03Y-5681I-291J274D01*
G02X790458Y-3557I1093J1031D01*
G03X790479Y-2996I-274J291D01*
G02X792529Y-3017I1035J946D01*
G03X792539Y-3578I290J-275D01*
G02X792581Y-5681I-1051J-1073D01*
G03Y-6230I291J-274D01*
G02X792533Y-8339I-1093J-1030D01*
G37*
G36*
G01X783553Y89417D02*
G03X783567Y88834I281J-285D01*
G02X781567I-1000J-1120D01*
G03X781581Y89417I-267J298D01*
G02X783553I986J997D01*
G37*
G36*
G01X777267Y89378D02*
G03X777294Y88817I298J-267D01*
G02X775213Y88777I-1020J-1103D01*
G03X775217Y89338I-283J283D01*
G02X777267Y89378I1006J976D01*
G37*
G36*
G01X787455Y67467D02*
G03X787439Y66906I277J-289D01*
G02X785389I-1025J-956D01*
G03X785373Y67467I-293J272D01*
G02X785326Y69585I1041J1083D01*
G03X785320Y70142I-290J275D01*
G02X785347Y72282I1068J1057D01*
G03X785363Y72843I-277J289D01*
G02X787413I1025J956D01*
G03X787429Y72282I293J-272D01*
G02X787476Y70164I-1041J-1083D01*
G03X787482Y69607I290J-275D01*
G02X787455Y67467I-1068J-1057D01*
G37*
G36*
G01X783553Y51617D02*
G03X783567Y51034I281J-285D01*
G02X781567I-1000J-1120D01*
G03X781581Y51617I-267J298D01*
G02X783553I986J997D01*
G37*
G36*
G01X777267Y51578D02*
G03X777294Y51017I298J-267D01*
G02X775213Y50977I-1020J-1103D01*
G03X775217Y51538I-283J283D01*
G02X777267Y51578I1006J976D01*
G37*
G36*
G01X787428Y48416D02*
G03X787413Y47855I277J-288D01*
G02X785363I-1025J-957D01*
G03X785348Y48416I-292J273D01*
G02X785292Y50527I1040J1084D01*
G03Y51073I-292J273D01*
G02X785337Y53173I1096J1027D01*
G03X785347Y53735I-280J286D01*
G02X787398Y53753I1017J965D01*
G03X787419Y53192I295J-270D01*
G02X787484Y51073I-1031J-1092D01*
G03Y50527I292J-273D01*
G02X787428Y48416I-1096J-1027D01*
G37*
G36*
G01X768870Y85952D02*
G02X768137Y84373I630J-1252D01*
G03X767553Y84630I-389J-93D01*
G02X765872Y84781I-729J1313D01*
G03X765244Y84611I-253J-310D01*
G02X764776Y86218I-1314J489D01*
G03X765397Y86412I241J319D01*
G02X768298Y86233I1427J-469D01*
G03X768870Y85952I393J77D01*
G37*
G36*
G01X787455Y29667D02*
G03X787439Y29106I277J-289D01*
G02X785389I-1025J-956D01*
G03X785373Y29667I-293J272D01*
G02X785326Y31785I1041J1083D01*
G03X785320Y32342I-290J275D01*
G02X785347Y34482I1068J1057D01*
G03X785363Y35043I-277J289D01*
G02X787413I1025J956D01*
G03X787429Y34482I293J-272D01*
G02X787476Y32364I-1041J-1083D01*
G03X787482Y31807I290J-275D01*
G02X787455Y29667I-1068J-1057D01*
G37*
G36*
G01X783553Y13817D02*
G03X783567Y13234I281J-285D01*
G02X781567I-1000J-1120D01*
G03X781581Y13817I-267J298D01*
G02X783553I986J997D01*
G37*
G36*
G01X777267Y13778D02*
G03X777294Y13217I298J-267D01*
G02X775213Y13177I-1020J-1103D01*
G03X775217Y13738I-283J283D01*
G02X777267Y13778I1006J976D01*
G37*
G36*
G01X787428Y10616D02*
G03X787413Y10055I277J-288D01*
G02X785363I-1025J-957D01*
G03X785348Y10616I-292J273D01*
G02X785292Y12727I1040J1084D01*
G03Y13273I-292J273D01*
G02X785337Y15373I1096J1027D01*
G03X785347Y15935I-280J286D01*
G02X787398Y15953I1017J965D01*
G03X787419Y15392I295J-270D01*
G02X787484Y13273I-1031J-1092D01*
G03Y12727I292J-273D01*
G02X787428Y10616I-1096J-1027D01*
G37*
G36*
G01X733473Y5181D02*
G03X733531Y4648I324J-234D01*
G02X731462Y4419I-931J-1048D01*
G03X731404Y4952I-324J234D01*
G02X731087Y6639I931J1048D01*
G03X730892Y7188I-356J183D01*
G02X732705Y7832I565J1283D01*
G03X732900Y7283I356J-183D01*
G02X733473Y5181I-565J-1283D01*
G37*
G36*
G01X753005Y1417D02*
G03X753573Y1396I294J271D01*
G02X753495Y-717I1027J-1096D01*
G03X752927Y-696I-294J-271D01*
G02X753005Y1417I-1027J1096D01*
G37*
G36*
G01X755174Y-5280D02*
G03X754602I-286J-280D01*
G02Y-3320I-1002J980D01*
G03X755174I286J280D01*
G02Y-5280I1002J-980D01*
G37*
G36*
G01X787455Y-8133D02*
G03X787439Y-8694I277J-289D01*
G02X785389I-1025J-956D01*
G03X785373Y-8133I-293J272D01*
G02X785326Y-6015I1041J1083D01*
G03X785320Y-5458I-290J275D01*
G02X785347Y-3318I1068J1057D01*
G03X785363Y-2757I-277J289D01*
G02X787413I1025J956D01*
G03X787429Y-3318I293J-272D01*
G02X787476Y-5436I-1041J-1083D01*
G03X787482Y-5993I290J-275D01*
G02X787455Y-8133I-1068J-1057D01*
G37*
G36*
G01X755546Y24075D02*
G02X755482Y22271I1168J-945D01*
G03X754843Y22294I-328J-229D01*
G02X754907Y24098I-1168J945D01*
G03X755546Y24075I328J229D01*
G37*
G36*
G01X725357Y22469D02*
G03X724811Y22434I-254J-308D01*
G02X724737Y24563I-1096J1028D01*
G03X725284Y24566I272J293D01*
G02X725357Y22469I966J-1016D01*
G37*
G36*
G01X715347Y4379D02*
G03Y3825I288J-277D01*
G02X713327I-1010J-973D01*
G03Y4379I-288J277D01*
G02Y6325I1010J973D01*
G03Y6879I-288J277D01*
G02X715347I1010J973D01*
G03Y6325I288J-277D01*
G02Y4379I-1010J-973D01*
G37*
G36*
G01X718758Y-5937D02*
G03X718305Y-6270I-58J-396D01*
G02X717047Y-4652I-1384J222D01*
G03X717481Y-4295I36J398D01*
G02X718758Y-5937I1494J-156D01*
G37*
G36*
G01X730373Y-16381D02*
G03X729849Y-16451I-222J-333D01*
G02X727413Y-16212I-1133J986D01*
G03X726910Y-16042I-347J-199D01*
G02X725340Y-15790I-583J1384D01*
G03X724814I-263J-302D01*
G02Y-13526I-987J1132D01*
G03X725340I263J302D01*
G02X726809Y-13235I988J-1132D01*
G03X727337Y-12837I129J379D01*
G02X730275Y-13198I1500J74D01*
G03X730774Y-13697I383J-116D01*
G02X730373Y-16381I436J-1437D01*
G37*
G36*
G01X718635Y-14747D02*
G02X717155Y-16225I-80J-1400D01*
G03X716778Y-15848I-399J-22D01*
G02X718258Y-14370I80J1400D01*
G03X718635Y-14747I399J22D01*
G37*
G36*
G01X1313449Y618405D02*
G03X1312903I-273J-292D01*
G02Y620597I-1027J1096D01*
G03X1313449I273J292D01*
G02Y618405I1027J-1096D01*
G37*
G36*
G01X1299110Y597327D02*
G03Y596773I288J-277D01*
G02X1297090I-1010J-973D01*
G03Y597327I-288J277D01*
G02X1299110I1010J973D01*
G37*
G36*
G01Y591527D02*
G03Y590973I288J-277D01*
G02X1297090I-1010J-973D01*
G03Y591527I-288J277D01*
G02X1299110I1010J973D01*
G37*
G36*
G01X1295168Y580860D02*
G02X1293590Y579282I-78J-1500D01*
G03X1293212Y579660I-399J-21D01*
G02X1294790Y581238I78J1500D01*
G03X1295168Y580860I399J21D01*
G37*
G36*
G01X1297354Y526683D02*
G03X1296766I-294J-270D01*
G02X1294737Y528885I-1105J1018D01*
G03Y529515I-246J315D01*
G02Y531885I923J1185D01*
G03Y532515I-246J315D01*
G02Y534885I923J1185D01*
G03Y535515I-246J315D01*
G02X1296766Y537717I924J1184D01*
G03X1297354I294J270D01*
G02X1299383Y535515I1105J-1018D01*
G03Y534885I246J-315D01*
G02Y532515I-923J-1185D01*
G03Y531885I246J-315D01*
G02Y529515I-923J-1185D01*
G03Y528885I246J-315D01*
G02X1297354Y526683I-924J-1184D01*
G37*
G36*
G01X1283696Y582027D02*
G02X1281504I-1096J-1027D01*
G03Y582573I-292J273D01*
G02X1282512Y585099I1096J1027D01*
G03X1282793Y585758I-23J399D01*
G02X1284655Y584287I4610J3921D01*
G03X1284079Y583861I-182J-356D01*
G02X1283696Y582573I-1479J-261D01*
G03Y582027I292J-273D01*
G37*
G36*
G01X1291919Y574784D02*
G02X1290161Y576142I-4516J-4029D01*
G03X1290731Y576594I182J356D01*
G02X1290690Y577037I1459J358D01*
G03X1290291Y577460I-399J23D01*
G02X1291792Y578877I1J1502D01*
G03X1292191Y578454I399J-23D01*
G02X1292212Y575450I-1J-1502D01*
G03X1291919Y574784I5J-400D01*
G37*
G36*
G01X1286807Y560474D02*
G02X1286125Y562315I-1407J526D01*
G03X1286693Y562526I193J350D01*
G02X1288836Y563309I1407J-526D01*
G03X1289425Y563583I196J349D01*
G02X1290164Y561991I1475J-283D01*
G03X1289575Y561717I-196J-349D01*
G02X1287375Y560685I-1475J283D01*
G03X1286807Y560474I-193J-350D01*
G37*
G36*
G01X1320827Y524440D02*
G03X1320273I-277J-288D01*
G02X1318254Y526384I-973J1010D01*
G03Y526916I-298J266D01*
G02Y528784I1046J934D01*
G03Y529316I-298J266D01*
G02Y531184I1046J934D01*
G03Y531716I-298J266D01*
G02X1320232Y533697I1046J934D01*
G03X1320787Y533719I266J299D01*
G02X1322810Y531777I1013J-969D01*
G03Y531223I288J-277D01*
G02X1322846Y529316I-1010J-973D01*
G03Y528784I298J-266D01*
G02Y526916I-1046J-934D01*
G03Y526384I298J-266D01*
G02X1320827Y524440I-1046J-934D01*
G37*
G36*
G01X1314796Y516773D02*
G03Y516227I292J-273D01*
G02X1312604I-1096J-1027D01*
G03Y516773I-292J273D01*
G02X1314796I1096J1027D01*
G37*
G36*
G01X1297393Y509678D02*
G03X1296867I-263J-302D01*
G02X1294831Y511885I-986J1133D01*
G03X1294848Y512440I-279J286D01*
G02X1295037Y514635I1112J1010D01*
G03Y515265I-246J315D01*
G02Y517635I923J1185D01*
G03Y518265I-246J315D01*
G02X1296947Y520582I923J1185D01*
G03X1297473I263J302D01*
G02X1299383Y518265I987J-1132D01*
G03Y517635I246J-315D01*
G02Y515265I-923J-1185D01*
G03Y514635I246J-315D01*
G02X1299509Y512375I-923J-1185D01*
G03X1299492Y511820I279J-286D01*
G02X1297393Y509678I-1112J-1010D01*
G37*
G36*
G01X1225841Y606267D02*
G03X1225825Y605706I277J-289D01*
G02X1223775I-1025J-956D01*
G03X1223759Y606267I-293J272D01*
G02X1223712Y608385I1041J1083D01*
G03X1223706Y608942I-290J275D01*
G02X1223733Y611082I1068J1057D01*
G03X1223749Y611643I-277J289D01*
G02X1225799I1025J956D01*
G03X1225815Y611082I293J-272D01*
G02X1225862Y608964I-1041J-1083D01*
G03X1225868Y608407I290J-275D01*
G02X1225841Y606267I-1068J-1057D01*
G37*
G36*
G01X1230919Y606061D02*
G03X1230906Y605499I278J-288D01*
G02X1228858Y605489I-1019J-963D01*
G03X1228840Y606050I-293J271D01*
G02X1228781Y608170I1034J1090D01*
G03Y608719I-291J274D01*
G02X1228844Y610843I1093J1031D01*
G03X1228865Y611404I-274J291D01*
G02X1230915Y611383I1035J946D01*
G03X1230925Y610822I290J-275D01*
G02X1230967Y608719I-1051J-1073D01*
G03Y608170I291J-274D01*
G02X1230919Y606061I-1093J-1030D01*
G37*
G36*
G01X1256445Y611927D02*
G02X1253793Y611931I-1325J707D01*
G03X1253088Y611936I-354J-187D01*
G02X1253098Y613360I-1317J721D01*
G03X1253803Y613355I354J187D01*
G02X1256435Y613359I1317J-721D01*
G03X1257139Y613364I351J193D01*
G02X1259786Y613371I1325J-707D01*
G03X1260489I352J190D01*
G02X1263132I1322J-714D01*
G03X1263836I352J191D01*
G02Y611943I1321J-714D01*
G03X1263132I-352J-191D01*
G02X1260489I-1322J714D01*
G03X1259786I-351J-190D01*
G02X1257149Y611932I-1322J714D01*
G03X1256445Y611927I-351J-193D01*
G37*
G36*
G01X1265461Y605947D02*
G02X1263831Y603771I-304J-1471D01*
G03X1263127Y603776I-353J-188D01*
G02X1260489Y603785I-1317J723D01*
G03X1259786I-351J-190D01*
G02Y605213I-1322J714D01*
G03X1260489I352J190D01*
G02X1261997Y605989I1321J-714D01*
G03X1262435Y606478I49J397D01*
G02X1265155Y606441I1365J322D01*
G03X1265461Y605947I387J-102D01*
G37*
G36*
G01X1259786Y592885D02*
G02X1257143Y592883I-1322J714D01*
G03X1256440Y592884I-352J-190D01*
G02X1256441Y594316I-1320J717D01*
G03X1257144Y594315I352J190D01*
G02X1259786Y594313I1320J-716D01*
G03X1260489I352J190D01*
G02X1263132I1322J-714D01*
G03X1263836I352J191D01*
G02X1266256Y594623I1321J-714D01*
G03X1266826Y594608I292J273D01*
G02X1268811Y594571I974J-1008D01*
G03X1269389I289J277D01*
G02Y592629I1011J-971D01*
G03X1268811I-289J-277D01*
G02X1266827Y592591I-1011J971D01*
G03X1266256Y592576I-278J-288D01*
G02X1263836Y592885I-1099J1023D01*
G03X1263132I-352J-191D01*
G02X1260489I-1322J714D01*
G03X1259786I-351J-190D01*
G37*
G36*
G01X1246064Y590417D02*
G03X1246078Y589834I281J-285D01*
G02X1244078I-1000J-1120D01*
G03X1244092Y590417I-267J298D01*
G02X1246064I986J997D01*
G37*
G36*
G01X1239371D02*
G03X1239385Y589834I281J-285D01*
G02X1237385I-1000J-1120D01*
G03X1237399Y590417I-267J298D01*
G02X1239371I986J997D01*
G37*
G36*
G01X1221939D02*
G03X1221953Y589834I281J-285D01*
G02X1219953I-1000J-1120D01*
G03X1219967Y590417I-267J298D01*
G02X1221939I986J997D01*
G37*
G36*
G01X1230814Y587343D02*
G03X1230795Y586736I251J-312D01*
G02X1228923Y586751I-944J-1036D01*
G03X1228914Y587359I-265J300D01*
G02X1228778Y589541I960J1155D01*
G03Y590087I-292J273D01*
G02X1228833Y592197I1096J1027D01*
G03X1228849Y592758I-277J289D01*
G02X1230899I1025J956D01*
G03X1230915Y592197I293J-272D01*
G02X1230970Y590087I-1041J-1083D01*
G03Y589541I292J-273D01*
G02X1230814Y587343I-1096J-1027D01*
G37*
G36*
G01X1225814Y587216D02*
G03X1225799Y586655I277J-288D01*
G02X1223749I-1025J-957D01*
G03X1223734Y587216I-292J273D01*
G02X1223678Y589327I1040J1084D01*
G03Y589873I-292J273D01*
G02X1223723Y591973I1096J1027D01*
G03X1223733Y592535I-280J286D01*
G02X1225784Y592553I1017J965D01*
G03X1225805Y591992I295J-270D01*
G02X1225870Y589873I-1031J-1092D01*
G03Y589327I292J-273D01*
G02X1225814Y587216I-1096J-1027D01*
G37*
G36*
G01X1225841Y568467D02*
G03X1225825Y567906I277J-289D01*
G02X1223775I-1025J-956D01*
G03X1223759Y568467I-293J272D01*
G02X1223712Y570585I1041J1083D01*
G03X1223706Y571142I-290J275D01*
G02X1223733Y573282I1068J1057D01*
G03X1223749Y573843I-277J289D01*
G02X1225799I1025J956D01*
G03X1225815Y573282I293J-272D01*
G02X1225862Y571164I-1041J-1083D01*
G03X1225868Y570607I290J-275D01*
G02X1225841Y568467I-1068J-1057D01*
G37*
G36*
G01X1230919Y568261D02*
G03X1230906Y567699I278J-288D01*
G02X1228858Y567689I-1019J-963D01*
G03X1228840Y568250I-293J271D01*
G02X1228781Y570370I1034J1090D01*
G03Y570919I-291J274D01*
G02X1228844Y573043I1093J1031D01*
G03X1228865Y573604I-274J291D01*
G02X1230915Y573583I1035J946D01*
G03X1230925Y573022I290J-275D01*
G02X1230967Y570919I-1051J-1073D01*
G03Y570370I291J-274D01*
G02X1230919Y568261I-1093J-1030D01*
G37*
G36*
G01X1246064Y552617D02*
G03X1246078Y552034I281J-285D01*
G02X1244078I-1000J-1120D01*
G03X1244092Y552617I-267J298D01*
G02X1246064I986J997D01*
G37*
G36*
G01X1239371D02*
G03X1239385Y552034I281J-285D01*
G02X1237385I-1000J-1120D01*
G03X1237399Y552617I-267J298D01*
G02X1239371I986J997D01*
G37*
G36*
G01X1221939D02*
G03X1221953Y552034I281J-285D01*
G02X1219953I-1000J-1120D01*
G03X1219967Y552617I-267J298D01*
G02X1221939I986J997D01*
G37*
G36*
G01X1230814Y549543D02*
G03X1230795Y548936I251J-312D01*
G02X1228923Y548951I-944J-1036D01*
G03X1228914Y549559I-265J300D01*
G02X1228778Y551741I960J1155D01*
G03Y552287I-292J273D01*
G02X1228833Y554397I1096J1027D01*
G03X1228849Y554958I-277J289D01*
G02X1230899I1025J956D01*
G03X1230915Y554397I293J-272D01*
G02X1230970Y552287I-1041J-1083D01*
G03Y551741I292J-273D01*
G02X1230814Y549543I-1096J-1027D01*
G37*
G36*
G01X1225814Y549416D02*
G03X1225799Y548855I277J-288D01*
G02X1223749I-1025J-957D01*
G03X1223734Y549416I-292J273D01*
G02X1223678Y551527I1040J1084D01*
G03Y552073I-292J273D01*
G02X1223723Y554173I1096J1027D01*
G03X1223733Y554735I-280J286D01*
G02X1225784Y554753I1017J965D01*
G03X1225805Y554192I295J-270D01*
G02X1225870Y552073I-1031J-1092D01*
G03Y551527I292J-273D01*
G02X1225814Y549416I-1096J-1027D01*
G37*
G36*
G01X1225841Y530667D02*
G03X1225825Y530106I277J-289D01*
G02X1223775I-1025J-956D01*
G03X1223759Y530667I-293J272D01*
G02X1223712Y532785I1041J1083D01*
G03X1223706Y533342I-290J275D01*
G02X1223733Y535482I1068J1057D01*
G03X1223749Y536043I-277J289D01*
G02X1225799I1025J956D01*
G03X1225815Y535482I293J-272D01*
G02X1225862Y533364I-1041J-1083D01*
G03X1225868Y532807I290J-275D01*
G02X1225841Y530667I-1068J-1057D01*
G37*
G36*
G01X1230919Y530461D02*
G03X1230906Y529899I278J-288D01*
G02X1228858Y529889I-1019J-963D01*
G03X1228840Y530450I-293J271D01*
G02X1228781Y532570I1034J1090D01*
G03Y533119I-291J274D01*
G02X1228844Y535243I1093J1031D01*
G03X1228865Y535804I-274J291D01*
G02X1230915Y535783I1035J946D01*
G03X1230925Y535222I290J-275D01*
G02X1230967Y533119I-1051J-1073D01*
G03Y532570I291J-274D01*
G02X1230919Y530461I-1093J-1030D01*
G37*
G36*
G01X1259786Y585043D02*
G02Y586471I-1322J714D01*
G03X1260489I352J190D01*
G02X1263132I1322J-714D01*
G03X1263836I352J191D01*
G02Y585043I1321J-714D01*
G03X1263132I-352J-191D01*
G02X1260489I-1322J714D01*
G03X1259786I-351J-190D01*
G37*
G36*
G01X1267071Y575431D02*
G02X1266696Y573582I829J-1131D01*
G03X1266101Y573689I-344J-204D01*
G02X1263836Y574143I-944J1168D01*
G03X1263132I-352J-191D01*
G02X1260489I-1322J714D01*
G03X1259786I-351J-190D01*
G02X1257149Y574132I-1322J714D01*
G03X1256445Y574127I-351J-193D01*
G02X1253793Y574131I-1325J707D01*
G03X1253088Y574136I-354J-187D01*
G02X1253098Y575560I-1317J721D01*
G03X1253803Y575555I354J187D01*
G02X1256435Y575559I1317J-721D01*
G03X1257139Y575564I351J193D01*
G02X1259786Y575571I1325J-707D01*
G03X1260489I352J190D01*
G02X1263132I1322J-714D01*
G03X1263836I352J191D01*
G02X1266482Y575565I1321J-714D01*
G03X1267071Y575431I353J188D01*
G37*
G36*
G01X1263841Y567399D02*
G02X1263831Y565971I1316J-723D01*
G03X1263127Y565976I-353J-188D01*
G02X1260489Y565985I-1317J723D01*
G03X1259786I-351J-190D01*
G02Y567413I-1322J714D01*
G03X1260489I352J190D01*
G02X1263137Y567404I1322J-714D01*
G03X1263841Y567399I353J188D01*
G37*
G36*
G01X1259786Y555085D02*
G02Y556513I-1322J714D01*
G03X1260489I352J190D01*
G02X1263132I1322J-714D01*
G03X1263836I352J191D01*
G02Y555085I1321J-714D01*
G03X1263132I-352J-191D01*
G02X1260489I-1322J714D01*
G03X1259786I-351J-190D01*
G37*
G36*
G01X1250462Y556536D02*
G02X1250437Y555108I1309J-737D01*
G03X1249734Y555120I-355J-184D01*
G02X1249759Y556548I-1309J737D01*
G03X1250462Y556536I355J184D01*
G37*
G36*
G01X1259786Y547243D02*
G02Y548671I-1322J714D01*
G03X1260489I352J190D01*
G02X1263132I1322J-714D01*
G03X1263836I352J191D01*
G02Y547243I1321J-714D01*
G03X1263132I-352J-191D01*
G02X1260489I-1322J714D01*
G03X1259786I-351J-190D01*
G37*
G36*
G01X1279078Y546695D02*
G02X1277835Y545452I240J-1483D01*
G03X1277377Y545910I-395J63D01*
G02X1278620Y547153I-240J1483D01*
G03X1279078Y546695I395J-63D01*
G37*
G36*
G01X1256445Y536327D02*
G02X1253793Y536331I-1325J707D01*
G03X1253088Y536336I-354J-187D01*
G02X1253098Y537760I-1317J721D01*
G03X1253803Y537755I354J187D01*
G02X1256435Y537759I1317J-721D01*
G03X1257139Y537764I351J193D01*
G02X1259786Y537771I1325J-707D01*
G03X1260489I352J190D01*
G02X1263132I1322J-714D01*
G03X1263836I352J191D01*
G02Y536343I1321J-714D01*
G03X1263132I-352J-191D01*
G02X1260489I-1322J714D01*
G03X1259786I-351J-190D01*
G02X1257149Y536332I-1322J714D01*
G03X1256445Y536327I-351J-193D01*
G37*
G36*
G01X1263841Y529599D02*
G02X1263831Y528171I1316J-723D01*
G03X1263127Y528176I-353J-188D01*
G02X1260489Y528185I-1317J723D01*
G03X1259786I-351J-190D01*
G02Y529613I-1322J714D01*
G03X1260489I352J190D01*
G02X1263137Y529604I1322J-714D01*
G03X1263841Y529599I353J188D01*
G37*
G36*
G01X1246064Y514817D02*
G03X1246078Y514234I281J-285D01*
G02X1244078I-1000J-1120D01*
G03X1244092Y514817I-267J298D01*
G02X1246064I986J997D01*
G37*
G36*
G01X1239371D02*
G03X1239385Y514234I281J-285D01*
G02X1237385I-1000J-1120D01*
G03X1237399Y514817I-267J298D01*
G02X1239371I986J997D01*
G37*
G36*
G01X1221939D02*
G03X1221953Y514234I281J-285D01*
G02X1219953I-1000J-1120D01*
G03X1219967Y514817I-267J298D01*
G02X1221939I986J997D01*
G37*
G36*
G01X1230814Y511743D02*
G03X1230795Y511136I251J-312D01*
G02X1228923Y511151I-944J-1036D01*
G03X1228914Y511759I-265J300D01*
G02X1228778Y513941I960J1155D01*
G03Y514487I-292J273D01*
G02X1228833Y516597I1096J1027D01*
G03X1228849Y517158I-277J289D01*
G02X1230899I1025J956D01*
G03X1230915Y516597I293J-272D01*
G02X1230970Y514487I-1041J-1083D01*
G03Y513941I292J-273D01*
G02X1230814Y511743I-1096J-1027D01*
G37*
G36*
G01X1225814Y511616D02*
G03X1225799Y511055I277J-288D01*
G02X1223749I-1025J-957D01*
G03X1223734Y511616I-292J273D01*
G02X1223678Y513727I1040J1084D01*
G03Y514273I-292J273D01*
G02X1223723Y516373I1096J1027D01*
G03X1223733Y516935I-280J286D01*
G02X1225784Y516953I1017J965D01*
G03X1225805Y516392I295J-270D01*
G02X1225870Y514273I-1031J-1092D01*
G03Y513727I292J-273D01*
G02X1225814Y511616I-1096J-1027D01*
G37*
G36*
G01X1259786Y517285D02*
G02X1257143Y517283I-1322J714D01*
G03X1256440Y517284I-352J-190D01*
G02X1256441Y518716I-1320J717D01*
G03X1257144Y518715I352J190D01*
G02X1259786Y518713I1320J-716D01*
G03X1260489I352J190D01*
G02X1263132I1322J-714D01*
G03X1263836I352J191D01*
G02Y517285I1321J-714D01*
G03X1263132I-352J-191D01*
G02X1260489I-1322J714D01*
G03X1259786I-351J-190D01*
G37*
G36*
G01X1273365Y511124D02*
G02X1273199Y509634I1211J-889D01*
G03X1272511Y509711I-366J-160D01*
G02X1272677Y511201I-1211J889D01*
G03X1273365Y511124I366J160D01*
G37*
G36*
G01X1253094Y509445D02*
G02X1253093Y510870I-1323J712D01*
G03X1253797I352J190D01*
G02X1256441Y510874I1323J-712D01*
G03X1257144Y510873I352J190D01*
G02X1259786Y510871I1320J-716D01*
G03X1260489I352J190D01*
G02X1263132I1322J-714D01*
G03X1263836I352J191D01*
G02Y509443I1321J-714D01*
G03X1263132I-352J-191D01*
G02X1260489I-1322J714D01*
G03X1259786I-351J-190D01*
G02X1257143Y509441I-1322J714D01*
G03X1256440Y509442I-352J-190D01*
G02X1253798Y509445I-1320J716D01*
G03X1253094I-352J-190D01*
G37*
G36*
G01X1189030Y606267D02*
G03X1189014Y605706I277J-289D01*
G02X1186964I-1025J-956D01*
G03X1186948Y606267I-293J272D01*
G02X1186901Y608385I1041J1083D01*
G03X1186895Y608942I-290J275D01*
G02X1186922Y611082I1068J1057D01*
G03X1186938Y611643I-277J289D01*
G02X1188988I1025J956D01*
G03X1189004Y611082I293J-272D01*
G02X1189051Y608964I-1041J-1083D01*
G03X1189057Y608407I290J-275D01*
G02X1189030Y606267I-1068J-1057D01*
G37*
G36*
G01X1194108Y606061D02*
G03X1194095Y605499I278J-288D01*
G02X1192047Y605489I-1019J-963D01*
G03X1192029Y606050I-293J271D01*
G02X1191970Y608170I1034J1090D01*
G03Y608719I-291J274D01*
G02X1192033Y610843I1093J1031D01*
G03X1192054Y611404I-274J291D01*
G02X1194104Y611383I1035J946D01*
G03X1194114Y610822I290J-275D01*
G02X1194156Y608719I-1051J-1073D01*
G03Y608170I291J-274D01*
G02X1194108Y606061I-1093J-1030D01*
G37*
G36*
G01X1209253Y590417D02*
G03X1209267Y589834I281J-285D01*
G02X1207267I-1000J-1120D01*
G03X1207281Y590417I-267J298D01*
G02X1209253I986J997D01*
G37*
G36*
G01X1202560D02*
G03X1202574Y589834I281J-285D01*
G02X1200574I-1000J-1120D01*
G03X1200588Y590417I-267J298D01*
G02X1202560I986J997D01*
G37*
G36*
G01X1185128D02*
G03X1185142Y589834I281J-285D01*
G02X1183142I-1000J-1120D01*
G03X1183156Y590417I-267J298D01*
G02X1185128I986J997D01*
G37*
G36*
G01X1178842Y590378D02*
G03X1178869Y589817I298J-267D01*
G02X1176788Y589777I-1020J-1103D01*
G03X1176792Y590338I-283J283D01*
G02X1178842Y590378I1006J976D01*
G37*
G36*
G01X1172442Y590417D02*
G03X1172456Y589834I281J-285D01*
G02X1170456I-1000J-1120D01*
G03X1170470Y590417I-267J298D01*
G02X1172442I986J997D01*
G37*
G36*
G01X1165749D02*
G03X1165763Y589834I281J-285D01*
G02X1163763I-1000J-1120D01*
G03X1163777Y590417I-267J298D01*
G02X1165749I986J997D01*
G37*
G36*
G01X1194003Y587343D02*
G03X1193984Y586736I251J-312D01*
G02X1192112Y586751I-944J-1036D01*
G03X1192103Y587359I-265J300D01*
G02X1191967Y589541I960J1155D01*
G03Y590087I-292J273D01*
G02X1192022Y592197I1096J1027D01*
G03X1192038Y592758I-277J289D01*
G02X1194088I1025J956D01*
G03X1194104Y592197I293J-272D01*
G02X1194159Y590087I-1041J-1083D01*
G03Y589541I292J-273D01*
G02X1194003Y587343I-1096J-1027D01*
G37*
G36*
G01X1189003Y587216D02*
G03X1188988Y586655I277J-288D01*
G02X1186938I-1025J-957D01*
G03X1186923Y587216I-292J273D01*
G02X1186867Y589327I1040J1084D01*
G03Y589873I-292J273D01*
G02X1186912Y591973I1096J1027D01*
G03X1186922Y592535I-280J286D01*
G02X1188973Y592553I1017J965D01*
G03X1188994Y591992I295J-270D01*
G02X1189059Y589873I-1031J-1092D01*
G03Y589327I292J-273D01*
G02X1189003Y587216I-1096J-1027D01*
G37*
G36*
G01X1189030Y568467D02*
G03X1189014Y567906I277J-289D01*
G02X1186964I-1025J-956D01*
G03X1186948Y568467I-293J272D01*
G02X1186901Y570585I1041J1083D01*
G03X1186895Y571142I-290J275D01*
G02X1186922Y573282I1068J1057D01*
G03X1186938Y573843I-277J289D01*
G02X1188988I1025J956D01*
G03X1189004Y573282I293J-272D01*
G02X1189051Y571164I-1041J-1083D01*
G03X1189057Y570607I290J-275D01*
G02X1189030Y568467I-1068J-1057D01*
G37*
G36*
G01X1194108Y568261D02*
G03X1194095Y567699I278J-288D01*
G02X1192047Y567689I-1019J-963D01*
G03X1192029Y568250I-293J271D01*
G02X1191970Y570370I1034J1090D01*
G03Y570919I-291J274D01*
G02X1192033Y573043I1093J1031D01*
G03X1192054Y573604I-274J291D01*
G02X1194104Y573583I1035J946D01*
G03X1194114Y573022I290J-275D01*
G02X1194156Y570919I-1051J-1073D01*
G03Y570370I291J-274D01*
G02X1194108Y568261I-1093J-1030D01*
G37*
G36*
G01X1209253Y552617D02*
G03X1209267Y552034I281J-285D01*
G02X1207267I-1000J-1120D01*
G03X1207281Y552617I-267J298D01*
G02X1209253I986J997D01*
G37*
G36*
G01X1202560D02*
G03X1202574Y552034I281J-285D01*
G02X1200574I-1000J-1120D01*
G03X1200588Y552617I-267J298D01*
G02X1202560I986J997D01*
G37*
G36*
G01X1185128D02*
G03X1185142Y552034I281J-285D01*
G02X1183142I-1000J-1120D01*
G03X1183156Y552617I-267J298D01*
G02X1185128I986J997D01*
G37*
G36*
G01X1178842Y552578D02*
G03X1178869Y552017I298J-267D01*
G02X1176788Y551977I-1020J-1103D01*
G03X1176792Y552538I-283J283D01*
G02X1178842Y552578I1006J976D01*
G37*
G36*
G01X1172442Y552617D02*
G03X1172456Y552034I281J-285D01*
G02X1170456I-1000J-1120D01*
G03X1170470Y552617I-267J298D01*
G02X1172442I986J997D01*
G37*
G36*
G01X1165749D02*
G03X1165763Y552034I281J-285D01*
G02X1163763I-1000J-1120D01*
G03X1163777Y552617I-267J298D01*
G02X1165749I986J997D01*
G37*
G36*
G01X1194003Y549543D02*
G03X1193984Y548936I251J-312D01*
G02X1192112Y548951I-944J-1036D01*
G03X1192103Y549559I-265J300D01*
G02X1191967Y551741I960J1155D01*
G03Y552287I-292J273D01*
G02X1192022Y554397I1096J1027D01*
G03X1192038Y554958I-277J289D01*
G02X1194088I1025J956D01*
G03X1194104Y554397I293J-272D01*
G02X1194159Y552287I-1041J-1083D01*
G03Y551741I292J-273D01*
G02X1194003Y549543I-1096J-1027D01*
G37*
G36*
G01X1189003Y549416D02*
G03X1188988Y548855I277J-288D01*
G02X1186938I-1025J-957D01*
G03X1186923Y549416I-292J273D01*
G02X1186867Y551527I1040J1084D01*
G03Y552073I-292J273D01*
G02X1186912Y554173I1096J1027D01*
G03X1186922Y554735I-280J286D01*
G02X1188973Y554753I1017J965D01*
G03X1188994Y554192I295J-270D01*
G02X1189059Y552073I-1031J-1092D01*
G03Y551527I292J-273D01*
G02X1189003Y549416I-1096J-1027D01*
G37*
G36*
G01X1189030Y530667D02*
G03X1189014Y530106I277J-289D01*
G02X1186964I-1025J-956D01*
G03X1186948Y530667I-293J272D01*
G02X1186901Y532785I1041J1083D01*
G03X1186895Y533342I-290J275D01*
G02X1186922Y535482I1068J1057D01*
G03X1186938Y536043I-277J289D01*
G02X1188988I1025J956D01*
G03X1189004Y535482I293J-272D01*
G02X1189051Y533364I-1041J-1083D01*
G03X1189057Y532807I290J-275D01*
G02X1189030Y530667I-1068J-1057D01*
G37*
G36*
G01X1194108Y530461D02*
G03X1194095Y529899I278J-288D01*
G02X1192047Y529889I-1019J-963D01*
G03X1192029Y530450I-293J271D01*
G02X1191970Y532570I1034J1090D01*
G03Y533119I-291J274D01*
G02X1192033Y535243I1093J1031D01*
G03X1192054Y535804I-274J291D01*
G02X1194104Y535783I1035J946D01*
G03X1194114Y535222I290J-275D01*
G02X1194156Y533119I-1051J-1073D01*
G03Y532570I291J-274D01*
G02X1194108Y530461I-1093J-1030D01*
G37*
G36*
G01X1209253Y514817D02*
G03X1209267Y514234I281J-285D01*
G02X1207267I-1000J-1120D01*
G03X1207281Y514817I-267J298D01*
G02X1209253I986J997D01*
G37*
G36*
G01X1202560D02*
G03X1202574Y514234I281J-285D01*
G02X1200574I-1000J-1120D01*
G03X1200588Y514817I-267J298D01*
G02X1202560I986J997D01*
G37*
G36*
G01X1185128D02*
G03X1185142Y514234I281J-285D01*
G02X1183142I-1000J-1120D01*
G03X1183156Y514817I-267J298D01*
G02X1185128I986J997D01*
G37*
G36*
G01X1178842Y514778D02*
G03X1178869Y514217I298J-267D01*
G02X1176788Y514177I-1020J-1103D01*
G03X1176792Y514738I-283J283D01*
G02X1178842Y514778I1006J976D01*
G37*
G36*
G01X1172442Y514817D02*
G03X1172456Y514234I281J-285D01*
G02X1170456I-1000J-1120D01*
G03X1170470Y514817I-267J298D01*
G02X1172442I986J997D01*
G37*
G36*
G01X1165749D02*
G03X1165763Y514234I281J-285D01*
G02X1163763I-1000J-1120D01*
G03X1163777Y514817I-267J298D01*
G02X1165749I986J997D01*
G37*
G36*
G01X1194003Y511743D02*
G03X1193984Y511136I251J-312D01*
G02X1192112Y511151I-944J-1036D01*
G03X1192103Y511759I-265J300D01*
G02X1191967Y513941I960J1155D01*
G03Y514487I-292J273D01*
G02X1192022Y516597I1096J1027D01*
G03X1192038Y517158I-277J289D01*
G02X1194088I1025J956D01*
G03X1194104Y516597I293J-272D01*
G02X1194159Y514487I-1041J-1083D01*
G03Y513941I292J-273D01*
G02X1194003Y511743I-1096J-1027D01*
G37*
G36*
G01X1189003Y511616D02*
G03X1188988Y511055I277J-288D01*
G02X1186938I-1025J-957D01*
G03X1186923Y511616I-292J273D01*
G02X1186867Y513727I1040J1084D01*
G03Y514273I-292J273D01*
G02X1186912Y516373I1096J1027D01*
G03X1186922Y516935I-280J286D01*
G02X1188973Y516953I1017J965D01*
G03X1188994Y516392I295J-270D01*
G02X1189059Y514273I-1031J-1092D01*
G03Y513727I292J-273D01*
G02X1189003Y511616I-1096J-1027D01*
G37*
G36*
G01X1152219Y606267D02*
G03X1152203Y605706I277J-289D01*
G02X1150153I-1025J-956D01*
G03X1150137Y606267I-293J272D01*
G02X1150090Y608385I1041J1083D01*
G03X1150084Y608942I-290J275D01*
G02X1150111Y611082I1068J1057D01*
G03X1150127Y611643I-277J289D01*
G02X1152177I1025J956D01*
G03X1152193Y611082I293J-272D01*
G02X1152240Y608964I-1041J-1083D01*
G03X1152246Y608407I290J-275D01*
G02X1152219Y606267I-1068J-1057D01*
G37*
G36*
G01X1115407D02*
G03X1115391Y605706I277J-289D01*
G02X1113341I-1025J-956D01*
G03X1113325Y606267I-293J272D01*
G02X1113278Y608385I1041J1083D01*
G03X1113272Y608942I-290J275D01*
G02X1113299Y611082I1068J1057D01*
G03X1113315Y611643I-277J289D01*
G02X1115365I1025J956D01*
G03X1115381Y611082I293J-272D01*
G02X1115428Y608964I-1041J-1083D01*
G03X1115434Y608407I290J-275D01*
G02X1115407Y606267I-1068J-1057D01*
G37*
G36*
G01X1157297Y606061D02*
G03X1157284Y605499I278J-288D01*
G02X1155236Y605489I-1019J-963D01*
G03X1155218Y606050I-293J271D01*
G02X1155159Y608170I1034J1090D01*
G03Y608719I-291J274D01*
G02X1155222Y610843I1093J1031D01*
G03X1155243Y611404I-274J291D01*
G02X1157293Y611383I1035J946D01*
G03X1157303Y610822I290J-275D01*
G02X1157345Y608719I-1051J-1073D01*
G03Y608170I291J-274D01*
G02X1157297Y606061I-1093J-1030D01*
G37*
G36*
G01X1120485D02*
G03X1120472Y605499I278J-288D01*
G02X1118424Y605489I-1019J-963D01*
G03X1118406Y606050I-293J271D01*
G02X1118347Y608170I1034J1090D01*
G03Y608719I-291J274D01*
G02X1118410Y610843I1093J1031D01*
G03X1118431Y611404I-274J291D01*
G02X1120481Y611383I1035J946D01*
G03X1120491Y610822I290J-275D01*
G02X1120533Y608719I-1051J-1073D01*
G03Y608170I291J-274D01*
G02X1120485Y606061I-1093J-1030D01*
G37*
G36*
G01X1148317Y590417D02*
G03X1148331Y589834I281J-285D01*
G02X1146331I-1000J-1120D01*
G03X1146345Y590417I-267J298D01*
G02X1148317I986J997D01*
G37*
G36*
G01X1142031Y590378D02*
G03X1142058Y589817I298J-267D01*
G02X1139977Y589777I-1020J-1103D01*
G03X1139981Y590338I-283J283D01*
G02X1142031Y590378I1006J976D01*
G37*
G36*
G01X1135631Y590417D02*
G03X1135645Y589834I281J-285D01*
G02X1133645I-1000J-1120D01*
G03X1133659Y590417I-267J298D01*
G02X1135631I986J997D01*
G37*
G36*
G01X1128938D02*
G03X1128952Y589834I281J-285D01*
G02X1126952I-1000J-1120D01*
G03X1126966Y590417I-267J298D01*
G02X1128938I986J997D01*
G37*
G36*
G01X1111545Y590358D02*
G03X1111561Y589797I293J-272D01*
G02X1109479I-1041J-1083D01*
G03X1109495Y590358I-277J289D01*
G02X1111545I1025J956D01*
G37*
G36*
G01X1105220Y590378D02*
G03X1105247Y589817I298J-267D01*
G02X1103166Y589777I-1020J-1103D01*
G03X1103170Y590338I-283J283D01*
G02X1105220Y590378I1006J976D01*
G37*
G36*
G01X1096799Y589794D02*
G03X1097019Y590330I-145J373D01*
G02X1098874Y589621I1281J570D01*
G03X1098682Y589075I164J-365D01*
G02X1096799Y589794I-1339J-681D01*
G37*
G36*
G01X1157192Y587343D02*
G03X1157173Y586736I251J-312D01*
G02X1155301Y586751I-944J-1036D01*
G03X1155292Y587359I-265J300D01*
G02X1155156Y589541I960J1155D01*
G03Y590087I-292J273D01*
G02X1155211Y592197I1096J1027D01*
G03X1155227Y592758I-277J289D01*
G02X1157277I1025J956D01*
G03X1157293Y592197I293J-272D01*
G02X1157348Y590087I-1041J-1083D01*
G03Y589541I292J-273D01*
G02X1157192Y587343I-1096J-1027D01*
G37*
G36*
G01X1120380D02*
G03X1120361Y586736I251J-312D01*
G02X1118489Y586751I-944J-1036D01*
G03X1118480Y587359I-265J300D01*
G02X1118344Y589541I960J1155D01*
G03Y590087I-292J273D01*
G02X1118399Y592197I1096J1027D01*
G03X1118415Y592758I-277J289D01*
G02X1120465I1025J956D01*
G03X1120481Y592197I293J-272D01*
G02X1120536Y590087I-1041J-1083D01*
G03Y589541I292J-273D01*
G02X1120380Y587343I-1096J-1027D01*
G37*
G36*
G01X1152192Y587216D02*
G03X1152177Y586655I277J-288D01*
G02X1150127I-1025J-957D01*
G03X1150112Y587216I-292J273D01*
G02X1150056Y589327I1040J1084D01*
G03Y589873I-292J273D01*
G02X1150101Y591973I1096J1027D01*
G03X1150111Y592535I-280J286D01*
G02X1152162Y592553I1017J965D01*
G03X1152183Y591992I295J-270D01*
G02X1152248Y589873I-1031J-1092D01*
G03Y589327I292J-273D01*
G02X1152192Y587216I-1096J-1027D01*
G37*
G36*
G01X1115380D02*
G03X1115365Y586655I277J-288D01*
G02X1113315I-1025J-957D01*
G03X1113300Y587216I-292J273D01*
G02X1113244Y589327I1040J1084D01*
G03Y589873I-292J273D01*
G02X1113289Y591973I1096J1027D01*
G03X1113299Y592535I-280J286D01*
G02X1115350Y592553I1017J965D01*
G03X1115371Y591992I295J-270D01*
G02X1115436Y589873I-1031J-1092D01*
G03Y589327I292J-273D01*
G02X1115380Y587216I-1096J-1027D01*
G37*
G36*
G01X1152219Y568467D02*
G03X1152203Y567906I277J-289D01*
G02X1150153I-1025J-956D01*
G03X1150137Y568467I-293J272D01*
G02X1150090Y570585I1041J1083D01*
G03X1150084Y571142I-290J275D01*
G02X1150111Y573282I1068J1057D01*
G03X1150127Y573843I-277J289D01*
G02X1152177I1025J956D01*
G03X1152193Y573282I293J-272D01*
G02X1152240Y571164I-1041J-1083D01*
G03X1152246Y570607I290J-275D01*
G02X1152219Y568467I-1068J-1057D01*
G37*
G36*
G01X1115407D02*
G03X1115391Y567906I277J-289D01*
G02X1113341I-1025J-956D01*
G03X1113325Y568467I-293J272D01*
G02X1113278Y570585I1041J1083D01*
G03X1113272Y571142I-290J275D01*
G02X1113299Y573282I1068J1057D01*
G03X1113315Y573843I-277J289D01*
G02X1115365I1025J956D01*
G03X1115381Y573282I293J-272D01*
G02X1115428Y571164I-1041J-1083D01*
G03X1115434Y570607I290J-275D01*
G02X1115407Y568467I-1068J-1057D01*
G37*
G36*
G01X1157297Y568261D02*
G03X1157284Y567699I278J-288D01*
G02X1155236Y567689I-1019J-963D01*
G03X1155218Y568250I-293J271D01*
G02X1155159Y570370I1034J1090D01*
G03Y570919I-291J274D01*
G02X1155222Y573043I1093J1031D01*
G03X1155243Y573604I-274J291D01*
G02X1157293Y573583I1035J946D01*
G03X1157303Y573022I290J-275D01*
G02X1157345Y570919I-1051J-1073D01*
G03Y570370I291J-274D01*
G02X1157297Y568261I-1093J-1030D01*
G37*
G36*
G01X1120485D02*
G03X1120472Y567699I278J-288D01*
G02X1118424Y567689I-1019J-963D01*
G03X1118406Y568250I-293J271D01*
G02X1118347Y570370I1034J1090D01*
G03Y570919I-291J274D01*
G02X1118410Y573043I1093J1031D01*
G03X1118431Y573604I-274J291D01*
G02X1120481Y573583I1035J946D01*
G03X1120491Y573022I290J-275D01*
G02X1120533Y570919I-1051J-1073D01*
G03Y570370I291J-274D01*
G02X1120485Y568261I-1093J-1030D01*
G37*
G36*
G01X1148317Y552617D02*
G03X1148331Y552034I281J-285D01*
G02X1146331I-1000J-1120D01*
G03X1146345Y552617I-267J298D01*
G02X1148317I986J997D01*
G37*
G36*
G01X1142031Y552578D02*
G03X1142058Y552017I298J-267D01*
G02X1139977Y551977I-1020J-1103D01*
G03X1139981Y552538I-283J283D01*
G02X1142031Y552578I1006J976D01*
G37*
G36*
G01X1135631Y552617D02*
G03X1135645Y552034I281J-285D01*
G02X1133645I-1000J-1120D01*
G03X1133659Y552617I-267J298D01*
G02X1135631I986J997D01*
G37*
G36*
G01X1128938D02*
G03X1128952Y552034I281J-285D01*
G02X1126952I-1000J-1120D01*
G03X1126966Y552617I-267J298D01*
G02X1128938I986J997D01*
G37*
G36*
G01X1111545Y552558D02*
G03X1111561Y551997I293J-272D01*
G02X1109479I-1041J-1083D01*
G03X1109495Y552558I-277J289D01*
G02X1111545I1025J956D01*
G37*
G36*
G01X1105220Y552578D02*
G03X1105247Y552017I298J-267D01*
G02X1103166Y551977I-1020J-1103D01*
G03X1103170Y552538I-283J283D01*
G02X1105220Y552578I1006J976D01*
G37*
G36*
G01X1157192Y549543D02*
G03X1157173Y548936I251J-312D01*
G02X1155301Y548951I-944J-1036D01*
G03X1155292Y549559I-265J300D01*
G02X1155156Y551741I960J1155D01*
G03Y552287I-292J273D01*
G02X1155211Y554397I1096J1027D01*
G03X1155227Y554958I-277J289D01*
G02X1157277I1025J956D01*
G03X1157293Y554397I293J-272D01*
G02X1157348Y552287I-1041J-1083D01*
G03Y551741I292J-273D01*
G02X1157192Y549543I-1096J-1027D01*
G37*
G36*
G01X1120380D02*
G03X1120361Y548936I251J-312D01*
G02X1118489Y548951I-944J-1036D01*
G03X1118480Y549559I-265J300D01*
G02X1118344Y551741I960J1155D01*
G03Y552287I-292J273D01*
G02X1118399Y554397I1096J1027D01*
G03X1118415Y554958I-277J289D01*
G02X1120465I1025J956D01*
G03X1120481Y554397I293J-272D01*
G02X1120536Y552287I-1041J-1083D01*
G03Y551741I292J-273D01*
G02X1120380Y549543I-1096J-1027D01*
G37*
G36*
G01X1152192Y549416D02*
G03X1152177Y548855I277J-288D01*
G02X1150127I-1025J-957D01*
G03X1150112Y549416I-292J273D01*
G02X1150056Y551527I1040J1084D01*
G03Y552073I-292J273D01*
G02X1150101Y554173I1096J1027D01*
G03X1150111Y554735I-280J286D01*
G02X1152162Y554753I1017J965D01*
G03X1152183Y554192I295J-270D01*
G02X1152248Y552073I-1031J-1092D01*
G03Y551527I292J-273D01*
G02X1152192Y549416I-1096J-1027D01*
G37*
G36*
G01X1115380D02*
G03X1115365Y548855I277J-288D01*
G02X1113315I-1025J-957D01*
G03X1113300Y549416I-292J273D01*
G02X1113244Y551527I1040J1084D01*
G03Y552073I-292J273D01*
G02X1113289Y554173I1096J1027D01*
G03X1113299Y554735I-280J286D01*
G02X1115350Y554753I1017J965D01*
G03X1115371Y554192I295J-270D01*
G02X1115436Y552073I-1031J-1092D01*
G03Y551527I292J-273D01*
G02X1115380Y549416I-1096J-1027D01*
G37*
G36*
G01X1152219Y530667D02*
G03X1152203Y530106I277J-289D01*
G02X1150153I-1025J-956D01*
G03X1150137Y530667I-293J272D01*
G02X1150090Y532785I1041J1083D01*
G03X1150084Y533342I-290J275D01*
G02X1150111Y535482I1068J1057D01*
G03X1150127Y536043I-277J289D01*
G02X1152177I1025J956D01*
G03X1152193Y535482I293J-272D01*
G02X1152240Y533364I-1041J-1083D01*
G03X1152246Y532807I290J-275D01*
G02X1152219Y530667I-1068J-1057D01*
G37*
G36*
G01X1115407D02*
G03X1115391Y530106I277J-289D01*
G02X1113341I-1025J-956D01*
G03X1113325Y530667I-293J272D01*
G02X1113278Y532785I1041J1083D01*
G03X1113272Y533342I-290J275D01*
G02X1113299Y535482I1068J1057D01*
G03X1113315Y536043I-277J289D01*
G02X1115365I1025J956D01*
G03X1115381Y535482I293J-272D01*
G02X1115428Y533364I-1041J-1083D01*
G03X1115434Y532807I290J-275D01*
G02X1115407Y530667I-1068J-1057D01*
G37*
G36*
G01X1157297Y530461D02*
G03X1157284Y529899I278J-288D01*
G02X1155236Y529889I-1019J-963D01*
G03X1155218Y530450I-293J271D01*
G02X1155159Y532570I1034J1090D01*
G03Y533119I-291J274D01*
G02X1155222Y535243I1093J1031D01*
G03X1155243Y535804I-274J291D01*
G02X1157293Y535783I1035J946D01*
G03X1157303Y535222I290J-275D01*
G02X1157345Y533119I-1051J-1073D01*
G03Y532570I291J-274D01*
G02X1157297Y530461I-1093J-1030D01*
G37*
G36*
G01X1120485D02*
G03X1120472Y529899I278J-288D01*
G02X1118424Y529889I-1019J-963D01*
G03X1118406Y530450I-293J271D01*
G02X1118347Y532570I1034J1090D01*
G03Y533119I-291J274D01*
G02X1118410Y535243I1093J1031D01*
G03X1118431Y535804I-274J291D01*
G02X1120481Y535783I1035J946D01*
G03X1120491Y535222I290J-275D01*
G02X1120533Y533119I-1051J-1073D01*
G03Y532570I291J-274D01*
G02X1120485Y530461I-1093J-1030D01*
G37*
G36*
G01X1099019Y532137D02*
G02X1097127Y532239I-1002J-981D01*
G03X1097159Y532828I-254J309D01*
G02X1097290Y534909I1001J982D01*
G03X1097264Y535556I-248J314D01*
G02X1099202Y537507I776J1168D01*
G03X1099900Y537568I332J223D01*
G02X1100019Y536215I1281J-569D01*
G03X1099321Y536154I-332J-223D01*
G02X1098910Y535623I-1282J568D01*
G03X1098936Y534976I248J-314D01*
G02X1099051Y532726I-776J-1168D01*
G03X1099019Y532137I254J-309D01*
G37*
G36*
G01X1148317Y514817D02*
G03X1148331Y514234I281J-285D01*
G02X1146331I-1000J-1120D01*
G03X1146345Y514817I-267J298D01*
G02X1148317I986J997D01*
G37*
G36*
G01X1142031Y514778D02*
G03X1142058Y514217I298J-267D01*
G02X1139977Y514177I-1020J-1103D01*
G03X1139981Y514738I-283J283D01*
G02X1142031Y514778I1006J976D01*
G37*
G36*
G01X1135631Y514817D02*
G03X1135645Y514234I281J-285D01*
G02X1133645I-1000J-1120D01*
G03X1133659Y514817I-267J298D01*
G02X1135631I986J997D01*
G37*
G36*
G01X1128938D02*
G03X1128952Y514234I281J-285D01*
G02X1126952I-1000J-1120D01*
G03X1126966Y514817I-267J298D01*
G02X1128938I986J997D01*
G37*
G36*
G01X1111545Y514758D02*
G03X1111561Y514197I293J-272D01*
G02X1109479I-1041J-1083D01*
G03X1109495Y514758I-277J289D01*
G02X1111545I1025J956D01*
G37*
G36*
G01X1105220Y514778D02*
G03X1105247Y514217I298J-267D01*
G02X1103166Y514177I-1020J-1103D01*
G03X1103170Y514738I-283J283D01*
G02X1105220Y514778I1006J976D01*
G37*
G36*
G01X1120536Y514487D02*
G03Y513941I292J-273D01*
G02X1118344I-1096J-1027D01*
G03Y514487I-292J273D01*
G02X1118399Y516597I1096J1027D01*
G03X1118415Y517158I-277J289D01*
G02X1120465I1025J956D01*
G03X1120481Y516597I293J-272D01*
G02X1120536Y514487I-1041J-1083D01*
G37*
G36*
G01X1098802Y513991D02*
G03X1098590Y513435I144J-373D01*
G02X1096841Y514103I-1247J-641D01*
G03X1097053Y514659I-144J373D01*
G02X1098802Y513991I1247J641D01*
G37*
G36*
G01X1157192Y511743D02*
G03X1157173Y511136I251J-312D01*
G02X1155301Y511151I-944J-1036D01*
G03X1155292Y511759I-265J300D01*
G02X1155156Y513941I960J1155D01*
G03Y514487I-292J273D01*
G02X1155211Y516597I1096J1027D01*
G03X1155227Y517158I-277J289D01*
G02X1157277I1025J956D01*
G03X1157293Y516597I293J-272D01*
G02X1157348Y514487I-1041J-1083D01*
G03Y513941I292J-273D01*
G02X1157192Y511743I-1096J-1027D01*
G37*
G36*
G01X1152192Y511616D02*
G03X1152177Y511055I277J-288D01*
G02X1150127I-1025J-957D01*
G03X1150112Y511616I-292J273D01*
G02X1150056Y513727I1040J1084D01*
G03Y514273I-292J273D01*
G02X1150101Y516373I1096J1027D01*
G03X1150111Y516935I-280J286D01*
G02X1152162Y516953I1017J965D01*
G03X1152183Y516392I295J-270D01*
G02X1152248Y514273I-1031J-1092D01*
G03Y513727I292J-273D01*
G02X1152192Y511616I-1096J-1027D01*
G37*
G36*
G01X1115380D02*
G03X1115365Y511055I277J-288D01*
G02X1113315I-1025J-957D01*
G03X1113300Y511616I-292J273D01*
G02X1113244Y513727I1040J1084D01*
G03Y514273I-292J273D01*
G02X1113289Y516373I1096J1027D01*
G03X1113299Y516935I-280J286D01*
G02X1115350Y516953I1017J965D01*
G03X1115371Y516392I295J-270D01*
G02X1115436Y514273I-1031J-1092D01*
G03Y513727I292J-273D01*
G02X1115380Y511616I-1096J-1027D01*
G37*
G36*
G01X1021954Y592663D02*
G03X1021382Y592659I-284J-282D01*
G02X1021421Y594700I-1082J1042D01*
G03X1021992Y594674I298J266D01*
G02X1023923Y594660I958J-1024D01*
G03X1024477I277J288D01*
G02Y592640I973J-1010D01*
G03X1023923I-277J-288D01*
G02X1021954Y592663I-973J1010D01*
G37*
G36*
G01X1012148Y611528D02*
G02Y612956I-1322J714D01*
G03X1012851I352J190D01*
G02Y611528I1322J-714D01*
G03X1012148I-352J-190D01*
G37*
G36*
G01X1022807Y612046D02*
G02X1021800Y610774I393J-1346D01*
G03X1021274Y611175I-399J21D01*
G02X1022296Y612465I-474J1425D01*
G03X1022807Y612046I398J-35D01*
G37*
G36*
G01X1012148Y603900D02*
G02Y605328I-1322J714D01*
G03X1012851I352J190D01*
G02Y603900I1322J-714D01*
G03X1012148I-352J-190D01*
G37*
G36*
G01X1012894Y592928D02*
G02Y594356I-1322J714D01*
G03X1013597I352J190D01*
G02Y592928I1322J-714D01*
G03X1012894I-352J-190D01*
G37*
G36*
G01X1007377Y589955D02*
G03Y589377I277J-289D01*
G02X1005435I-971J-1011D01*
G03Y589955I-277J289D01*
G02X1007377I971J1011D01*
G37*
G36*
G01X1012788Y584675D02*
G03X1012211I-288J-277D01*
G02Y586753I-1085J1039D01*
G03X1012788I288J277D01*
G02X1014956Y586755I1085J-1039D01*
G03X1015517Y586739I289J277D01*
G02Y584689I956J-1025D01*
G03X1014956Y584673I-272J-293D01*
G02X1012788Y584675I-1083J1041D01*
G37*
G36*
G01X1008303Y570999D02*
G03Y570421I277J-289D01*
G02X1006361I-971J-1011D01*
G03Y570999I-277J289D01*
G02X1008303I971J1011D01*
G37*
G36*
G01X1008118Y552100D02*
G03Y551522I277J-289D01*
G02X1006176I-971J-1011D01*
G03Y552100I-277J289D01*
G02X1008118I971J1011D01*
G37*
G36*
G01X1008178Y533126D02*
G03Y532548I277J-289D01*
G02X1006236I-971J-1011D01*
G03Y533126I-277J289D01*
G02X1008178I971J1011D01*
G37*
G36*
G01X1012148Y574028D02*
G02Y575456I-1322J714D01*
G03X1012851I352J190D01*
G02Y574028I1322J-714D01*
G03X1012148I-352J-190D01*
G37*
G36*
G01Y566100D02*
G02Y567528I-1322J714D01*
G03X1012851I352J190D01*
G02Y566100I1322J-714D01*
G03X1012148I-352J-190D01*
G37*
G36*
G01X1012306Y516269D02*
G03X1012857Y516258I281J284D01*
G02X1012817Y514083I1016J-1107D01*
G03X1012266Y514094I-281J-284D01*
G02X1012306Y516269I-1016J1107D01*
G37*
G36*
G01X1012788Y509075D02*
G03X1012211I-288J-277D01*
G02Y511153I-1085J1039D01*
G03X1012788I288J277D01*
G02Y509075I1085J-1039D01*
G37*
G36*
G01X1014525Y546561D02*
G02X1012788Y546875I-652J1353D01*
G03X1012211I-288J-277D01*
G02Y548953I-1085J1039D01*
G03X1012788I288J277D01*
G02X1014525Y549267I1085J-1039D01*
G03X1015098Y549627I173J360D01*
G01Y554014D01*
G03X1014588Y554398I-400J0D01*
G02X1012892Y555058I-415J1444D01*
G03X1012209I-342J-208D01*
G02Y556626I-1281J784D01*
G03X1012892I341J208D01*
G02X1014588Y557286I1281J-784D01*
G03X1015098Y557670I110J384D01*
G01Y561915D01*
X1017685Y564502D01*
X1026015D01*
X1029502Y561015D01*
Y545115D01*
X1029602Y545015D01*
Y516085D01*
X1027115Y513598D01*
X1022885D01*
X1018898Y517585D01*
Y540685D01*
X1015098Y544485D01*
Y546201D01*
G03X1014525Y546561I-400J0D01*
G37*
G36*
G01X934699Y606267D02*
G03X934683Y605706I277J-289D01*
G02X932633I-1025J-956D01*
G03X932617Y606267I-293J272D01*
G02X932570Y608385I1041J1083D01*
G03X932564Y608942I-290J275D01*
G02X932591Y611082I1068J1057D01*
G03X932607Y611643I-277J289D01*
G02X934657I1025J956D01*
G03X934673Y611082I293J-272D01*
G02X934720Y608964I-1041J-1083D01*
G03X934726Y608407I290J-275D01*
G02X934699Y606267I-1068J-1057D01*
G37*
G36*
G01X939777Y606061D02*
G03X939764Y605499I278J-288D01*
G02X937716Y605489I-1019J-963D01*
G03X937698Y606050I-293J271D01*
G02X937639Y608170I1034J1090D01*
G03Y608719I-291J274D01*
G02X937702Y610843I1093J1031D01*
G03X937723Y611404I-274J291D01*
G02X939773Y611383I1035J946D01*
G03X939783Y610822I290J-275D01*
G02X939825Y608719I-1051J-1073D01*
G03Y608170I291J-274D01*
G02X939777Y606061I-1093J-1030D01*
G37*
G36*
G01X954890Y590435D02*
G03X954915Y589853I286J-279D01*
G02X952915Y589816I-979J-1139D01*
G03X952919Y590399I-272J293D01*
G02X954890Y590435I967J1015D01*
G37*
G36*
G01X948229Y590417D02*
G03X948243Y589834I281J-285D01*
G02X946243I-1000J-1120D01*
G03X946257Y590417I-267J298D01*
G02X948229I986J997D01*
G37*
G36*
G01X930797D02*
G03X930811Y589834I281J-285D01*
G02X928811I-1000J-1120D01*
G03X928825Y590417I-267J298D01*
G02X930797I986J997D01*
G37*
G36*
G01X924511Y590378D02*
G03X924538Y589817I298J-267D01*
G02X922457Y589777I-1020J-1103D01*
G03X922461Y590338I-283J283D01*
G02X924511Y590378I1006J976D01*
G37*
G36*
G01X918111Y590417D02*
G03X918125Y589834I281J-285D01*
G02X916125I-1000J-1120D01*
G03X916139Y590417I-267J298D01*
G02X918111I986J997D01*
G37*
G36*
G01X958426Y589947D02*
G03X958416Y589356I264J-300D01*
G02X956530Y589387I-960J-1022D01*
G03X956540Y589978I-264J300D01*
G02X956475Y591957I960J1022D01*
G03X956427Y592547I-292J273D01*
G02X958308Y592700I856J1110D01*
G03X958356Y592110I292J-273D01*
G02X958426Y589947I-856J-1110D01*
G37*
G36*
G01X939672Y587343D02*
G03X939653Y586736I251J-312D01*
G02X937781Y586751I-944J-1036D01*
G03X937772Y587359I-265J300D01*
G02X937636Y589541I960J1155D01*
G03Y590087I-292J273D01*
G02X937691Y592197I1096J1027D01*
G03X937707Y592758I-277J289D01*
G02X939757I1025J956D01*
G03X939773Y592197I293J-272D01*
G02X939828Y590087I-1041J-1083D01*
G03Y589541I292J-273D01*
G02X939672Y587343I-1096J-1027D01*
G37*
G36*
G01X934672Y587216D02*
G03X934657Y586655I277J-288D01*
G02X932607I-1025J-957D01*
G03X932592Y587216I-292J273D01*
G02X932536Y589327I1040J1084D01*
G03Y589873I-292J273D01*
G02X932581Y591973I1096J1027D01*
G03X932591Y592535I-280J286D01*
G02X934642Y592553I1017J965D01*
G03X934663Y591992I295J-270D01*
G02X934728Y589873I-1031J-1092D01*
G03Y589327I292J-273D01*
G02X934672Y587216I-1096J-1027D01*
G37*
G36*
G01X934699Y568467D02*
G03X934683Y567906I277J-289D01*
G02X932633I-1025J-956D01*
G03X932617Y568467I-293J272D01*
G02X932570Y570585I1041J1083D01*
G03X932564Y571142I-290J275D01*
G02X932591Y573282I1068J1057D01*
G03X932607Y573843I-277J289D01*
G02X934657I1025J956D01*
G03X934673Y573282I293J-272D01*
G02X934720Y571164I-1041J-1083D01*
G03X934726Y570607I290J-275D01*
G02X934699Y568467I-1068J-1057D01*
G37*
G36*
G01X939777Y568261D02*
G03X939764Y567699I278J-288D01*
G02X937716Y567689I-1019J-963D01*
G03X937698Y568250I-293J271D01*
G02X937639Y570370I1034J1090D01*
G03Y570919I-291J274D01*
G02X937702Y573043I1093J1031D01*
G03X937723Y573604I-274J291D01*
G02X939773Y573583I1035J946D01*
G03X939783Y573022I290J-275D01*
G02X939825Y570919I-1051J-1073D01*
G03Y570370I291J-274D01*
G02X939777Y568261I-1093J-1030D01*
G37*
G36*
G01X954890Y552635D02*
G03X954915Y552053I286J-279D01*
G02X952915Y552016I-979J-1139D01*
G03X952919Y552599I-272J293D01*
G02X954890Y552635I967J1015D01*
G37*
G36*
G01X948229Y552617D02*
G03X948243Y552034I281J-285D01*
G02X946243I-1000J-1120D01*
G03X946257Y552617I-267J298D01*
G02X948229I986J997D01*
G37*
G36*
G01X930797D02*
G03X930811Y552034I281J-285D01*
G02X928811I-1000J-1120D01*
G03X928825Y552617I-267J298D01*
G02X930797I986J997D01*
G37*
G36*
G01X924511Y552578D02*
G03X924538Y552017I298J-267D01*
G02X922457Y551977I-1020J-1103D01*
G03X922461Y552538I-283J283D01*
G02X924511Y552578I1006J976D01*
G37*
G36*
G01X918111Y552617D02*
G03X918125Y552034I281J-285D01*
G02X916125I-1000J-1120D01*
G03X916139Y552617I-267J298D01*
G02X918111I986J997D01*
G37*
G36*
G01X939672Y549543D02*
G03X939653Y548936I251J-312D01*
G02X937781Y548951I-944J-1036D01*
G03X937772Y549559I-265J300D01*
G02X937636Y551741I960J1155D01*
G03Y552287I-292J273D01*
G02X937691Y554397I1096J1027D01*
G03X937707Y554958I-277J289D01*
G02X939757I1025J956D01*
G03X939773Y554397I293J-272D01*
G02X939828Y552287I-1041J-1083D01*
G03Y551741I292J-273D01*
G02X939672Y549543I-1096J-1027D01*
G37*
G36*
G01X934672Y549416D02*
G03X934657Y548855I277J-288D01*
G02X932607I-1025J-957D01*
G03X932592Y549416I-292J273D01*
G02X932536Y551527I1040J1084D01*
G03Y552073I-292J273D01*
G02X932581Y554173I1096J1027D01*
G03X932591Y554735I-280J286D01*
G02X934642Y554753I1017J965D01*
G03X934663Y554192I295J-270D01*
G02X934728Y552073I-1031J-1092D01*
G03Y551527I292J-273D01*
G02X934672Y549416I-1096J-1027D01*
G37*
G36*
G01X934699Y530667D02*
G03X934683Y530106I277J-289D01*
G02X932633I-1025J-956D01*
G03X932617Y530667I-293J272D01*
G02X932570Y532785I1041J1083D01*
G03X932564Y533342I-290J275D01*
G02X932591Y535482I1068J1057D01*
G03X932607Y536043I-277J289D01*
G02X934657I1025J956D01*
G03X934673Y535482I293J-272D01*
G02X934720Y533364I-1041J-1083D01*
G03X934726Y532807I290J-275D01*
G02X934699Y530667I-1068J-1057D01*
G37*
G36*
G01X939777Y530461D02*
G03X939764Y529899I278J-288D01*
G02X937716Y529889I-1019J-963D01*
G03X937698Y530450I-293J271D01*
G02X937639Y532570I1034J1090D01*
G03Y533119I-291J274D01*
G02X937702Y535243I1093J1031D01*
G03X937723Y535804I-274J291D01*
G02X939773Y535783I1035J946D01*
G03X939783Y535222I290J-275D01*
G02X939825Y533119I-1051J-1073D01*
G03Y532570I291J-274D01*
G02X939777Y530461I-1093J-1030D01*
G37*
G36*
G01X954890Y514835D02*
G03X954915Y514253I286J-279D01*
G02X952915Y514216I-979J-1139D01*
G03X952919Y514799I-272J293D01*
G02X954890Y514835I967J1015D01*
G37*
G36*
G01X948229Y514817D02*
G03X948243Y514234I281J-285D01*
G02X946243I-1000J-1120D01*
G03X946257Y514817I-267J298D01*
G02X948229I986J997D01*
G37*
G36*
G01X930797D02*
G03X930811Y514234I281J-285D01*
G02X928811I-1000J-1120D01*
G03X928825Y514817I-267J298D01*
G02X930797I986J997D01*
G37*
G36*
G01X924511Y514778D02*
G03X924538Y514217I298J-267D01*
G02X922457Y514177I-1020J-1103D01*
G03X922461Y514738I-283J283D01*
G02X924511Y514778I1006J976D01*
G37*
G36*
G01X918111Y514817D02*
G03X918125Y514234I281J-285D01*
G02X916125I-1000J-1120D01*
G03X916139Y514817I-267J298D01*
G02X918111I986J997D01*
G37*
G36*
G01X939672Y511743D02*
G03X939653Y511136I251J-312D01*
G02X937781Y511151I-944J-1036D01*
G03X937772Y511759I-265J300D01*
G02X937636Y513941I960J1155D01*
G03Y514487I-292J273D01*
G02X937691Y516597I1096J1027D01*
G03X937707Y517158I-277J289D01*
G02X939757I1025J956D01*
G03X939773Y516597I293J-272D01*
G02X939828Y514487I-1041J-1083D01*
G03Y513941I292J-273D01*
G02X939672Y511743I-1096J-1027D01*
G37*
G36*
G01X934672Y511616D02*
G03X934657Y511055I277J-288D01*
G02X932607I-1025J-957D01*
G03X932592Y511616I-292J273D01*
G02X932536Y513727I1040J1084D01*
G03Y514273I-292J273D01*
G02X932581Y516373I1096J1027D01*
G03X932591Y516935I-280J286D01*
G02X934642Y516953I1017J965D01*
G03X934663Y516392I295J-270D01*
G02X934728Y514273I-1031J-1092D01*
G03Y513727I292J-273D01*
G02X934672Y511616I-1096J-1027D01*
G37*
G36*
G01X897888Y606267D02*
G03X897872Y605706I277J-289D01*
G02X895822I-1025J-956D01*
G03X895806Y606267I-293J272D01*
G02X895759Y608385I1041J1083D01*
G03X895753Y608942I-290J275D01*
G02X895780Y611082I1068J1057D01*
G03X895796Y611643I-277J289D01*
G02X897846I1025J956D01*
G03X897862Y611082I293J-272D01*
G02X897909Y608964I-1041J-1083D01*
G03X897915Y608407I290J-275D01*
G02X897888Y606267I-1068J-1057D01*
G37*
G36*
G01X861077D02*
G03X861061Y605706I277J-289D01*
G02X859011I-1025J-956D01*
G03X858995Y606267I-293J272D01*
G02X858948Y608385I1041J1083D01*
G03X858942Y608942I-290J275D01*
G02X858969Y611082I1068J1057D01*
G03X858985Y611643I-277J289D01*
G02X861035I1025J956D01*
G03X861051Y611082I293J-272D01*
G02X861098Y608964I-1041J-1083D01*
G03X861104Y608407I290J-275D01*
G02X861077Y606267I-1068J-1057D01*
G37*
G36*
G01X902966Y606061D02*
G03X902953Y605499I278J-288D01*
G02X900905Y605489I-1019J-963D01*
G03X900887Y606050I-293J271D01*
G02X900828Y608170I1034J1090D01*
G03Y608719I-291J274D01*
G02X900891Y610843I1093J1031D01*
G03X900912Y611404I-274J291D01*
G02X902962Y611383I1035J946D01*
G03X902972Y610822I290J-275D01*
G02X903014Y608719I-1051J-1073D01*
G03Y608170I291J-274D01*
G02X902966Y606061I-1093J-1030D01*
G37*
G36*
G01X866155D02*
G03X866142Y605499I278J-288D01*
G02X864094Y605489I-1019J-963D01*
G03X864076Y606050I-293J271D01*
G02X864017Y608170I1034J1090D01*
G03Y608719I-291J274D01*
G02X864080Y610843I1093J1031D01*
G03X864101Y611404I-274J291D01*
G02X866151Y611383I1035J946D01*
G03X866161Y610822I290J-275D01*
G02X866203Y608719I-1051J-1073D01*
G03Y608170I291J-274D01*
G02X866155Y606061I-1093J-1030D01*
G37*
G36*
G01X911418Y590417D02*
G03X911432Y589834I281J-285D01*
G02X909432I-1000J-1120D01*
G03X909446Y590417I-267J298D01*
G02X911418I986J997D01*
G37*
G36*
G01X893986D02*
G03X894000Y589834I281J-285D01*
G02X892000I-1000J-1120D01*
G03X892014Y590417I-267J298D01*
G02X893986I986J997D01*
G37*
G36*
G01X887700Y590378D02*
G03X887727Y589817I298J-267D01*
G02X885646Y589777I-1020J-1103D01*
G03X885650Y590338I-283J283D01*
G02X887700Y590378I1006J976D01*
G37*
G36*
G01X881300Y590417D02*
G03X881314Y589834I281J-285D01*
G02X879314I-1000J-1120D01*
G03X879328Y590417I-267J298D01*
G02X881300I986J997D01*
G37*
G36*
G01X874607D02*
G03X874621Y589834I281J-285D01*
G02X872621I-1000J-1120D01*
G03X872635Y590417I-267J298D01*
G02X874607I986J997D01*
G37*
G36*
G01X857175D02*
G03X857189Y589834I281J-285D01*
G02X855189I-1000J-1120D01*
G03X855203Y590417I-267J298D01*
G02X857175I986J997D01*
G37*
G36*
G01X850889Y590378D02*
G03X850916Y589817I298J-267D01*
G02X848835Y589777I-1020J-1103D01*
G03X848839Y590338I-283J283D01*
G02X850889Y590378I1006J976D01*
G37*
G36*
G01X902861Y587343D02*
G03X902842Y586736I251J-312D01*
G02X900970Y586751I-944J-1036D01*
G03X900961Y587359I-265J300D01*
G02X900825Y589541I960J1155D01*
G03Y590087I-292J273D01*
G02X900880Y592197I1096J1027D01*
G03X900896Y592758I-277J289D01*
G02X902946I1025J956D01*
G03X902962Y592197I293J-272D01*
G02X903017Y590087I-1041J-1083D01*
G03Y589541I292J-273D01*
G02X902861Y587343I-1096J-1027D01*
G37*
G36*
G01X866050D02*
G03X866031Y586736I251J-312D01*
G02X864159Y586751I-944J-1036D01*
G03X864150Y587359I-265J300D01*
G02X864014Y589541I960J1155D01*
G03Y590087I-292J273D01*
G02X864069Y592197I1096J1027D01*
G03X864085Y592758I-277J289D01*
G02X866135I1025J956D01*
G03X866151Y592197I293J-272D01*
G02X866206Y590087I-1041J-1083D01*
G03Y589541I292J-273D01*
G02X866050Y587343I-1096J-1027D01*
G37*
G36*
G01X897861Y587216D02*
G03X897846Y586655I277J-288D01*
G02X895796I-1025J-957D01*
G03X895781Y587216I-292J273D01*
G02X895725Y589327I1040J1084D01*
G03Y589873I-292J273D01*
G02X895770Y591973I1096J1027D01*
G03X895780Y592535I-280J286D01*
G02X897831Y592553I1017J965D01*
G03X897852Y591992I295J-270D01*
G02X897917Y589873I-1031J-1092D01*
G03Y589327I292J-273D01*
G02X897861Y587216I-1096J-1027D01*
G37*
G36*
G01X861050D02*
G03X861035Y586655I277J-288D01*
G02X858985I-1025J-957D01*
G03X858970Y587216I-292J273D01*
G02X858914Y589327I1040J1084D01*
G03Y589873I-292J273D01*
G02X858959Y591973I1096J1027D01*
G03X858969Y592535I-280J286D01*
G02X861020Y592553I1017J965D01*
G03X861041Y591992I295J-270D01*
G02X861106Y589873I-1031J-1092D01*
G03Y589327I292J-273D01*
G02X861050Y587216I-1096J-1027D01*
G37*
G36*
G01X897888Y568467D02*
G03X897872Y567906I277J-289D01*
G02X895822I-1025J-956D01*
G03X895806Y568467I-293J272D01*
G02X895759Y570585I1041J1083D01*
G03X895753Y571142I-290J275D01*
G02X895780Y573282I1068J1057D01*
G03X895796Y573843I-277J289D01*
G02X897846I1025J956D01*
G03X897862Y573282I293J-272D01*
G02X897909Y571164I-1041J-1083D01*
G03X897915Y570607I290J-275D01*
G02X897888Y568467I-1068J-1057D01*
G37*
G36*
G01X861077D02*
G03X861061Y567906I277J-289D01*
G02X859011I-1025J-956D01*
G03X858995Y568467I-293J272D01*
G02X858948Y570585I1041J1083D01*
G03X858942Y571142I-290J275D01*
G02X858969Y573282I1068J1057D01*
G03X858985Y573843I-277J289D01*
G02X861035I1025J956D01*
G03X861051Y573282I293J-272D01*
G02X861098Y571164I-1041J-1083D01*
G03X861104Y570607I290J-275D01*
G02X861077Y568467I-1068J-1057D01*
G37*
G36*
G01X902966Y568261D02*
G03X902953Y567699I278J-288D01*
G02X900905Y567689I-1019J-963D01*
G03X900887Y568250I-293J271D01*
G02X900828Y570370I1034J1090D01*
G03Y570919I-291J274D01*
G02X900891Y573043I1093J1031D01*
G03X900912Y573604I-274J291D01*
G02X902962Y573583I1035J946D01*
G03X902972Y573022I290J-275D01*
G02X903014Y570919I-1051J-1073D01*
G03Y570370I291J-274D01*
G02X902966Y568261I-1093J-1030D01*
G37*
G36*
G01X866155D02*
G03X866142Y567699I278J-288D01*
G02X864094Y567689I-1019J-963D01*
G03X864076Y568250I-293J271D01*
G02X864017Y570370I1034J1090D01*
G03Y570919I-291J274D01*
G02X864080Y573043I1093J1031D01*
G03X864101Y573604I-274J291D01*
G02X866151Y573583I1035J946D01*
G03X866161Y573022I290J-275D01*
G02X866203Y570919I-1051J-1073D01*
G03Y570370I291J-274D01*
G02X866155Y568261I-1093J-1030D01*
G37*
G36*
G01X911418Y552617D02*
G03X911432Y552034I281J-285D01*
G02X909432I-1000J-1120D01*
G03X909446Y552617I-267J298D01*
G02X911418I986J997D01*
G37*
G36*
G01X893986D02*
G03X894000Y552034I281J-285D01*
G02X892000I-1000J-1120D01*
G03X892014Y552617I-267J298D01*
G02X893986I986J997D01*
G37*
G36*
G01X887700Y552578D02*
G03X887727Y552017I298J-267D01*
G02X885646Y551977I-1020J-1103D01*
G03X885650Y552538I-283J283D01*
G02X887700Y552578I1006J976D01*
G37*
G36*
G01X881300Y552617D02*
G03X881314Y552034I281J-285D01*
G02X879314I-1000J-1120D01*
G03X879328Y552617I-267J298D01*
G02X881300I986J997D01*
G37*
G36*
G01X874607D02*
G03X874621Y552034I281J-285D01*
G02X872621I-1000J-1120D01*
G03X872635Y552617I-267J298D01*
G02X874607I986J997D01*
G37*
G36*
G01X857175D02*
G03X857189Y552034I281J-285D01*
G02X855189I-1000J-1120D01*
G03X855203Y552617I-267J298D01*
G02X857175I986J997D01*
G37*
G36*
G01X850889Y552578D02*
G03X850916Y552017I298J-267D01*
G02X848835Y551977I-1020J-1103D01*
G03X848839Y552538I-283J283D01*
G02X850889Y552578I1006J976D01*
G37*
G36*
G01X902861Y549543D02*
G03X902842Y548936I251J-312D01*
G02X900970Y548951I-944J-1036D01*
G03X900961Y549559I-265J300D01*
G02X900825Y551741I960J1155D01*
G03Y552287I-292J273D01*
G02X900880Y554397I1096J1027D01*
G03X900896Y554958I-277J289D01*
G02X902946I1025J956D01*
G03X902962Y554397I293J-272D01*
G02X903017Y552287I-1041J-1083D01*
G03Y551741I292J-273D01*
G02X902861Y549543I-1096J-1027D01*
G37*
G36*
G01X866050D02*
G03X866031Y548936I251J-312D01*
G02X864159Y548951I-944J-1036D01*
G03X864150Y549559I-265J300D01*
G02X864014Y551741I960J1155D01*
G03Y552287I-292J273D01*
G02X864069Y554397I1096J1027D01*
G03X864085Y554958I-277J289D01*
G02X866135I1025J956D01*
G03X866151Y554397I293J-272D01*
G02X866206Y552287I-1041J-1083D01*
G03Y551741I292J-273D01*
G02X866050Y549543I-1096J-1027D01*
G37*
G36*
G01X897861Y549416D02*
G03X897846Y548855I277J-288D01*
G02X895796I-1025J-957D01*
G03X895781Y549416I-292J273D01*
G02X895725Y551527I1040J1084D01*
G03Y552073I-292J273D01*
G02X895770Y554173I1096J1027D01*
G03X895780Y554735I-280J286D01*
G02X897831Y554753I1017J965D01*
G03X897852Y554192I295J-270D01*
G02X897917Y552073I-1031J-1092D01*
G03Y551527I292J-273D01*
G02X897861Y549416I-1096J-1027D01*
G37*
G36*
G01X861050D02*
G03X861035Y548855I277J-288D01*
G02X858985I-1025J-957D01*
G03X858970Y549416I-292J273D01*
G02X858914Y551527I1040J1084D01*
G03Y552073I-292J273D01*
G02X858959Y554173I1096J1027D01*
G03X858969Y554735I-280J286D01*
G02X861020Y554753I1017J965D01*
G03X861041Y554192I295J-270D01*
G02X861106Y552073I-1031J-1092D01*
G03Y551527I292J-273D01*
G02X861050Y549416I-1096J-1027D01*
G37*
G36*
G01X897909Y533364D02*
G03X897915Y532807I290J-275D01*
G02X895759Y532785I-1067J-1057D01*
G03X895753Y533342I-290J275D01*
G02X895780Y535482I1068J1057D01*
G03X895796Y536043I-277J289D01*
G02X897846I1025J956D01*
G03X897862Y535482I293J-272D01*
G02X897909Y533364I-1041J-1083D01*
G37*
G36*
G01X861077Y530667D02*
G03X861061Y530106I277J-289D01*
G02X859011I-1025J-956D01*
G03X858995Y530667I-293J272D01*
G02X858948Y532785I1041J1083D01*
G03X858942Y533342I-290J275D01*
G02X858969Y535482I1068J1057D01*
G03X858985Y536043I-277J289D01*
G02X861035I1025J956D01*
G03X861051Y535482I293J-272D01*
G02X861098Y533364I-1041J-1083D01*
G03X861104Y532807I290J-275D01*
G02X861077Y530667I-1068J-1057D01*
G37*
G36*
G01X902966Y530461D02*
G03X902953Y529899I278J-288D01*
G02X900905Y529889I-1019J-963D01*
G03X900887Y530450I-293J271D01*
G02X900828Y532570I1034J1090D01*
G03Y533119I-291J274D01*
G02X900891Y535243I1093J1031D01*
G03X900912Y535804I-274J291D01*
G02X902962Y535783I1035J946D01*
G03X902972Y535222I290J-275D01*
G02X903014Y533119I-1051J-1073D01*
G03Y532570I291J-274D01*
G02X902966Y530461I-1093J-1030D01*
G37*
G36*
G01X866155D02*
G03X866142Y529899I278J-288D01*
G02X864094Y529889I-1019J-963D01*
G03X864076Y530450I-293J271D01*
G02X864017Y532570I1034J1090D01*
G03Y533119I-291J274D01*
G02X864080Y535243I1093J1031D01*
G03X864101Y535804I-274J291D01*
G02X866151Y535783I1035J946D01*
G03X866161Y535222I290J-275D01*
G02X866203Y533119I-1051J-1073D01*
G03Y532570I291J-274D01*
G02X866155Y530461I-1093J-1030D01*
G37*
G36*
G01X911418Y514817D02*
G03X911432Y514234I281J-285D01*
G02X909432I-1000J-1120D01*
G03X909446Y514817I-267J298D01*
G02X911418I986J997D01*
G37*
G36*
G01X893986D02*
G03X894000Y514234I281J-285D01*
G02X892000I-1000J-1120D01*
G03X892014Y514817I-267J298D01*
G02X893986I986J997D01*
G37*
G36*
G01X887700Y514778D02*
G03X887727Y514217I298J-267D01*
G02X885646Y514177I-1020J-1103D01*
G03X885650Y514738I-283J283D01*
G02X887700Y514778I1006J976D01*
G37*
G36*
G01X881300Y514817D02*
G03X881314Y514234I281J-285D01*
G02X879314I-1000J-1120D01*
G03X879328Y514817I-267J298D01*
G02X881300I986J997D01*
G37*
G36*
G01X874607D02*
G03X874621Y514234I281J-285D01*
G02X872621I-1000J-1120D01*
G03X872635Y514817I-267J298D01*
G02X874607I986J997D01*
G37*
G36*
G01X857175D02*
G03X857189Y514234I281J-285D01*
G02X855189I-1000J-1120D01*
G03X855203Y514817I-267J298D01*
G02X857175I986J997D01*
G37*
G36*
G01X850889Y514778D02*
G03X850916Y514217I298J-267D01*
G02X848835Y514177I-1020J-1103D01*
G03X848839Y514738I-283J283D01*
G02X850889Y514778I1006J976D01*
G37*
G36*
G01X902861Y511743D02*
G03X902842Y511136I251J-312D01*
G02X900970Y511151I-944J-1036D01*
G03X900961Y511759I-265J300D01*
G02X900825Y513941I960J1155D01*
G03Y514487I-292J273D01*
G02X900880Y516597I1096J1027D01*
G03X900896Y517158I-277J289D01*
G02X902946I1025J956D01*
G03X902962Y516597I293J-272D01*
G02X903017Y514487I-1041J-1083D01*
G03Y513941I292J-273D01*
G02X902861Y511743I-1096J-1027D01*
G37*
G36*
G01X866050D02*
G03X866031Y511136I251J-312D01*
G02X864159Y511151I-944J-1036D01*
G03X864150Y511759I-265J300D01*
G02X864014Y513941I960J1155D01*
G03Y514487I-292J273D01*
G02X864069Y516597I1096J1027D01*
G03X864085Y517158I-277J289D01*
G02X866135I1025J956D01*
G03X866151Y516597I293J-272D01*
G02X866206Y514487I-1041J-1083D01*
G03Y513941I292J-273D01*
G02X866050Y511743I-1096J-1027D01*
G37*
G36*
G01X897861Y511616D02*
G03X897846Y511055I277J-288D01*
G02X895796I-1025J-957D01*
G03X895781Y511616I-292J273D01*
G02X895725Y513727I1040J1084D01*
G03Y514273I-292J273D01*
G02X895770Y516373I1096J1027D01*
G03X895780Y516935I-280J286D01*
G02X897831Y516953I1017J965D01*
G03X897852Y516392I295J-270D01*
G02X897917Y514273I-1031J-1092D01*
G03Y513727I292J-273D01*
G02X897861Y511616I-1096J-1027D01*
G37*
G36*
G01X861050D02*
G03X861035Y511055I277J-288D01*
G02X858985I-1025J-957D01*
G03X858970Y511616I-292J273D01*
G02X858914Y513727I1040J1084D01*
G03Y514273I-292J273D01*
G02X858959Y516373I1096J1027D01*
G03X858969Y516935I-280J286D01*
G02X861020Y516953I1017J965D01*
G03X861041Y516392I295J-270D01*
G02X861106Y514273I-1031J-1092D01*
G03Y513727I292J-273D01*
G02X861050Y511616I-1096J-1027D01*
G37*
G36*
G01X824266Y606267D02*
G03X824250Y605706I277J-289D01*
G02X822200I-1025J-956D01*
G03X822184Y606267I-293J272D01*
G02X822137Y608385I1041J1083D01*
G03X822131Y608942I-290J275D01*
G02X822158Y611082I1068J1057D01*
G03X822174Y611643I-277J289D01*
G02X824224I1025J956D01*
G03X824240Y611082I293J-272D01*
G02X824287Y608964I-1041J-1083D01*
G03X824293Y608407I290J-275D01*
G02X824266Y606267I-1068J-1057D01*
G37*
G36*
G01X829344Y606061D02*
G03X829331Y605499I278J-288D01*
G02X827283Y605489I-1019J-963D01*
G03X827265Y606050I-293J271D01*
G02X827206Y608170I1034J1090D01*
G03Y608719I-291J274D01*
G02X827269Y610843I1093J1031D01*
G03X827290Y611404I-274J291D01*
G02X829340Y611383I1035J946D01*
G03X829350Y610822I290J-275D01*
G02X829392Y608719I-1051J-1073D01*
G03Y608170I291J-274D01*
G02X829344Y606061I-1093J-1030D01*
G37*
G36*
G01X792533D02*
G03X792520Y605499I278J-288D01*
G02X790472Y605489I-1019J-963D01*
G03X790454Y606050I-293J271D01*
G02X790395Y608170I1034J1090D01*
G03Y608719I-291J274D01*
G02X790458Y610843I1093J1031D01*
G03X790479Y611404I-274J291D01*
G02X792529Y611383I1035J946D01*
G03X792539Y610822I290J-275D01*
G02X792581Y608719I-1051J-1073D01*
G03Y608170I291J-274D01*
G02X792533Y606061I-1093J-1030D01*
G37*
G36*
G01X844489Y590417D02*
G03X844503Y589834I281J-285D01*
G02X842503I-1000J-1120D01*
G03X842517Y590417I-267J298D01*
G02X844489I986J997D01*
G37*
G36*
G01X837796D02*
G03X837810Y589834I281J-285D01*
G02X835810I-1000J-1120D01*
G03X835824Y590417I-267J298D01*
G02X837796I986J997D01*
G37*
G36*
G01X820384Y590387D02*
G03X820399Y589816I287J-278D01*
G02X818357I-1021J-1102D01*
G03X818372Y590387I-272J293D01*
G02X820384I1006J977D01*
G37*
G36*
G01X814078Y590378D02*
G03X814105Y589817I298J-267D01*
G02X812024Y589777I-1020J-1103D01*
G03X812028Y590338I-283J283D01*
G02X814078Y590378I1006J976D01*
G37*
G36*
G01X807678Y590417D02*
G03X807692Y589834I281J-285D01*
G02X805692I-1000J-1120D01*
G03X805706Y590417I-267J298D01*
G02X807678I986J997D01*
G37*
G36*
G01X800985D02*
G03X800999Y589834I281J-285D01*
G02X798999I-1000J-1120D01*
G03X799013Y590417I-267J298D01*
G02X800985I986J997D01*
G37*
G36*
G01X829239Y587343D02*
G03X829220Y586736I251J-312D01*
G02X827348Y586751I-944J-1036D01*
G03X827339Y587359I-265J300D01*
G02X827203Y589541I960J1155D01*
G03Y590087I-292J273D01*
G02X827258Y592197I1096J1027D01*
G03X827274Y592758I-277J289D01*
G02X829324I1025J956D01*
G03X829340Y592197I293J-272D01*
G02X829395Y590087I-1041J-1083D01*
G03Y589541I292J-273D01*
G02X829239Y587343I-1096J-1027D01*
G37*
G36*
G01X792428D02*
G03X792409Y586736I251J-312D01*
G02X790537Y586751I-944J-1036D01*
G03X790528Y587359I-265J300D01*
G02X790392Y589541I960J1155D01*
G03Y590087I-292J273D01*
G02X790447Y592197I1096J1027D01*
G03X790463Y592758I-277J289D01*
G02X792513I1025J956D01*
G03X792529Y592197I293J-272D01*
G02X792584Y590087I-1041J-1083D01*
G03Y589541I292J-273D01*
G02X792428Y587343I-1096J-1027D01*
G37*
G36*
G01X824239Y587216D02*
G03X824224Y586655I277J-288D01*
G02X822174I-1025J-957D01*
G03X822159Y587216I-292J273D01*
G02X822103Y589327I1040J1084D01*
G03Y589873I-292J273D01*
G02X822148Y591973I1096J1027D01*
G03X822158Y592535I-280J286D01*
G02X824209Y592553I1017J965D01*
G03X824230Y591992I295J-270D01*
G02X824295Y589873I-1031J-1092D01*
G03Y589327I292J-273D01*
G02X824239Y587216I-1096J-1027D01*
G37*
G36*
G01X824266Y568467D02*
G03X824250Y567906I277J-289D01*
G02X822200I-1025J-956D01*
G03X822184Y568467I-293J272D01*
G02X822137Y570585I1041J1083D01*
G03X822131Y571142I-290J275D01*
G02X822158Y573282I1068J1057D01*
G03X822174Y573843I-277J289D01*
G02X824224I1025J956D01*
G03X824240Y573282I293J-272D01*
G02X824287Y571164I-1041J-1083D01*
G03X824293Y570607I290J-275D01*
G02X824266Y568467I-1068J-1057D01*
G37*
G36*
G01X829344Y568261D02*
G03X829331Y567699I278J-288D01*
G02X827283Y567689I-1019J-963D01*
G03X827265Y568250I-293J271D01*
G02X827206Y570370I1034J1090D01*
G03Y570919I-291J274D01*
G02X827269Y573043I1093J1031D01*
G03X827290Y573604I-274J291D01*
G02X829340Y573583I1035J946D01*
G03X829350Y573022I290J-275D01*
G02X829392Y570919I-1051J-1073D01*
G03Y570370I291J-274D01*
G02X829344Y568261I-1093J-1030D01*
G37*
G36*
G01X792533D02*
G03X792520Y567699I278J-288D01*
G02X790472Y567689I-1019J-963D01*
G03X790454Y568250I-293J271D01*
G02X790395Y570370I1034J1090D01*
G03Y570919I-291J274D01*
G02X790458Y573043I1093J1031D01*
G03X790479Y573604I-274J291D01*
G02X792529Y573583I1035J946D01*
G03X792539Y573022I290J-275D01*
G02X792581Y570919I-1051J-1073D01*
G03Y570370I291J-274D01*
G02X792533Y568261I-1093J-1030D01*
G37*
G36*
G01X844489Y552617D02*
G03X844503Y552034I281J-285D01*
G02X842503I-1000J-1120D01*
G03X842517Y552617I-267J298D01*
G02X844489I986J997D01*
G37*
G36*
G01X837796D02*
G03X837810Y552034I281J-285D01*
G02X835810I-1000J-1120D01*
G03X835824Y552617I-267J298D01*
G02X837796I986J997D01*
G37*
G36*
G01X820384Y552587D02*
G03X820399Y552016I287J-278D01*
G02X818357I-1021J-1102D01*
G03X818372Y552587I-272J293D01*
G02X820384I1006J977D01*
G37*
G36*
G01X814078Y552578D02*
G03X814105Y552017I298J-267D01*
G02X812024Y551977I-1020J-1103D01*
G03X812028Y552538I-283J283D01*
G02X814078Y552578I1006J976D01*
G37*
G36*
G01X807678Y552617D02*
G03X807692Y552034I281J-285D01*
G02X805692I-1000J-1120D01*
G03X805706Y552617I-267J298D01*
G02X807678I986J997D01*
G37*
G36*
G01X800985D02*
G03X800999Y552034I281J-285D01*
G02X798999I-1000J-1120D01*
G03X799013Y552617I-267J298D01*
G02X800985I986J997D01*
G37*
G36*
G01X829239Y549543D02*
G03X829220Y548936I251J-312D01*
G02X827348Y548951I-944J-1036D01*
G03X827339Y549559I-265J300D01*
G02X827203Y551741I960J1155D01*
G03Y552287I-292J273D01*
G02X827258Y554397I1096J1027D01*
G03X827274Y554958I-277J289D01*
G02X829324I1025J956D01*
G03X829340Y554397I293J-272D01*
G02X829395Y552287I-1041J-1083D01*
G03Y551741I292J-273D01*
G02X829239Y549543I-1096J-1027D01*
G37*
G36*
G01X792428D02*
G03X792409Y548936I251J-312D01*
G02X790537Y548951I-944J-1036D01*
G03X790528Y549559I-265J300D01*
G02X790392Y551741I960J1155D01*
G03Y552287I-292J273D01*
G02X790447Y554397I1096J1027D01*
G03X790463Y554958I-277J289D01*
G02X792513I1025J956D01*
G03X792529Y554397I293J-272D01*
G02X792584Y552287I-1041J-1083D01*
G03Y551741I292J-273D01*
G02X792428Y549543I-1096J-1027D01*
G37*
G36*
G01X824239Y549416D02*
G03X824224Y548855I277J-288D01*
G02X822174I-1025J-957D01*
G03X822159Y549416I-292J273D01*
G02X822103Y551527I1040J1084D01*
G03Y552073I-292J273D01*
G02X822148Y554173I1096J1027D01*
G03X822158Y554735I-280J286D01*
G02X824209Y554753I1017J965D01*
G03X824230Y554192I295J-270D01*
G02X824295Y552073I-1031J-1092D01*
G03Y551527I292J-273D01*
G02X824239Y549416I-1096J-1027D01*
G37*
G36*
G01X824266Y530667D02*
G03X824250Y530106I277J-289D01*
G02X822200I-1025J-956D01*
G03X822184Y530667I-293J272D01*
G02X822137Y532785I1041J1083D01*
G03X822131Y533342I-290J275D01*
G02X822158Y535482I1068J1057D01*
G03X822174Y536043I-277J289D01*
G02X824224I1025J956D01*
G03X824240Y535482I293J-272D01*
G02X824287Y533364I-1041J-1083D01*
G03X824293Y532807I290J-275D01*
G02X824266Y530667I-1068J-1057D01*
G37*
G36*
G01X829344Y530461D02*
G03X829331Y529899I278J-288D01*
G02X827283Y529889I-1019J-963D01*
G03X827265Y530450I-293J271D01*
G02X827206Y532570I1034J1090D01*
G03Y533119I-291J274D01*
G02X827269Y535243I1093J1031D01*
G03X827290Y535804I-274J291D01*
G02X829340Y535783I1035J946D01*
G03X829350Y535222I290J-275D01*
G02X829392Y533119I-1051J-1073D01*
G03Y532570I291J-274D01*
G02X829344Y530461I-1093J-1030D01*
G37*
G36*
G01X792533D02*
G03X792520Y529899I278J-288D01*
G02X790472Y529889I-1019J-963D01*
G03X790454Y530450I-293J271D01*
G02X790395Y532570I1034J1090D01*
G03Y533119I-291J274D01*
G02X790458Y535243I1093J1031D01*
G03X790479Y535804I-274J291D01*
G02X792529Y535783I1035J946D01*
G03X792539Y535222I290J-275D01*
G02X792581Y533119I-1051J-1073D01*
G03Y532570I291J-274D01*
G02X792533Y530461I-1093J-1030D01*
G37*
G36*
G01X844489Y514817D02*
G03X844503Y514234I281J-285D01*
G02X842503I-1000J-1120D01*
G03X842517Y514817I-267J298D01*
G02X844489I986J997D01*
G37*
G36*
G01X837796D02*
G03X837810Y514234I281J-285D01*
G02X835810I-1000J-1120D01*
G03X835824Y514817I-267J298D01*
G02X837796I986J997D01*
G37*
G36*
G01X820384Y514787D02*
G03X820399Y514216I287J-278D01*
G02X818357I-1021J-1102D01*
G03X818372Y514787I-272J293D01*
G02X820384I1006J977D01*
G37*
G36*
G01X814078Y514778D02*
G03X814105Y514217I298J-267D01*
G02X812024Y514177I-1020J-1103D01*
G03X812028Y514738I-283J283D01*
G02X814078Y514778I1006J976D01*
G37*
G36*
G01X807678Y514817D02*
G03X807692Y514234I281J-285D01*
G02X805692I-1000J-1120D01*
G03X805706Y514817I-267J298D01*
G02X807678I986J997D01*
G37*
G36*
G01X800985D02*
G03X800999Y514234I281J-285D01*
G02X798999I-1000J-1120D01*
G03X799013Y514817I-267J298D01*
G02X800985I986J997D01*
G37*
G36*
G01X829395Y514487D02*
G03Y513941I292J-273D01*
G02X827203I-1096J-1027D01*
G03Y514487I-292J273D01*
G02X827258Y516597I1096J1027D01*
G03X827274Y517158I-277J289D01*
G02X829324I1025J956D01*
G03X829340Y516597I293J-272D01*
G02X829395Y514487I-1041J-1083D01*
G37*
G36*
G01X792428Y511743D02*
G03X792409Y511136I251J-312D01*
G02X790537Y511151I-944J-1036D01*
G03X790528Y511759I-265J300D01*
G02X790392Y513941I960J1155D01*
G03Y514487I-292J273D01*
G02X790447Y516597I1096J1027D01*
G03X790463Y517158I-277J289D01*
G02X792513I1025J956D01*
G03X792529Y516597I293J-272D01*
G02X792584Y514487I-1041J-1083D01*
G03Y513941I292J-273D01*
G02X792428Y511743I-1096J-1027D01*
G37*
G36*
G01X824239Y511616D02*
G03X824224Y511055I277J-288D01*
G02X822174I-1025J-957D01*
G03X822159Y511616I-292J273D01*
G02X822103Y513727I1040J1084D01*
G03Y514273I-292J273D01*
G02X822148Y516373I1096J1027D01*
G03X822158Y516935I-280J286D01*
G02X824209Y516953I1017J965D01*
G03X824230Y516392I295J-270D01*
G02X824295Y514273I-1031J-1092D01*
G03Y513727I292J-273D01*
G02X824239Y511616I-1096J-1027D01*
G37*
G36*
G01X787455Y606267D02*
G03X787439Y605706I277J-289D01*
G02X785389I-1025J-956D01*
G03X785373Y606267I-293J272D01*
G02X785326Y608385I1041J1083D01*
G03X785320Y608942I-290J275D01*
G02X785347Y611082I1068J1057D01*
G03X785363Y611643I-277J289D01*
G02X787413I1025J956D01*
G03X787429Y611082I293J-272D01*
G02X787476Y608964I-1041J-1083D01*
G03X787482Y608407I290J-275D01*
G02X787455Y606267I-1068J-1057D01*
G37*
G36*
G01X754907Y592660D02*
G03X754330Y592649I-283J-282D01*
G02X754293Y594590I-1030J951D01*
G03X754870Y594601I283J282D01*
G02X754907Y592660I1030J-951D01*
G37*
G36*
G01X765634Y591716D02*
G03X765606Y592320I-276J290D01*
G02X767518Y592364I929J1180D01*
G03Y591760I262J-302D01*
G02X765634Y591716I-918J-1060D01*
G37*
G36*
G01X783553Y590417D02*
G03X783567Y589834I281J-285D01*
G02X781567I-1000J-1120D01*
G03X781581Y590417I-267J298D01*
G02X783553I986J997D01*
G37*
G36*
G01X777267Y590378D02*
G03X777294Y589817I298J-267D01*
G02X775213Y589777I-1020J-1103D01*
G03X775217Y590338I-283J283D01*
G02X777267Y590378I1006J976D01*
G37*
G36*
G01X785363Y586655D02*
G03X785348Y587216I-292J273D01*
G02X785292Y589327I1040J1084D01*
G03Y589873I-292J273D01*
G02X785337Y591973I1096J1027D01*
G03X785347Y592535I-280J286D01*
G02X787398Y592553I1017J965D01*
G03X787419Y591992I295J-270D01*
G02X787484Y589873I-1031J-1092D01*
G03Y589327I292J-273D01*
G02X787428Y587216I-1096J-1027D01*
G03X787413Y586655I277J-288D01*
G02X785363I-1025J-957D01*
G37*
G36*
G01X787455Y568467D02*
G03X787439Y567906I277J-289D01*
G02X785389I-1025J-956D01*
G03X785373Y568467I-293J272D01*
G02X785326Y570585I1041J1083D01*
G03X785320Y571142I-290J275D01*
G02X785347Y573282I1068J1057D01*
G03X785363Y573843I-277J289D01*
G02X787413I1025J956D01*
G03X787429Y573282I293J-272D01*
G02X787476Y571164I-1041J-1083D01*
G03X787482Y570607I290J-275D01*
G02X787455Y568467I-1068J-1057D01*
G37*
G36*
G01X783553Y552617D02*
G03X783567Y552034I281J-285D01*
G02X781567I-1000J-1120D01*
G03X781581Y552617I-267J298D01*
G02X783553I986J997D01*
G37*
G36*
G01X777267Y552578D02*
G03X777294Y552017I298J-267D01*
G02X775213Y551977I-1020J-1103D01*
G03X775217Y552538I-283J283D01*
G02X777267Y552578I1006J976D01*
G37*
G36*
G01X785363Y548855D02*
G03X785348Y549416I-292J273D01*
G02X785292Y551527I1040J1084D01*
G03Y552073I-292J273D01*
G02X785337Y554173I1096J1027D01*
G03X785347Y554735I-280J286D01*
G02X787398Y554753I1017J965D01*
G03X787419Y554192I295J-270D01*
G02X787484Y552073I-1031J-1092D01*
G03Y551527I292J-273D01*
G02X787428Y549416I-1096J-1027D01*
G03X787413Y548855I277J-288D01*
G02X785363I-1025J-957D01*
G37*
G36*
G01X787455Y530667D02*
G03X787439Y530106I277J-289D01*
G02X785389I-1025J-956D01*
G03X785373Y530667I-293J272D01*
G02X785326Y532785I1041J1083D01*
G03X785320Y533342I-290J275D01*
G02X785347Y535482I1068J1057D01*
G03X785363Y536043I-277J289D01*
G02X787413I1025J956D01*
G03X787429Y535482I293J-272D01*
G02X787476Y533364I-1041J-1083D01*
G03X787482Y532807I290J-275D01*
G02X787455Y530667I-1068J-1057D01*
G37*
G36*
G01X764935Y585425D02*
G02X763900Y586633I-1485J-225D01*
G03X764415Y587075I120J382D01*
G02X765450Y585867I1485J225D01*
G03X764935Y585425I-120J-382D01*
G37*
G36*
G01X783553Y514817D02*
G03X783567Y514234I281J-285D01*
G02X781567I-1000J-1120D01*
G03X781581Y514817I-267J298D01*
G02X783553I986J997D01*
G37*
G36*
G01X777267Y514778D02*
G03X777294Y514217I298J-267D01*
G02X775213Y514177I-1020J-1103D01*
G03X775217Y514738I-283J283D01*
G02X777267Y514778I1006J976D01*
G37*
G36*
G01X787428Y511616D02*
G03X787413Y511055I277J-288D01*
G02X785363I-1025J-957D01*
G03X785348Y511616I-292J273D01*
G02X785292Y513727I1040J1084D01*
G03Y514273I-292J273D01*
G02X785337Y516373I1096J1027D01*
G03X785347Y516935I-280J286D01*
G02X787398Y516953I1017J965D01*
G03X787419Y516392I295J-270D01*
G02X787484Y514273I-1031J-1092D01*
G03Y513727I292J-273D01*
G02X787428Y511616I-1096J-1027D01*
G37*
G36*
G01X722273Y608773D02*
G02Y610327I-1167J777D01*
G03X722939I333J222D01*
G02X724780Y610779I1167J-777D01*
G03X725369Y611075I193J351D01*
G02X727949Y611902I1488J-204D01*
G03X728530Y611900I291J274D01*
G02X730762Y611834I1086J-1037D01*
G03X731385Y611850I305J259D01*
G02X731471Y610048I1115J-850D01*
G03X730849Y610005I-294J-271D01*
G02X728524Y609832I-1233J858D01*
G03X727943Y609834I-291J-274D01*
G02X726086Y609582I-1086J1037D01*
G03X725487Y609308I-205J-343D01*
G02X722939Y608773I-1381J242D01*
G03X722273I-333J-222D01*
G37*
G36*
G01X724326Y599288D02*
G02X723867Y597660I847J-1117D01*
G03X723253Y597833I-372J-146D01*
G02X723712Y599461I-847J1117D01*
G03X724326Y599288I372J146D01*
G37*
G36*
G01X709195Y588479D02*
G03X708884Y588024I84J-391D01*
G02X706116I-1384J-224D01*
G03X705805Y588479I-395J64D01*
G02X707189Y590733I295J1371D01*
G03X707811I311J252D01*
G02X709195Y588479I1089J-883D01*
G37*
G36*
G01X724322Y580004D02*
G03X723696Y579991I-308J-255D01*
G02Y581809I-1196J909D01*
G03X724322Y581796I318J242D01*
G02Y580004I1078J-896D01*
G37*
G36*
G01X776892Y377686D02*
G03X776286Y377668I-295J-270D01*
G02X774019Y379637I-1164J949D01*
G03X774032Y380166I-293J272D01*
G02X774050Y382120I1150J966D01*
G03Y382646I-302J263D01*
G02X776314I1132J987D01*
G03Y382120I302J-263D01*
G02X776284Y380112I-1132J-987D01*
G03X776271Y379583I293J-272D01*
G02X776368Y379453I-1154J-962D01*
G03X776706Y379463I166J112D01*
G02X776892Y377686I1294J-763D01*
G37*
G36*
G01X778810Y371129D02*
G03X778193Y371122I-306J-258D01*
G02X778172Y372904I-1093J878D01*
G03X778789Y372911I306J258D01*
G02X778810Y371129I1093J-878D01*
G37*
G36*
G01X771160Y372542D02*
G03X770929Y373080I-366J161D01*
G02X772683Y373834I472J1320D01*
G03X772914Y373296I366J-161D01*
G02X771160Y372542I-472J-1320D01*
G37*
G36*
G01X767955Y352504D02*
G03X768121Y351953I349J-195D01*
G02X766254Y351393I-644J-1245D01*
G03X766088Y351944I-349J195D01*
G02X767955Y352504I644J1245D01*
G37*
G36*
G01X776250Y347661D02*
G03X776535Y347659I143J139D01*
G02X776633Y345450I1065J-1059D01*
G03X776122Y345454I-258J-306D01*
G02X774069Y347637I-951J1163D01*
G03X774082Y348166I-293J272D01*
G02X774100Y350120I1150J966D01*
G03Y350646I-302J263D01*
G02X776364I1132J987D01*
G03Y350120I302J-263D01*
G02X776216Y347998I-1132J-987D01*
G03X776208Y347702I131J-152D01*
G02X776250Y347661I-1028J-1095D01*
G37*
G36*
G01X776797Y313582D02*
G03X776244Y313565I-268J-297D01*
G02X774069Y315637I-1073J1051D01*
G03X774082Y316166I-293J272D01*
G02X774100Y318120I1150J966D01*
G03Y318646I-302J263D01*
G02X776364I1132J987D01*
G03Y318120I302J-263D01*
G02X776216Y315998I-1132J-987D01*
G03X776208Y315702I131J-152D01*
G02X776301Y315606I-1031J-1092D01*
G03X776610Y315616I150J132D01*
G02X776797Y313582I1190J-916D01*
G37*
G36*
G01X772396Y309446D02*
G03X772325Y308851I227J-329D01*
G02X770482Y309072I-1047J-933D01*
G03X770553Y309667I-227J329D01*
G02X772396Y309446I1047J933D01*
G37*
G36*
G01X776293Y283614D02*
G03X776590Y283612I149J133D01*
G02X776694Y281484I1110J-1012D01*
G03X776162Y281488I-268J-297D01*
G02X774069Y283637I-991J1129D01*
G03X774082Y284166I-293J272D01*
G02X774100Y286120I1150J966D01*
G03Y286646I-302J263D01*
G02X776364I1132J987D01*
G03Y286120I302J-263D01*
G02X776216Y283998I-1132J-987D01*
G03X776208Y283702I131J-152D01*
G02X776293Y283614I-1037J-1086D01*
G37*
G36*
G01X746896Y281538D02*
G02X752004Y280262I2904J762D01*
G02X746896Y281538I-2904J-762D01*
G37*
G36*
G01X778572Y275068D02*
G03X777973Y274913I-236J-323D01*
G02X777528Y276632I-1273J588D01*
G03X778127Y276787I236J323D01*
G02X778572Y275068I1273J-588D01*
G37*
G36*
G01X752199Y274925D02*
G02X757405Y274771I2647J1415D01*
G02X752199Y274925I-2647J-1415D01*
G37*
G36*
G01X746387Y268945D02*
G02X751693Y268755I2703J1305D01*
G02X746387Y268945I-2703J-1305D01*
G37*
G36*
G01X752813Y251578D02*
G02X750240Y251423I-1450J2629D01*
G02X746261Y255750I-1540J2577D01*
G02X751686Y257192I2439J1750D01*
G02X752813Y256836I-323J-2985D01*
G02Y251578I1450J-2629D01*
G37*
G36*
G01X766693Y253259D02*
G03X766354Y252751I45J-397D01*
G02X764846Y253756I-1347J-388D01*
G03X765185Y254264I-45J397D01*
G02X765602Y255701I1347J388D01*
G03X765624Y256278I-266J299D01*
G02X767562Y256203I1008J974D01*
G03X767540Y255626I266J-299D01*
G02X766693Y253259I-1008J-974D01*
G37*
G36*
G01X776293Y251614D02*
G03X776590Y251612I149J133D01*
G02X776694Y249484I1110J-1012D01*
G03X776162Y249488I-268J-297D01*
G02X774069Y251637I-991J1129D01*
G03X774082Y252166I-293J272D01*
G02X774100Y254120I1150J966D01*
G03Y254646I-302J263D01*
G02X776364I1132J987D01*
G03Y254120I302J-263D01*
G02X776216Y251998I-1132J-987D01*
G03X776208Y251702I131J-152D01*
G02X776293Y251614I-1037J-1086D01*
G37*
G36*
G01X747300Y242136D02*
G03X747304Y241569I284J-282D01*
G02X745324Y241555I-983J-1000D01*
G03X745320Y242122I-284J282D01*
G02X747300Y242136I983J1000D01*
G37*
G36*
G01X767662Y224140D02*
G03X767640Y223563I266J-299D01*
G02X765702Y223638I-1008J-974D01*
G03X765724Y224215I-266J299D01*
G02X767662Y224140I1008J974D01*
G37*
G36*
G01X776293Y219614D02*
G03X776590Y219612I149J133D01*
G02X776694Y217484I1110J-1012D01*
G03X776162Y217488I-268J-297D01*
G02X774069Y219637I-991J1129D01*
G03X774082Y220166I-293J272D01*
G02X774100Y222120I1150J966D01*
G03Y222646I-302J263D01*
G02X776364I1132J987D01*
G03Y222120I302J-263D01*
G02X776216Y219998I-1132J-987D01*
G03X776208Y219702I131J-152D01*
G02X776293Y219614I-1037J-1086D01*
G37*
G36*
G01X766290Y380798D02*
G02X764936Y381765I-1333J-435D01*
G03X765310Y382289I-6J400D01*
G02X766009Y383974I1333J435D01*
G03X766122Y384602I-181J357D01*
G02X767789Y384300I1033J948D01*
G03X767676Y383672I181J-357D01*
G02X766664Y381322I-1033J-948D01*
G03X766290Y380798I6J-400D01*
G37*
G36*
G01X764923Y374919D02*
G02X763374Y374904I-763J-1176D01*
G03X763367Y375571I-224J331D01*
G02X764916Y375586I763J1176D01*
G03X764923Y374919I224J-331D01*
G37*
G36*
G01X761107Y361064D02*
G02X759612Y360885I-607J-1264D01*
G03X759533Y361555I-253J310D01*
G02X761028Y361734I607J1264D01*
G03X761107Y361064I253J-310D01*
G37*
G36*
G01X775465Y339137D02*
G02X775435Y340868I-1118J846D01*
G03X776064Y340879I310J252D01*
G02X778252Y340939I1118J-846D01*
G03X778862I305J259D01*
G02Y339127I1070J-906D01*
G03X778252I-305J-259D01*
G02X776094Y339148I-1070J906D01*
G03X775465Y339137I-310J-252D01*
G37*
G36*
G01X764141Y339743D02*
G02X763234Y340819I-1381J-244D01*
G03X763763Y341265I135J377D01*
G02X764359Y342669I1381J242D01*
G03X764352Y343336I-224J331D01*
G02X765901Y343351I763J1176D01*
G03X765908Y342684I224J-331D01*
G02X764670Y340189I-764J-1176D01*
G03X764141Y339743I-135J-377D01*
G37*
G36*
G01X766382Y316635D02*
G02X765182Y317754I-1375J-272D01*
G03X765625Y318228I50J397D01*
G02X765973Y319454I1375J272D01*
G03X765913Y320051I-293J272D01*
G02X767759Y320235I819J1138D01*
G03X767819Y319638I293J-272D01*
G02X766825Y317109I-819J-1138D01*
G03X766382Y316635I-50J-397D01*
G37*
G36*
G01X765908Y310684D02*
G02X764359Y310669I-763J-1176D01*
G03X764352Y311336I-224J331D01*
G02X765901Y311351I763J1176D01*
G03X765908Y310684I224J-331D01*
G37*
G36*
G01X777591Y306631D02*
G02X777150Y308191I-1321J469D01*
G03X777779Y308369I252J311D01*
G02X778220Y306809I1321J-469D01*
G03X777591Y306631I-252J-311D01*
G37*
G36*
G01X766364Y284716D02*
G02X765442Y285696I-1357J-353D01*
G03X765953Y286177I124J380D01*
G02X765923Y286323I1357J355D01*
G03X765406Y286644I-395J-60D01*
G02X766367Y288187I-426J1336D01*
G03X766884Y287866I395J60D01*
G02X766875Y285197I426J-1336D01*
G03X766364Y284716I-124J-380D01*
G37*
G36*
G01X765908Y278684D02*
G02X764359Y278669I-763J-1176D01*
G03X764352Y279336I-224J331D01*
G02X765901Y279351I763J1176D01*
G03X765908Y278684I224J-331D01*
G37*
G36*
G01Y246684D02*
G02X764359Y246669I-763J-1176D01*
G03X764352Y247336I-224J331D01*
G02X765901Y247351I763J1176D01*
G03X765908Y246684I224J-331D01*
G37*
G36*
G01X778282Y242932D02*
G02X778000Y244483I-1282J568D01*
G03X778650Y244601I285J281D01*
G02X778932Y243050I1282J-568D01*
G03X778282Y242932I-285J-281D01*
G37*
G36*
G01X1069992Y337612D02*
G03X1069392I-300J-265D01*
G02Y339734I-1200J1061D01*
G03X1069992I300J265D01*
G02Y337612I1200J-1061D01*
G37*
G36*
G01X1062792D02*
G03X1062192I-300J-265D01*
G02Y339734I-1200J1061D01*
G03X1062792I300J265D01*
G02Y337612I1200J-1061D01*
G37*
G36*
G01X1079082Y337472D02*
G03X1078482I-300J-265D01*
G02Y339594I-1200J1061D01*
G03X1079082I300J265D01*
G02Y337472I1200J-1061D01*
G37*
G36*
G01X1049571Y337418D02*
G03X1048941I-315J-246D01*
G02Y339264I-1185J923D01*
G03X1049571I315J246D01*
G02X1051899Y339316I1185J-923D01*
G03X1052518Y339329I304J259D01*
G02X1054791Y339438I1183J-925D01*
G03X1055423Y339505I290J275D01*
G02X1055588Y337617I1369J-832D01*
G03X1054954Y337574I-301J-264D01*
G02X1052559Y337429I-1252J830D01*
G03X1051940Y337416I-304J-259D01*
G02X1049571Y337418I-1184J925D01*
G37*
G36*
G01X844127Y330490D02*
G03X843573I-277J-288D01*
G02Y332510I-973J1010D01*
G03X844127I277J288D01*
G02X846073I973J-1010D01*
G03X846627I277J288D01*
G02Y330490I973J-1010D01*
G03X846073I-277J-288D01*
G02X844127I-973J1010D01*
G37*
G36*
G01X1077820Y323113D02*
G03X1077220I-300J-265D01*
G02Y325235I-1200J1061D01*
G03X1077820I300J265D01*
G02Y323113I1200J-1061D01*
G37*
G36*
G01X1017207Y311236D02*
G03X1016654Y311109I-213J-338D01*
G02X1016286Y313212I-1361J846D01*
G03X1016850Y313281I248J314D01*
G02X1018914Y313445I1107J-860D01*
G03X1019458Y313442I274J292D01*
G02X1021395Y313399I946J-1034D01*
G03X1021953Y313391I283J283D01*
G02X1023893Y313377I963J-1019D01*
G03X1024453Y313379I279J286D01*
G02X1026438Y313364I985J-998D01*
G03X1027015Y313371I285J281D01*
G02X1027039Y311431I1024J-957D01*
G03X1026462Y311424I-285J-281D01*
G02X1024460Y311376I-1025J957D01*
G03X1023900Y311374I-279J-286D01*
G02X1021924Y311381I-984J998D01*
G03X1021366Y311389I-283J-283D01*
G02X1019447Y311384I-962J1019D01*
G03X1018903Y311387I-274J-292D01*
G02X1017207Y311236I-947J1034D01*
G37*
G36*
G01X844127Y298890D02*
G03X843573I-277J-288D01*
G02Y300910I-973J1010D01*
G03X844127I277J288D01*
G02X846073I973J-1010D01*
G03X846627I277J288D01*
G02Y298890I973J-1010D01*
G03X846073I-277J-288D01*
G02X844127I-973J1010D01*
G37*
G36*
G01X1048167Y294798D02*
G03X1047567I-300J-265D01*
G02Y296920I-1200J1061D01*
G03X1048167I300J265D01*
G02Y294798I1200J-1061D01*
G37*
G36*
G01X1040967D02*
G03X1040367I-300J-265D01*
G02Y296920I-1200J1061D01*
G03X1040967I300J265D01*
G02Y294798I1200J-1061D01*
G37*
G36*
G01X1033767D02*
G03X1033167I-300J-265D01*
G02Y296920I-1200J1061D01*
G03X1033767I300J265D01*
G02Y294798I1200J-1061D01*
G37*
G36*
G01X1026567D02*
G03X1025967I-300J-265D01*
G02Y296920I-1200J1061D01*
G03X1026567I300J265D01*
G02Y294798I1200J-1061D01*
G37*
G36*
G01X1019367D02*
G03X1018767I-300J-265D01*
G02Y296920I-1200J1061D01*
G03X1019367I300J265D01*
G02Y294798I1200J-1061D01*
G37*
G36*
G01X1026702Y277843D02*
G03X1026102I-300J-265D01*
G02Y279965I-1200J1061D01*
G03X1026702I300J265D01*
G02Y277843I1200J-1061D01*
G37*
G36*
G01X1019502D02*
G03X1018902I-300J-265D01*
G02Y279965I-1200J1061D01*
G03X1019502I300J265D01*
G02Y277843I1200J-1061D01*
G37*
G36*
G01X1031550Y272689D02*
G03Y272089I265J-300D01*
G02X1029428I-1061J-1200D01*
G03Y272689I-265J300D01*
G02X1031550I1061J1200D01*
G37*
G36*
G01X844127Y267190D02*
G03X843573I-277J-288D01*
G02Y269210I-973J1010D01*
G03X844127I277J288D01*
G02X846073I973J-1010D01*
G03X846627I277J288D01*
G02Y267190I973J-1010D01*
G03X846073I-277J-288D01*
G02X844127I-973J1010D01*
G37*
G36*
G01X1048817Y263976D02*
G03X1048187I-315J-246D01*
G02Y265822I-1185J923D01*
G03X1048817I315J246D01*
G02Y263976I1185J-923D01*
G37*
G36*
G01X1042317D02*
G03X1041687I-315J-246D01*
G02Y265822I-1185J923D01*
G03X1042317I315J246D01*
G02Y263976I1185J-923D01*
G37*
G36*
G01X848610Y239927D02*
G03Y239373I288J-277D01*
G02X846590I-1010J-973D01*
G03Y239927I-288J277D01*
G02Y241873I1010J973D01*
G03Y242427I-288J277D01*
G02X848610I1010J973D01*
G03Y241873I288J-277D01*
G02Y239927I-1010J-973D01*
G37*
G36*
G01X842410Y239827D02*
G03Y239273I288J-277D01*
G02X840390I-1010J-973D01*
G03Y239827I-288J277D01*
G02Y241773I1010J973D01*
G03Y242327I-288J277D01*
G02X842410I1010J973D01*
G03Y241773I288J-277D01*
G02Y239827I-1010J-973D01*
G37*
G36*
G01X1036980Y323069D02*
G02Y325279I-1160J1105D01*
G03X1037560I290J275D01*
G02X1039820Y325338I1160J-1105D01*
G03X1040370I275J291D01*
G02X1042570I1100J-1164D01*
G03X1043120I275J291D01*
G02X1045420Y325235I1100J-1164D01*
G03X1046020I300J265D01*
G02X1048420I1200J-1061D01*
G03X1049020I300J265D01*
G02X1051420I1200J-1061D01*
G03X1052020I300J265D01*
G02X1054420I1200J-1061D01*
G03X1055020I300J265D01*
G02X1057420I1200J-1061D01*
G03X1058020I300J265D01*
G02X1060420I1200J-1061D01*
G03X1061020I300J265D01*
G02X1063420I1200J-1061D01*
G03X1064020I300J265D01*
G02X1066660Y324875I1200J-1061D01*
G03X1067380I360J175D01*
G02X1070020Y325235I1440J-701D01*
G03X1070620I300J265D01*
G02Y323113I1200J-1061D01*
G03X1070020I-300J-265D01*
G02X1067380Y323473I-1200J1061D01*
G03X1066660I-360J-175D01*
G02X1064020Y323113I-1440J701D01*
G03X1063420I-300J-265D01*
G02X1061020I-1200J1061D01*
G03X1060420I-300J-265D01*
G02X1058020I-1200J1061D01*
G03X1057420I-300J-265D01*
G02X1055020I-1200J1061D01*
G03X1054420I-300J-265D01*
G02X1052020I-1200J1061D01*
G03X1051420I-300J-265D01*
G02X1049020I-1200J1061D01*
G03X1048420I-300J-265D01*
G02X1046020I-1200J1061D01*
G03X1045420I-300J-265D01*
G02X1043120Y323010I-1200J1061D01*
G03X1042570I-275J-291D01*
G02X1040370I-1100J1164D01*
G03X1039820I-275J-291D01*
G02X1037560Y323069I-1100J1164D01*
G03X1036980I-290J-275D01*
G37*
G36*
G01X1037239Y278042D02*
G02X1037181Y279611I-1425J733D01*
G03X1037877Y279637I341J209D01*
G02X1040502Y279965I1425J-733D01*
G03X1041102I300J265D01*
G02Y277843I1200J-1061D01*
G03X1040502I-300J-265D01*
G02X1037935Y278068I-1200J1061D01*
G03X1037239Y278042I-341J-209D01*
G37*
G36*
G01X1224394Y258062D02*
G02X1223990Y259683I-1294J538D01*
G03X1224614Y259838I255J309D01*
G02X1224898Y260273I1296J-536D01*
G03Y260827I-288J277D01*
G02X1224659Y261164I1012J971D01*
G03X1224126Y261341I-356J-182D01*
G02X1224757Y263236I-618J1258D01*
G03X1225290Y263059I356J182D01*
G02X1226918Y260827I619J-1258D01*
G03Y260273I288J-277D01*
G02X1225018Y258217I-1009J-973D01*
G03X1224394Y258062I-255J-309D01*
G37*
G36*
G01X1227949Y209453D02*
G03X1227966Y208928I310J-253D01*
G02X1225703Y208854I-1099J-1024D01*
G03X1225686Y209379I-310J253D01*
G02X1225689Y211430I1099J1024D01*
G03Y211976I-292J273D01*
G02X1225857Y214184I1096J1027D01*
G03X1225945Y214718I-247J315D01*
G02X1228128Y214362I1255J825D01*
G03X1228040Y213828I247J-315D01*
G02X1227881Y211976I-1255J-825D01*
G03Y211430I292J-273D01*
G02X1227949Y209453I-1096J-1027D01*
G37*
G36*
G01X1222396Y206973D02*
G03Y206427I292J-273D01*
G02X1220204I-1096J-1027D01*
G03Y206973I-292J273D01*
G02X1222396I1096J1027D01*
G37*
G36*
G01X1215224Y266528D02*
G03Y267082I-288J277D01*
G02X1215718Y269359I1010J973D01*
G03X1215932Y269901I-148J371D01*
G02X1217716Y269196I1268J599D01*
G03X1217502Y268654I148J-371D01*
G02X1217244Y267082I-1268J-599D01*
G03Y266528I288J-277D01*
G02X1215586Y264312I-1010J-973D01*
G03X1215047Y264144I-185J-355D01*
G02X1214456Y266043I-1239J656D01*
G03X1214995Y266211I185J355D01*
G02X1215224Y266528I1240J-655D01*
G37*
G36*
G01X1218566Y244363D02*
G03X1219170Y244341I312J251D01*
G02X1219104Y242503I1024J-957D01*
G03X1218500Y242525I-312J-251D01*
G02X1216404Y242579I-1024J957D01*
G03X1215795Y242582I-306J-258D01*
G02X1213747Y242499I-1063J914D01*
G03X1213184I-282J-285D01*
G02Y244493I-985J997D01*
G03X1213747I282J285D01*
G02X1215804Y244399I985J-997D01*
G03X1216413Y244396I306J258D01*
G02X1218566Y244363I1063J-914D01*
G37*
G36*
G01X1220270Y214898D02*
G02X1218893Y216271I-1402J-29D01*
G03X1219300Y216679I7J400D01*
G02X1219317Y216923I1402J25D01*
G03X1218979Y217097I-198J31D01*
G02X1218210Y219486I-979J1003D01*
G03X1218658Y219980I60J396D01*
G02X1219807Y218937I1359J343D01*
G03X1219359Y218443I-60J-396D01*
G02X1219396Y218228I-1359J-345D01*
G03X1219996Y217919I398J37D01*
G02X1220677Y215306I706J-1211D01*
G03X1220270Y214898I-7J-400D01*
G37*
G36*
G01X1113707Y314299D02*
G03X1113702Y313770I298J-267D01*
G02X1111298Y313793I-1212J-1047D01*
G03X1111303Y314322I-298J267D01*
G02X1113707Y314299I1212J1047D01*
G37*
G36*
G01X1115399Y297711D02*
G03X1115861Y297293I399J-23D01*
G02X1114597Y295898I235J-1483D01*
G03X1114135Y296316I-399J23D01*
G02X1115399Y297711I-235J1483D01*
G37*
G36*
G01X1118706Y287537D02*
G02X1118374Y285590I815J-1141D01*
G03X1117814Y285685I-327J-230D01*
G02X1115658Y287234I-815J1141D01*
G03X1115266Y287750I-383J116D01*
G02X1113797Y289702I-36J1502D01*
G03X1113356Y290217I-382J119D01*
G02X1114565Y291252I-224J1485D01*
G03X1115006Y290737I382J-119D01*
G02X1116649Y288759I224J-1485D01*
G03X1117020Y288228I378J-131D01*
G02X1118146Y287632I-21J-1402D01*
G03X1118706Y287537I327J230D01*
G37*
G36*
G01X1097717Y280095D02*
G03X1098228I255J308D01*
G02X1098225Y277784I958J-1157D01*
G03X1097714I-256J-308D01*
G02X1097717Y280095I-958J1157D01*
G37*
G36*
G01X1109765Y275810D02*
G03X1109221Y275772I-252J-311D01*
G02X1109137Y277909I-1096J1027D01*
G03X1109682Y277915I269J296D01*
G02X1109765Y275810I966J-1016D01*
G37*
G36*
G01X1102046Y273345D02*
G03X1101576Y273030I-78J-392D01*
G02X1100397Y274688I-1376J270D01*
G03X1100849Y275028I56J396D01*
G02X1102046Y273345I1487J-209D01*
G37*
G36*
G01X1160440Y261386D02*
G03X1160444Y260810I279J-286D01*
G02X1158360Y260794I-1034J-1090D01*
G03X1158356Y261370I-279J286D01*
G02X1158455Y263636I1034J1090D01*
G03X1158511Y264208I-249J313D01*
G02X1158176Y265100I1067J910D01*
G03X1157786Y265494I-400J-6D01*
G02X1159222Y266913I34J1402D01*
G03X1159612Y266519I400J6D01*
G02X1160645Y266027I-34J-1402D01*
G03X1161233Y266004I305J259D01*
G02X1161110Y264030I1067J-1057D01*
G03X1160523Y264082I-317J-243D01*
G02X1160507Y264067I-966J1015D01*
G03X1160481Y263492I265J-300D01*
G02X1160440Y261386I-1091J-1032D01*
G37*
G36*
G01X1106370Y267394D02*
G02X1105573Y268628I-1499J-94D01*
G03X1106160Y268994I187J354D01*
G02X1106662Y270113I1401J44D01*
G03X1106656Y270731I-257J307D01*
G02X1108512Y270706I944J1169D01*
G03X1108489Y270089I242J-318D01*
G02X1106945Y267779I-928J-1051D01*
G03X1106370Y267394I-176J-359D01*
G37*
G36*
G01X1084167Y294798D02*
G03X1083567I-300J-265D01*
G02Y296920I-1200J1061D01*
G03X1084167I300J265D01*
G02Y294798I1200J-1061D01*
G37*
G36*
G01X1076967D02*
G03X1076367I-300J-265D01*
G02Y296920I-1200J1061D01*
G03X1076967I300J265D01*
G02Y294798I1200J-1061D01*
G37*
G36*
G01X1069767D02*
G03X1069167I-300J-265D01*
G02Y296920I-1200J1061D01*
G03X1069767I300J265D01*
G02Y294798I1200J-1061D01*
G37*
G36*
G01X1102935Y293354D02*
G03X1103463Y293233I330J227D01*
G02X1102936Y290934I793J-1392D01*
G03X1102408Y291055I-330J-227D01*
G02X1100320Y291505I-792J1392D01*
G03X1099748Y291583I-323J-236D01*
G02X1097556Y291780I-992J1258D01*
G03X1096956I-300J-265D01*
G02X1094624Y293975I-1200J1062D01*
G03X1094586Y294574I-283J283D01*
G02X1094360Y294787I981J1267D01*
G03X1093761Y294791I-301J-263D01*
G02X1091367Y294798I-1194J1068D01*
G03X1090767I-300J-265D01*
G02Y296920I-1200J1061D01*
G03X1091367I300J265D01*
G02X1093774Y296913I1200J-1061D01*
G03X1094373Y296909I301J263D01*
G02X1096767Y296902I1194J-1068D01*
G03X1097367I300J265D01*
G02X1099761Y296909I1200J-1061D01*
G03X1100360Y296913I298J267D01*
G02X1102702Y296989I1206J-1054D01*
G03X1103233Y296957I283J282D01*
G02X1103086Y294566I988J-1261D01*
G03X1102555Y294598I-283J-282D01*
G02X1102424Y294506I-985J1263D01*
G03X1102434Y293824I214J-338D01*
G02X1102935Y293354I-820J-1376D01*
G37*
G36*
G01X1104888Y308828D02*
G02X1102375Y307251I-1132J-987D01*
G03X1101849Y307461I-368J-157D01*
G02X1099875Y308251I-593J1380D01*
G03X1099349Y308461I-368J-157D01*
G02X1097532Y308971I-593J1380D01*
G03X1096889Y308984I-326J-232D01*
G02X1096926Y310774I-1187J920D01*
G03X1097569Y310761I326J232D01*
G02X1100137Y310431I1187J-920D01*
G03X1100663Y310221I368J157D01*
G02X1101747Y310261I594J-1380D01*
G03X1102272Y310576I130J378D01*
G02X1104888Y309354I1484J-235D01*
G03Y308828I302J-263D01*
G37*
G36*
G01X1084242Y277941D02*
G03X1083606I-318J-242D01*
G02Y279879I-1276J969D01*
G03X1084242I318J242D01*
G02Y277941I1276J-969D01*
G37*
G36*
G01X1077102Y277849D02*
G03X1076502I-300J-265D01*
G02Y279971I-1200J1061D01*
G03X1077102I300J265D01*
G02Y277849I1200J-1061D01*
G37*
G36*
G01X1069668Y277918D02*
G03X1069041I-314J-248D01*
G02Y279902I-1258J992D01*
G03X1069668I314J248D01*
G02Y277918I1258J-992D01*
G37*
G36*
G01X1096677Y267649D02*
G03Y267041I260J-304D01*
G02X1094723I-977J-1141D01*
G03Y267649I-260J304D01*
G02X1096677I977J1141D01*
G37*
G36*
G01X1074367Y266089D02*
G03X1074899Y266044I291J274D01*
G02X1074698Y263668I966J-1278D01*
G03X1074166Y263713I-291J-274D01*
G02X1072074Y263851I-966J1278D01*
G03X1071495Y263833I-281J-285D01*
G02X1071426Y266040I-1195J1067D01*
G03X1072005Y266058I281J285D01*
G02X1074367Y266089I1195J-1067D01*
G37*
G36*
G01X1087254Y263369D02*
G02X1084819Y263312I-1193J-1069D01*
G03X1084807Y263831I-310J252D01*
G02X1084629Y264072I1194J1068D01*
G03X1083916Y264016I-342J-207D01*
G02X1081173Y263629I-1484J604D01*
G03X1080648Y263722I-314J-247D01*
G02X1080984Y265995I-789J1278D01*
G03X1081513Y265932I300J265D01*
G02X1083803Y265448I919J-1312D01*
G03X1084516Y265504I342J207D01*
G02X1087517Y265414I1484J-604D01*
G03X1087871Y265363I190J64D01*
G02X1087930Y265442I1232J-859D01*
G03X1087909Y265968I-311J251D01*
G02X1090258Y267821I1091J1032D01*
G03X1090952Y267863I335J218D01*
G02X1093212Y266006I1348J-663D01*
G03X1093154Y265425I243J-318D01*
G02X1090981Y263655I-1054J-925D01*
G03X1090333Y263643I-320J-241D01*
G02X1087692Y263978I-1233J857D01*
G03X1087337Y264018I-188J-70D01*
G02X1087242Y263888I-1339J879D01*
G03X1087254Y263369I310J-252D01*
G37*
G36*
G01X1244901Y398344D02*
G02X1243959Y399733I-1502J-5D01*
G03X1244508Y400105I149J371D01*
G02X1245450Y398716I1502J5D01*
G03X1244901Y398344I-149J-371D01*
G37*
G36*
G01X1106863Y335153D02*
G02X1104858Y335082I-963J-1153D01*
G03X1104837Y335677I-277J288D01*
G02X1106316Y338240I963J1153D01*
G03X1106853Y338645I138J376D01*
G02X1107815Y337413I1398J100D01*
G03X1107293Y336990I-124J-380D01*
G02X1106842Y335748I-1493J-161D01*
G03X1106863Y335153I277J-288D01*
G37*
G36*
G01X1370996Y395697D02*
G03X1370418I-289J-277D01*
G02Y397639I-1011J971D01*
G03X1370996I289J277D01*
G02Y395697I1011J-971D01*
G37*
G36*
G01X1375339Y386481D02*
G03Y385955I302J-263D01*
G02X1373075I-1132J-987D01*
G03Y386481I-302J263D01*
G02X1373105Y388489I1132J987D01*
G03X1373118Y389018I-293J272D01*
G02X1375370Y388964I1150J967D01*
G03X1375357Y388435I293J-272D01*
G02X1375339Y386481I-1150J-966D01*
G37*
G36*
G01X1360102Y382802D02*
G03X1360302Y382602I200J0D01*
G02X1360350Y379599I-2J-1502D01*
G03X1360156Y379393I6J-200D01*
G02Y379286I-1501J-54D01*
G03X1360480Y378876I399J-17D01*
G02X1360135Y375899I-280J-1476D01*
G03X1359778Y375290I-17J-399D01*
G02X1359502Y373381I-1278J-790D01*
G03X1359490Y372797I267J-298D01*
G02X1357525Y372788I-978J-1005D01*
G03X1357508Y373372I-281J284D01*
G02X1358565Y376001I992J1128D01*
G03X1358922Y376610I17J399D01*
G02X1358699Y377466I1278J790D01*
G03X1358375Y377876I-399J17D01*
G02X1358605Y380853I280J1476D01*
G03X1358799Y381059I-6J200D01*
G02X1358798Y381098I1501J58D01*
G03X1358598Y381298I-200J0D01*
G02X1358362Y384283I2J1502D01*
G03X1358698Y384683I-64J395D01*
G02X1358702Y384810I1502J16D01*
G03X1358387Y385231I-399J30D01*
G02X1358422Y388176I313J1469D01*
G03X1358737Y388660I-74J393D01*
G02X1358698Y389002I1463J340D01*
G03X1358355Y389398I-400J0D01*
G02X1357436Y391872I213J1487D01*
G03Y392398I-302J263D01*
G02X1359700I1132J987D01*
G03Y391872I302J-263D01*
G02X1360061Y390723I-1132J-987D01*
G03X1360253Y390501I199J-22D01*
G02X1360356Y390494I-50J-1501D01*
G03X1360576Y390715I21J199D01*
G02X1360936Y391872I1492J170D01*
G03Y392398I-302J263D01*
G02X1363200I1132J987D01*
G03Y391872I302J-263D01*
G02X1362095Y389383I-1132J-987D01*
G03X1361702Y388987I7J-400D01*
G02X1360478Y387524I-1502J13D01*
G03X1360163Y387040I74J-393D01*
G02X1360198Y386590I-1463J-340D01*
G03X1360513Y386169I399J-30D01*
G02X1360438Y383217I-313J-1469D01*
G03X1360102Y382817I64J-395D01*
G01Y382802D01*
G37*
G36*
G01X1381129Y371450D02*
G02X1379271I-929J-1050D01*
G03Y372050I-265J300D01*
G02X1378921Y372526I929J1050D01*
G03X1378233Y372599I-365J-164D01*
G02X1377889Y372267I-1131J828D01*
G03X1377862Y371625I224J-331D01*
G02X1375667Y370041I-883J-1089D01*
G03X1375083Y370239I-374J-142D01*
G02X1373399Y372466I-739J1192D01*
G03X1373369Y373082I-270J296D01*
G02X1375689Y374773I899J1203D01*
G03X1376297Y374575I378J129D01*
G02X1378382Y374002I806J-1147D01*
G03X1379070Y373929I365J164D01*
G02X1381129Y372050I1131J-829D01*
G03Y371450I265J-300D01*
G37*
G36*
G01X1357736Y359878D02*
G02X1357671Y361577I-1270J802D01*
G03X1358330Y361602I321J239D01*
G02X1360825Y361669I1270J-802D01*
G03X1361453Y361638I326J232D01*
G02X1361402Y359858I1057J-921D01*
G03X1360773Y359862I-316J-245D01*
G02X1358395Y359903I-1173J938D01*
G03X1357736Y359878I-321J-239D01*
G37*
G36*
G01X1343321Y360990D02*
G03X1343905Y360822I364J166D01*
G02X1343364Y358945I826J-1255D01*
G03X1342780Y359113I-364J-166D01*
G02X1343321Y360990I-826J1255D01*
G37*
G36*
G01X1338933Y351103D02*
G02X1338120Y349481I664J-1347D01*
G03X1337550Y349766I-393J-74D01*
G02X1338363Y351388I-664J1347D01*
G03X1338933Y351103I393J74D01*
G37*
G36*
G01X1331530Y347307D02*
G02X1331474Y345600I1083J-890D01*
G03X1330840Y345621I-325J-233D01*
G02X1330896Y347328I-1083J890D01*
G03X1331530Y347307I325J233D01*
G37*
G36*
G01X1306859Y308248D02*
G03X1306876Y307664I281J-284D01*
G02X1304964Y307608I-926J-1053D01*
G03X1304947Y308192I-281J284D01*
G02X1304877Y308258I926J1053D01*
G03X1304338Y308284I-284J-282D01*
G02X1304507Y310434I-958J1157D01*
G03X1305044Y310376I300J264D01*
G02X1306859Y308248I830J-1130D01*
G37*
G36*
G01X1300762Y300202D02*
G03X1300755Y299626I274J-291D01*
G02X1298673Y299653I-1055J-1069D01*
G03X1298680Y300229I-274J291D01*
G02X1300762Y300202I1055J1069D01*
G37*
G36*
G01X1322999Y321051D02*
G02X1322250Y319673I751J-1301D01*
G03X1321651Y319999I-399J-21D01*
G02X1322400Y321377I-751J1301D01*
G03X1322999Y321051I399J21D01*
G37*
G36*
G01X1970868Y500661D02*
G02X1969208Y501075I-1577J-2787D01*
G03X1969487Y501751I-10J400D01*
G02X1970940Y501389I1013J969D01*
G03X1970868Y500661I125J-380D01*
G37*
G36*
G01X1970288Y483021D02*
G03X1970070Y482434I125J-380D01*
G02X1967831Y482651I-1200J-724D01*
G03X1967729Y483269I-297J268D01*
G02X1970288Y483021I1562J2795D01*
G37*
G36*
G01X1962657Y618342D02*
G03X1962643Y617738I255J-308D01*
G02X1960757I-943J-1038D01*
G03X1960743Y618342I-269J296D01*
G02X1962657I957J1158D01*
G37*
G36*
G01X1931517Y617794D02*
G03Y617206I270J-294D01*
G02X1929483I-1017J-1106D01*
G03Y617794I-270J294D01*
G02X1931517I1017J1106D01*
G37*
G36*
G01X1921115Y605433D02*
G03X1921746Y605412I324J235D01*
G02X1921685Y603567I1154J-962D01*
G03X1921054Y603588I-324J-235D01*
G02X1921115Y605433I-1154J962D01*
G37*
G36*
G01X1936346Y608546D02*
G02X1935381Y607402I424J-1336D01*
G03X1934852Y607834I-396J55D01*
G02X1935830Y608995I-502J1416D01*
G03X1936346Y608546I394J-68D01*
G37*
G36*
G01X1930653Y535242D02*
G02Y529840I0J-2701D01*
G01X1928253D01*
G02Y535242I0J2701D01*
G01X1930653D01*
G37*
G36*
G01X1935870Y569709D02*
G03X1936396Y569415I391J83D01*
G02X1935430Y567691I504J-1415D01*
G03X1934904Y567985I-391J-83D01*
G02X1935870Y569709I-504J1415D01*
G37*
G36*
G01X1934250Y563906D02*
G03X1934628Y563402I386J-104D01*
G02X1933150Y562294I-28J-1502D01*
G03X1932772Y562798I-386J104D01*
G02X1934250Y563906I28J1502D01*
G37*
G36*
G01X1909395Y557787D02*
G03X1909957Y557781I284J282D01*
G02X1909877Y555702I1043J-1081D01*
G03X1909317Y555739I-299J-266D01*
G02X1909395Y557787I-917J1060D01*
G37*
G36*
G01X1936798Y551349D02*
G03X1937303Y551117I373J146D01*
G02X1936402Y549151I497J-1417D01*
G03X1935897Y549383I-373J-146D01*
G02X1936798Y551349I-497J1417D01*
G37*
G36*
G01X1923217Y545380D02*
G03X1923112Y544760I191J-351D01*
G02X1921283Y545070I-1112J-1010D01*
G03X1921388Y545690I-191J351D01*
G02X1923217Y545380I1112J1010D01*
G37*
G36*
G01X1940776Y542558D02*
G03X1940755Y541969I260J-304D01*
G02X1938435Y540090I-1055J-1069D01*
G03X1937931Y540237I-336J-216D01*
G02X1938130Y542852I-631J1363D01*
G03X1938424Y543099I111J167D01*
G02X1938324Y543419I1375J605D01*
G03X1937778Y543714I-393J-74D01*
G02X1937812Y546472I-578J1386D01*
G03X1938359Y546724I163J365D01*
G02X1940896Y545273I1441J-424D01*
G03Y544727I292J-273D01*
G02X1940776Y542558I-1096J-1027D01*
G37*
G36*
G01X1942833Y537022D02*
G02X1941904Y535571I467J-1322D01*
G03X1941357Y535905I-398J-37D01*
G02X1942300Y537378I-557J1395D01*
G03X1942833Y537022I399J21D01*
G37*
G36*
G01X1958308Y548314D02*
G02X1957619Y547089I812J-1263D01*
G03X1957003Y547436I-400J10D01*
G02X1957692Y548661I-812J1263D01*
G03X1958308Y548314I400J-10D01*
G37*
G36*
G01X1924325Y573500D02*
G02X1922875I-725J-1200D01*
G03X1922864Y574191I-207J342D01*
G02X1924336I736J1309D01*
G03X1924325Y573500I196J-349D01*
G37*
G36*
G01X1920820Y587102D02*
G02X1920606Y585366I980J-1002D01*
G03X1919974Y585430I-340J-210D01*
G02X1920191Y587193I-1094J1030D01*
G03X1920820Y587102I349J195D01*
G37*
G36*
G01X1932053Y513904D02*
G02Y508500I0J-2702D01*
G01X1926853D01*
G02Y513904I0J2702D01*
G01X1932053D01*
G37*
G36*
G01X1911615Y509777D02*
G03X1910985I-315J-246D01*
G02Y511623I-1185J923D01*
G03X1911615I315J246D01*
G02Y509777I1185J-923D01*
G37*
G36*
G01X1939943Y478362D02*
G03X1939957Y477758I269J-296D01*
G02X1938043I-957J-1158D01*
G03X1938057Y478362I-255J308D01*
G02X1939943I943J1038D01*
G37*
G36*
G01X1911423Y473815D02*
G03Y473185I246J-315D01*
G02X1909577I-923J-1185D01*
G03Y473815I-246J315D01*
G02X1911423I923J1185D01*
G37*
G36*
G01X1915424Y468001D02*
G03X1916048I312J250D01*
G02X1916047Y465998I1250J-1002D01*
G03X1915423I-312J-250D01*
G02X1912903Y466023I-1250J1002D01*
G03X1912269I-317J-243D01*
G02Y467977I-1270J977D01*
G03X1912903I317J243D01*
G02X1915424Y468001I1270J-977D01*
G37*
G36*
G01X1946339Y473319D02*
G02X1946189Y474918I-1339J681D01*
G03X1946861Y474981I316J245D01*
G02X1947011Y473382I1339J-681D01*
G03X1946339Y473319I-316J-245D01*
G37*
G36*
G01X1948335Y483476D02*
G02X1946551Y483581I-955J-1026D01*
G03X1946575Y484208I-236J323D01*
G02X1948385Y484102I975J1142D01*
G03X1948335Y483476I222J-333D01*
G37*
G36*
G01X1958589Y507241D02*
G02X1957865Y505872I671J-1231D01*
G03X1957264Y506177I-398J-40D01*
G02X1957999Y507567I-764J1293D01*
G03X1958589Y507241I399J25D01*
G37*
G36*
G01X1889927Y535242D02*
G02Y529840I0J-2701D01*
G01X1884727D01*
G02Y535242I0J2701D01*
G01X1889927D01*
G37*
G36*
G01X1859563Y558005D02*
G03X1859284Y557542I113J-384D01*
G02X1857473Y558708I-1472J-297D01*
G03X1857779Y559154I-90J390D01*
G02X1859563Y558005I1388J196D01*
G37*
G36*
G01X1872229Y542494D02*
G02X1872128Y541122I1281J-784D01*
G03X1871425Y541184I-368J-156D01*
G02X1871524Y542535I-1175J765D01*
G03X1872229Y542494I363J167D01*
G37*
G36*
G01X1900099Y546084D02*
G02X1898351Y546667I-1249J-834D01*
G03X1898551Y547266I-133J377D01*
G02X1898517Y547319I1247J837D01*
G03X1897991Y547466I-342J-208D01*
G02X1898583Y549581I-691J1334D01*
G03X1899109Y549434I342J208D01*
G02X1900299Y546683I691J-1334D01*
G03X1900099Y546084I133J-377D01*
G37*
G36*
G01X1849886Y546497D02*
G02X1847914I-986J-997D01*
G03X1847900Y547080I-281J285D01*
G02X1848050Y549438I1000J1120D01*
G03X1848029Y550111I-227J330D01*
G02X1849650Y550162I771J1289D01*
G03X1849671Y549489I227J-330D01*
G02X1849900Y547080I-771J-1289D01*
G03X1849886Y546497I267J-298D01*
G37*
G36*
G01X1857222Y548299D02*
G02X1855414Y549464I-1472J-299D01*
G03X1855720Y549910I-90J390D01*
G02X1856137Y551119I1388J198D01*
G03Y551697I-277J289D01*
G02X1856026Y551817I972J1010D01*
G03X1855711Y551809I-154J-127D01*
G02X1853025Y552948I-1203J899D01*
G03X1852582Y553409I-395J64D01*
G02X1853883Y554660I-182J1491D01*
G03X1854326Y554199I395J-64D01*
G02X1855591Y553749I182J-1491D01*
G03X1856152Y553733I289J277D01*
G02X1858064I956J-1025D01*
G03X1858625Y553749I272J293D01*
G02Y551667I1083J-1041D01*
G03X1858064Y551683I-289J-277D01*
G02X1857927Y551570I-959J1023D01*
G03Y551246I117J-162D01*
G02X1857502Y548762I-819J-1138D01*
G03X1857222Y548299I112J-384D01*
G37*
G36*
G01X1858246Y575380D02*
G02X1856692Y574505I-246J-1380D01*
G03X1856372Y575045I-373J144D01*
G02X1857950Y575934I201J1489D01*
G03X1858246Y575380I367J-160D01*
G37*
G36*
G01X1888527Y513904D02*
G02Y508500I0J-2702D01*
G01X1886127D01*
G02Y513904I0J2702D01*
G01X1888527D01*
G37*
G36*
G01X1843621Y506748D02*
G03X1843743Y506189I334J-220D01*
G02X1841829Y505772I-743J-1189D01*
G03X1841707Y506331I-334J220D01*
G02X1842559Y508918I743J1189D01*
G03X1842990Y509298I31J399D01*
G02X1844295Y507741I1500J-68D01*
G03X1843845Y507383I-52J-397D01*
G02X1843621Y506748I-1396J135D01*
G37*
G36*
G01X1875015Y501490D02*
G03X1875507Y501266I368J156D01*
G02X1874590Y499252I466J-1428D01*
G03X1874098Y499476I-368J-156D01*
G02X1875015Y501490I-466J1428D01*
G37*
G36*
G01X1842073Y490404D02*
G03X1841527I-273J-292D01*
G02X1839404Y492527I-1027J1096D01*
G03Y493073I-292J273D01*
G02X1841527Y495196I1096J1027D01*
G03X1842073I273J292D01*
G02X1844196Y493073I1027J-1096D01*
G03Y492527I292J-273D01*
G02X1842073Y490404I-1096J-1027D01*
G37*
G36*
G01X1852090Y486211D02*
G03X1851560Y486017I-168J-363D01*
G02X1850807Y487913I-1270J593D01*
G03X1851326Y488136I148J372D01*
G02X1852090Y486211I1393J-561D01*
G37*
G36*
G01X1841596Y486223D02*
G03Y485677I292J-273D01*
G02X1839404I-1096J-1027D01*
G03Y486223I-292J273D01*
G02X1841596I1096J1027D01*
G37*
G36*
G01X1842565Y474801D02*
G03X1841935I-315J-246D01*
G02Y476647I-1185J923D01*
G03X1842565I315J246D01*
G02Y474801I1185J-923D01*
G37*
G36*
G01X1844885Y468200D02*
G02X1843928Y466855I445J-1330D01*
G03X1843387Y467225I-400J-4D01*
G02X1844358Y468590I-530J1405D01*
G03X1844885Y468200I400J-11D01*
G37*
G36*
G01X1851740Y493715D02*
G02X1851295Y492096I979J-1140D01*
G03X1850667Y492282I-379J-127D01*
G02X1851106Y493876I-872J1098D01*
G03X1851740Y493715I374J142D01*
G37*
G36*
G01X1867986Y516372D02*
G02X1867938Y517961I-1298J756D01*
G03X1868616Y517981I333J222D01*
G02X1868664Y516392I1298J-756D01*
G03X1867986Y516372I-333J-222D01*
G37*
G36*
G01X1861153Y521422D02*
G02X1859208Y521252I-873J-1222D01*
G03X1859024Y521919I-286J280D01*
G02X1861218Y522111I830J3144D01*
G03X1861153Y521422I167J-363D01*
G37*
G36*
G01X1777969Y620885D02*
G03X1778368Y620402I391J-83D01*
G02X1776931Y619215I32J-1502D01*
G03X1776532Y619698I-391J83D01*
G02X1777969Y620885I-32J1502D01*
G37*
G36*
G01X1804772Y601902D02*
G03X1804178Y601662I-207J-342D01*
G02X1803850Y604145I-3193J841D01*
G03X1804486Y604068I347J199D01*
G02X1804772Y601902I1014J-968D01*
G37*
G36*
G01X1788425Y599446D02*
G03Y598845I263J-300D01*
G02X1786575I-925J-1054D01*
G03Y599446I-263J300D01*
G02X1788425I925J1054D01*
G37*
G36*
G01X1801343Y595110D02*
G03X1801349Y594538I283J-283D01*
G02X1799387Y594518I-971J-1011D01*
G03X1799381Y595090I-283J283D01*
G02X1801343Y595110I971J1011D01*
G37*
G36*
G01X1824276Y594887D02*
G02X1823619Y593554I738J-1192D01*
G03X1823011Y593854I-398J-40D01*
G02X1821611Y593810I-738J1192D01*
G03X1821030Y593534I-189J-353D01*
G02X1820316Y595039I-1376J269D01*
G03X1820897Y595315I189J353D01*
G02X1823668Y595187I1376J-269D01*
G03X1824276Y594887I398J40D01*
G37*
G36*
G01X1815269Y582819D02*
G03X1814723Y582693I-209J-341D01*
G02X1814239Y584782I-1267J807D01*
G03X1814785Y584908I209J341D01*
G02X1815269Y582819I1267J-807D01*
G37*
G36*
G01X1829887Y574715D02*
G03X1829998Y574116I310J-252D01*
G02X1828213Y573785I-698J-1216D01*
G03X1828102Y574384I-310J252D01*
G02X1829887Y574715I698J1216D01*
G37*
G36*
G01X1809558Y573173D02*
G03X1810053Y572797I400J12D01*
G02X1811351Y570417I334J-1362D01*
G03Y569837I275J-290D01*
G02X1809038Y568431I-966J-1016D01*
G03X1808529Y568699I-384J-112D01*
G02X1807134Y571310I-472J1426D01*
G03Y571940I-246J315D01*
G02X1809558Y573173I923J1185D01*
G37*
G36*
G01X1793999Y567398D02*
G03X1793600Y566977I0J-400D01*
G02X1792177Y568400I-1500J-77D01*
G03X1792598Y568799I21J399D01*
G01Y568801D01*
G02X1794000Y567398I1402J-1D01*
G01X1793999D01*
G37*
G36*
G01X1794481Y559433D02*
G03X1794405Y558856I234J-324D01*
G02X1792499Y559105I-1085J-888D01*
G03X1792575Y559682I-234J324D01*
G02X1794481Y559433I1085J888D01*
G37*
G36*
G01X1810785Y555991D02*
G03X1811295Y555682I393J74D01*
G02X1810340Y554016I409J-1341D01*
G03X1809816Y554299I-389J-93D01*
G02X1810785Y555991I-507J1414D01*
G37*
G36*
G01X1829978Y553196D02*
G03X1830604Y553209I308J255D01*
G02Y551391I1196J-909D01*
G03X1829978Y551404I-318J-242D01*
G02Y553196I-1078J896D01*
G37*
G36*
G01X1794888Y551715D02*
G03X1794866Y551116I254J-309D01*
G02X1793012Y551185I-966J-1016D01*
G03X1793034Y551784I-254J309D01*
G02X1794888Y551715I966J1016D01*
G37*
G36*
G01X1835767Y535757D02*
G02Y534043I1233J-857D01*
G03X1835119Y534055I-328J-229D01*
G02Y535745I-1119J845D01*
G03X1835767Y535757I320J241D01*
G37*
G36*
G01X1811291Y544448D02*
G02X1811069Y546068I-1239J655D01*
G03X1811713Y546156I290J275D01*
G02X1811935Y544536I1239J-655D01*
G03X1811291Y544448I-290J-275D01*
G37*
G36*
G01X1830196Y546366D02*
G02X1829424Y547756I-1396J134D01*
G03X1830001Y548090I178J358D01*
G02X1830784Y546679I1499J-91D01*
G03X1830196Y546366I-190J-351D01*
G37*
G36*
G01X1807341Y550014D02*
G02X1806148Y550601I-1141J-814D01*
G03X1806459Y551233I-15J400D01*
G02X1807652Y550646I1141J814D01*
G03X1807341Y550014I15J-400D01*
G37*
G36*
G01X1816995Y551606D02*
G02X1815565I-715J-1206D01*
G03Y552294I-204J344D01*
G02X1816995I715J1206D01*
G03Y551606I204J-344D01*
G37*
G36*
G01X1781692Y566333D02*
G02X1779913Y566036I-692J-1333D01*
G03X1779808Y566667I-290J276D01*
G02X1779449Y569073I692J1333D01*
G03Y569645I-280J286D01*
G02X1781551I1051J1073D01*
G03Y569073I280J-286D01*
G02X1781587Y566964I-1051J-1073D01*
G03X1781692Y566333I290J-276D01*
G37*
G36*
G01X1780383Y580715D02*
G02X1778538Y580654I-883J-1215D01*
G03X1778517Y581285I-256J307D01*
G02X1778400Y583621I883J1215D01*
G03X1778326Y584270I-266J298D01*
G02X1778155Y586619I674J1230D01*
G03X1778143Y587267I-241J320D01*
G02X1779857I857J1233D01*
G03X1779845Y586619I229J-328D01*
G02X1779972Y584490I-845J-1119D01*
G03X1780071Y583844I278J-288D01*
G02X1780362Y581346I-671J-1344D01*
G03X1780383Y580715I256J-307D01*
G37*
G36*
G01X1793376Y584614D02*
G02X1791922Y585280I-1207J-714D01*
G03X1792188Y585890I-70J394D01*
G02X1792039Y587212I1264J812D01*
G03X1791594Y587741I-376J135D01*
G02X1792682Y588687I-245J1381D01*
G03X1793144Y588171I380J-125D01*
G02X1793664Y585214I308J-1470D01*
G03X1793376Y584614I56J-396D01*
G37*
G36*
G01X1786488Y584117D02*
G02X1786266Y585432I-1438J433D01*
G03X1786969Y585541I324J235D01*
G02X1787188Y584246I1331J-441D01*
G03X1786488Y584117I-317J-244D01*
G37*
G36*
G01X1818626Y526496D02*
G03X1818269Y526014I34J-398D01*
G02X1816745Y527201I-1469J-314D01*
G03X1817126Y527666I-14J400D01*
G02X1818626Y526496I1383J227D01*
G37*
G36*
G01X1785015Y521466D02*
G03X1784469Y521445I-262J-302D01*
G02X1782362Y521415I-1069J1055D01*
G03X1781823Y521428I-277J-289D01*
G02X1781876Y523647I-985J1134D01*
G03X1782415Y523634I277J289D01*
G02X1784385I985J-1134D01*
G03X1784931Y523655I262J302D01*
G02X1785015Y521466I1069J-1055D01*
G37*
G36*
G01X1790913Y521002D02*
G03X1790713Y520508I177J-359D01*
G02X1788637Y521348I-1413J-508D01*
G03X1788837Y521842I-177J359D01*
G02X1790913Y521002I1413J508D01*
G37*
G36*
G01X1811406Y514823D02*
G03X1811355Y514260I256J-307D01*
G02X1809302Y514504I-1155J-960D01*
G03X1809383Y515063I-240J320D01*
G02X1811406Y514823I1125J837D01*
G37*
G36*
G01X1828930Y515048D02*
G03X1828909Y514396I221J-333D01*
G02X1826503Y513075I-909J-1196D01*
G03X1826020Y513432I-398J-34D01*
G02X1826131Y516339I-320J1468D01*
G03X1826635Y516633I114J383D01*
G02X1827083Y517405I1464J-334D01*
G03X1827104Y517973I-271J294D01*
G02X1829217Y517895I1096J1027D01*
G03X1829196Y517327I271J-294D01*
G02X1828930Y515048I-1096J-1027D01*
G37*
G36*
G01X1822619Y490442D02*
G03X1822953Y491061I-1J400D01*
G02X1825027Y490756I1172J769D01*
G03X1825041Y490132I257J-306D01*
G02X1825636Y488940I-916J-1202D01*
G01Y488845D01*
X1825627Y488761D01*
G02X1824125Y487418I-1502J169D01*
G01X1819124D01*
G02X1818209Y490132I1J1512D01*
G03X1818223Y490756I-243J318D01*
G02X1820297Y491061I902J1074D01*
G03X1820631Y490442I335J-219D01*
G01X1822619D01*
G37*
G36*
G01X1788019D02*
G03X1788353Y491061I-1J400D01*
G02X1790427Y490756I1172J769D01*
G03X1790441Y490132I257J-306D01*
G02X1791036Y488940I-916J-1202D01*
G01Y488845D01*
X1791027Y488761D01*
G02X1789525Y487418I-1502J169D01*
G01X1784524D01*
G02X1783609Y490132I1J1512D01*
G03X1783623Y490756I-243J318D01*
G02X1785697Y491061I902J1074D01*
G03X1786031Y490442I335J-219D01*
G01X1788019D01*
G37*
G36*
G01X1791283Y477788D02*
G03X1790948Y477170I0J-400D01*
G02X1788951Y477538I-1174J-767D01*
G03X1788979Y478163I-235J324D01*
G02X1789975Y480812I996J1137D01*
G01X1794975D01*
G02X1796486Y479310I-1J-1512D01*
G01Y479215D01*
X1796477Y479131D01*
G02X1795968Y478160I-1502J169D01*
G03X1795994Y477536I262J-302D01*
G02X1793989Y477170I-830J-1130D01*
G03X1793654Y477788I-335J218D01*
G01X1791283D01*
G37*
G36*
G01X1803006Y472444D02*
G03X1802672Y471824I0J-400D01*
G02X1800608Y472136I-1172J-769D01*
G03X1800598Y472761I-255J309D01*
G02X1801525Y475466I927J1194D01*
G01X1806525D01*
G02X1808036Y473965I0J-1511D01*
G01Y473870D01*
X1808027Y473786D01*
G02X1807472Y472777I-1502J169D01*
G03X1807473Y472152I250J-312D01*
G02X1805428Y471824I-873J-1097D01*
G03X1805094Y472444I-334J220D01*
G01X1803006D01*
G37*
G36*
G01X1837457Y467182D02*
G03X1836951Y466813I-106J-385D01*
G02X1835865Y468236I-1401J57D01*
G03X1836355Y468627I90J390D01*
G02X1837457Y467182I1502J3D01*
G37*
G36*
G01X1783132Y466324D02*
G02Y467686I-1225J681D01*
G03X1783832I350J194D01*
G02Y466324I1225J-681D01*
G03X1783132I-350J-194D01*
G37*
G36*
G01X1795730D02*
G02Y467686I-1225J681D01*
G03X1796430I350J194D01*
G02Y466324I1225J-681D01*
G03X1795730I-350J-194D01*
G37*
G36*
G01X1808329D02*
G02Y467686I-1225J681D01*
G03X1809029I350J194D01*
G02Y466324I1225J-681D01*
G03X1808329I-350J-194D01*
G37*
G36*
G01X1820927D02*
G02Y467686I-1225J681D01*
G03X1821627I350J194D01*
G02Y466324I1225J-681D01*
G03X1820927I-350J-194D01*
G37*
G36*
G01X1826434Y475416D02*
G03X1826107Y474786I1J-400D01*
G02X1824222Y475172I-1147J-806D01*
G03X1824281Y475808I-210J340D01*
G02X1825297Y478438I1016J1119D01*
G01X1828802D01*
G03X1829117Y479085I0J400D01*
G02X1830956Y478757I1103J865D01*
G03X1830915Y478104I209J-341D01*
G02X1831478Y476937I-948J-1177D01*
G01Y476842D01*
X1831469Y476758D01*
G02X1829967Y475416I-1502J169D01*
G01X1826434D01*
G37*
G36*
G01X1815889Y479832D02*
G03X1816208Y480473I0J400D01*
G02X1818194Y480220I1117J847D01*
G03X1818219Y479574I248J-314D01*
G02X1818886Y478330I-844J-1254D01*
G01Y478235D01*
X1818877Y478151D01*
G02X1817375Y476808I-1502J169D01*
G01X1812375D01*
G02X1811490Y479545I0J1512D01*
G03X1811493Y480191I-234J324D01*
G02X1813442Y480473I832J1129D01*
G03X1813761Y479832I319J-241D01*
G01X1815889D01*
G37*
G36*
G01X1799619Y490442D02*
G03X1799953Y491061I-1J400D01*
G02X1802265Y492646I1172J769D01*
G03X1802866Y492589I325J233D01*
G02X1805127Y492366I1034J-1089D01*
G03X1805792Y492382I327J230D01*
G02X1808147Y490861I1183J-752D01*
G03X1808481Y490242I335J-219D01*
G01X1810469D01*
G03X1810803Y490861I-1J400D01*
G02X1812877Y490556I1172J769D01*
G03X1812891Y489932I257J-306D01*
G02X1813486Y488740I-916J-1202D01*
G01Y488645D01*
X1813477Y488561D01*
G02X1811975Y487218I-1502J169D01*
G01X1806975D01*
G02X1806059Y489932I0J1512D01*
G03X1806073Y490556I-243J318D01*
G02X1805859Y490781I903J1073D01*
G03X1805196Y490741I-318J-242D01*
G02X1802639Y490684I-1296J759D01*
G03X1802042Y490769I-336J-218D01*
G02X1802027Y490756I-926J1053D01*
G03X1802041Y490132I257J-306D01*
G02X1802636Y488940I-916J-1202D01*
G01Y488845D01*
X1802627Y488761D01*
G02X1801125Y487418I-1502J169D01*
G01X1796124D01*
G02X1795209Y490132I1J1512D01*
G03X1795223Y490756I-243J318D01*
G02X1797297Y491061I902J1074D01*
G03X1797631Y490442I335J-219D01*
G01X1799619D01*
G37*
G36*
G01X1789261Y495772D02*
G02X1786782Y495841I-1216J882D01*
G03X1786116Y495851I-336J-217D01*
G02X1786141Y497514I-1238J850D01*
G03X1786807Y497504I336J217D01*
G02X1789252Y497548I1238J-850D01*
G03X1789897Y497552I321J238D01*
G02X1789906Y495776I1216J-882D01*
G03X1789261Y495772I-321J-238D01*
G37*
G36*
G01X1797553Y514117D02*
G02X1796878Y515400I-1400J83D01*
G03X1797483Y515719I206J343D01*
G02X1798158Y514436I1400J-83D01*
G03X1797553Y514117I-206J-343D01*
G37*
G36*
G01X1835939Y519690D02*
G02X1834672Y520996I-1399J-90D01*
G03X1835107Y521437I37J398D01*
G02X1835155Y522011I1493J164D01*
G03X1834630Y522494I-385J109D01*
G02X1835545Y523489I-530J1406D01*
G03X1836070Y523006I385J-109D01*
G02X1836393Y520112I529J-1406D01*
G03X1835939Y519690I-55J-396D01*
G37*
G36*
G01X1804213Y522569D02*
G02X1802541Y526180I-3227J698D01*
G03X1803122Y526459I188J353D01*
G02X1803575Y527253I1378J-260D01*
G03X1803409Y527942I-264J301D01*
G02X1802573Y528542I342J1359D01*
G03X1802006Y528653I-337J-216D01*
G02X1802379Y530559I-806J1147D01*
G03X1802946Y530448I337J216D01*
G02X1804677Y528248I806J-1147D01*
G03X1804843Y527559I264J-301D01*
G02X1805726Y525521I-343J-1359D01*
G03X1806076Y524927I350J-194D01*
G02X1804931Y522716I0J-1402D01*
G03X1804213Y522569I-327J-231D01*
G37*
G36*
G01X1719091Y593613D02*
G03X1719084Y593049I280J-286D01*
G02X1716954Y593073I-1077J-1047D01*
G03X1716961Y593637I-280J286D01*
G02X1716905Y595671I1076J1047D01*
G03Y596197I-302J263D01*
G02X1719169I1132J987D01*
G03Y595671I302J-263D01*
G02X1719091Y593613I-1132J-988D01*
G37*
G36*
G01X1763216Y590944D02*
G03Y590666I144J-139D01*
G02X1760908I-1154J-1111D01*
G03Y590944I-144J139D01*
G02X1763216I1154J1111D01*
G37*
G36*
G01X1764670Y598328D02*
G02X1764488Y600095I-1170J772D01*
G03X1765112Y600173I281J284D01*
G02X1765298Y598380I1288J-773D01*
G03X1764670Y598328I-294J-272D01*
G37*
G36*
G01X1727086Y615676D02*
G02X1727063Y614062I1255J-825D01*
G03X1726388Y614071I-340J-210D01*
G02X1726411Y615685I-1255J825D01*
G03X1727086Y615676I340J210D01*
G37*
G36*
G01X1731837Y581021D02*
G03X1732383Y581002I283J283D01*
G02X1732305Y578807I985J-1134D01*
G03X1731759Y578826I-283J-283D01*
G02X1731837Y581021I-985J1134D01*
G37*
G36*
G01X1726617Y570629D02*
G03Y569999I246J-315D01*
G02X1724771I-923J-1185D01*
G03Y570629I-246J315D01*
G02X1726617I923J1185D01*
G37*
G36*
G01X1766317Y564724D02*
G03X1766435Y565324I-194J350D01*
G02X1768212Y564976I1094J876D01*
G03X1768094Y564376I194J-350D01*
G02X1766317Y564724I-1094J-876D01*
G37*
G36*
G01X1744336Y563252D02*
G03X1744252Y562664I223J-332D01*
G02X1742264Y562948I-1152J-964D01*
G03X1742348Y563536I-223J332D01*
G02X1742378Y565498I1152J964D01*
G03X1742314Y566087I-299J265D01*
G02X1742069Y568288I886J1213D01*
G03X1742027Y568856I-301J263D01*
G02X1744131Y569012I973J1144D01*
G03X1744173Y568444I301J-263D01*
G02X1744322Y566302I-973J-1144D01*
G03X1744386Y565713I299J-265D01*
G02X1744336Y563252I-886J-1213D01*
G37*
G36*
G01X1739262Y559755D02*
G03X1739418Y559206I348J-198D01*
G02X1737393Y558633I-721J-1318D01*
G03X1737237Y559182I-348J198D01*
G02X1739262Y559755I721J1318D01*
G37*
G36*
G01X1755907Y553120D02*
G03X1755381Y552910I-158J-367D01*
G02X1754593Y554880I-1381J590D01*
G03X1755119Y555090I158J367D01*
G02X1757685Y555423I1381J-590D01*
G03X1758315I315J246D01*
G02Y553577I1185J-923D01*
G03X1757685I-315J-246D01*
G02X1755907Y553120I-1185J923D01*
G37*
G36*
G01X1743894Y534951D02*
G03X1743351I-271J-294D01*
G02Y538631I-1697J1840D01*
G03X1743894I272J294D01*
G02X1747288I1697J-1840D01*
G03X1747831I272J294D01*
G02X1751225I1697J-1840D01*
G03X1751768I271J294D01*
G02X1755162I1697J-1840D01*
G03X1755705I271J294D01*
G02X1759099I1697J-1840D01*
G03X1759642I272J294D01*
G02Y534951I1697J-1840D01*
G03X1759099I-271J-294D01*
G02X1755705I-1697J1840D01*
G03X1755162I-272J-294D01*
G02X1751768I-1697J1840D01*
G03X1751225I-272J-294D01*
G02X1747831I-1697J1840D01*
G03X1747288I-271J-294D01*
G02X1743894I-1697J1840D01*
G37*
G36*
G01X1739196Y549377D02*
G02X1737135Y549281I-980J-1138D01*
G03X1737108Y549862I-288J278D01*
G02X1737496Y552380I980J1138D01*
G03X1737582Y553065I-158J368D01*
G02X1739090Y552875I916J1190D01*
G03X1739004Y552190I158J-368D01*
G02X1739169Y549958I-916J-1190D01*
G03X1739196Y549377I288J-278D01*
G37*
G36*
G01X1772218Y574065D02*
G02X1769297Y574449I-1499J-100D01*
G03X1768937Y574977I-378J129D01*
G02X1770244Y575732I62J1401D01*
G03X1770457Y575443I178J-92D01*
G02X1770688Y575466I264J-1479D01*
G03X1771079Y575892I-8J400D01*
G02X1772609Y574491I1499J101D01*
G03X1772218Y574065I8J-400D01*
G37*
G36*
G01X1745015Y574997D02*
G02X1744745Y573376I985J-997D01*
G03X1744095Y573472I-358J-178D01*
G02X1744369Y575118I-1095J1028D01*
G03X1745015Y574997I365J164D01*
G37*
G36*
G01X1743226Y586649D02*
G02X1741536I-845J-1119D01*
G03X1741524Y587297I-241J320D01*
G02Y589763I857J1233D01*
G03X1741536Y590411I-229J328D01*
G02X1741064Y591050I845J1118D01*
G03X1740371Y591156I-376J-138D01*
G02X1739690Y590658I-1191J915D01*
G03X1739534Y590009I136J-376D01*
G02X1737800Y587624I-1100J-1023D01*
G03X1737289Y587468I-169J-363D01*
G02X1736637Y589606I-1286J776D01*
G03X1737148Y589762I169J363D01*
G02X1737923Y590398I1286J-776D01*
G03X1738079Y591047I-136J376D01*
G02X1738612Y593461I1100J1023D01*
G03X1738842Y593955I-151J371D01*
G02X1738832Y594853I1428J465D01*
G03X1738609Y595335I-383J115D01*
G02X1740593Y596122I602J1376D01*
G03X1740717Y595853I184J-78D01*
G02X1740837Y595810I-446J-1434D01*
G03X1741111Y595979I75J185D01*
G02X1742226Y594496I1398J-110D01*
G03X1741751Y594170I-80J-392D01*
G02X1740837Y593028I-1481J249D01*
G03X1740607Y592534I151J-371D01*
G02X1740681Y592089I-1428J-466D01*
G03X1741068Y592022I200J3D01*
G02X1743226Y590411I1313J-492D01*
G03X1743238Y589763I241J-320D01*
G02Y587297I-857J-1233D01*
G03X1743226Y586649I229J-328D01*
G37*
G36*
G01X1728189Y518029D02*
G03X1727611I-289J-277D01*
G02Y519971I-1011J971D01*
G03X1728189I289J277D01*
G02Y518029I1011J-971D01*
G37*
G36*
G01X1750836Y514598D02*
G03X1750455Y514108I9J-400D01*
G02X1748995Y515189I-1365J-318D01*
G03X1749353Y515696I-27J399D01*
G02X1750836Y514598I1447J404D01*
G37*
G36*
G01X1738822Y502129D02*
G03X1738637Y501585I171J-362D01*
G02X1736658Y502258I-1337J-685D01*
G03X1736843Y502802I-171J362D01*
G02X1738822Y502129I1337J685D01*
G37*
G36*
G01X1768819Y488866D02*
G03X1769153Y489486I0J400D01*
G02X1771227Y489181I1172J769D01*
G03X1771241Y488557I257J-306D01*
G02X1771836Y487365I-916J-1202D01*
G01Y487270D01*
X1771827Y487186D01*
G02X1770325Y485844I-1502J169D01*
G01X1765324D01*
G02X1764409Y488557I1J1511D01*
G03X1764423Y489181I-243J318D01*
G02X1766497Y489486I902J1074D01*
G03X1766831Y488866I334J-220D01*
G01X1768819D01*
G37*
G36*
G01X1745337Y466324D02*
G02Y467686I-1225J681D01*
G03X1746037I350J194D01*
G02Y466324I1225J-681D01*
G03X1745337I-350J-194D01*
G37*
G36*
G01X1757935D02*
G02Y467686I-1225J681D01*
G03X1758635I350J194D01*
G02Y466324I1225J-681D01*
G03X1757935I-350J-194D01*
G37*
G36*
G01X1770534D02*
G02Y467686I-1225J681D01*
G03X1771234I350J194D01*
G02Y466324I1225J-681D01*
G03X1770534I-350J-194D01*
G37*
G36*
G01X1774643Y472912D02*
G02X1773009Y473413I-1143J-812D01*
G03X1773168Y474053I-140J375D01*
G02X1774300Y476566I1132J1002D01*
G01X1779300D01*
G02X1780812Y475065I0J-1512D01*
G01Y474970D01*
X1780802Y474886D01*
G02X1780332Y473951I-1502J169D01*
G03X1780404Y473312I273J-293D01*
G02X1778557Y472912I-704J-1212D01*
G03X1778231Y473544I-326J232D01*
G01X1774969D01*
G03X1774643Y472912I0J-400D01*
G37*
G36*
G01X1762435Y474144D02*
G03X1762094Y473534I0J-400D01*
G02X1760360Y474094I-1194J-734D01*
G03X1760518Y474712I-154J369D01*
G02X1761700Y477166I1182J942D01*
G01X1766700D01*
G02X1768212Y475665I0J-1512D01*
G01Y475570D01*
X1768202Y475486D01*
G02X1767787Y474605I-1502J169D01*
G03X1767903Y473966I288J-278D01*
G02X1766157Y473512I-603J-1266D01*
G03X1765831Y474144I-326J232D01*
G01X1762435D01*
G37*
G36*
G01X1741900Y489266D02*
G02X1743412Y487765I0J-1512D01*
G01Y487670D01*
X1743402Y487586D01*
G02X1743161Y486922I-1502J169D01*
G03X1743363Y486323I334J-221D01*
G02X1741661Y485656I-463J-1323D01*
G03X1741308Y486244I-353J188D01*
G01X1736899D01*
G02X1735592Y486998I1J1511D01*
G03X1734969Y487087I-346J-200D01*
G02X1735180Y488858I-969J1014D01*
G03X1735806Y488798I337J216D01*
G02X1736899Y489266I1093J-1043D01*
G01X1741900D01*
G37*
G36*
G01X1750135Y486344D02*
G03X1749794Y485734I0J-400D01*
G02X1748003Y486268I-1194J-734D01*
G03X1748139Y486887I-171J362D01*
G02X1749300Y489366I1161J968D01*
G01X1754300D01*
G02X1755812Y487865I0J-1512D01*
G01Y487770D01*
X1755802Y487686D01*
G02X1755461Y486887I-1502J169D01*
G03X1755597Y486268I307J-257D01*
G02X1753806Y485734I-597J-1268D01*
G03X1753465Y486344I-341J210D01*
G01X1750135D01*
G37*
G36*
G01X1753575Y494894D02*
G02X1753353Y494911I4J1512D01*
G03X1753142Y494630I-29J-198D01*
G02X1750938Y492996I-1274J-585D01*
G03X1750389Y492979I-266J-299D01*
G02X1748054Y494373I-993J990D01*
G03X1747671Y494888I-383J115D01*
G01X1743124D01*
G02X1742025Y495363I1J1512D01*
G03X1741438Y495358I-291J-274D01*
G02X1741366Y497316I-1038J942D01*
G03X1741952Y497353I276J290D01*
G02X1743125Y497912I1174J-953D01*
G01X1748125D01*
G02X1749636Y496410I-1J-1512D01*
G01Y496315D01*
X1749627Y496231D01*
G02X1749531Y495845I-1502J169D01*
G03X1749790Y495314I372J-147D01*
G02X1750326Y495018I-393J-1345D01*
G03X1750875Y495035I266J299D01*
G02X1751775Y495444I993J-990D01*
G03X1752131Y495961I-26J399D01*
G02X1753575Y497918I1445J445D01*
G01X1758575D01*
G02X1760086Y496416I-1J-1512D01*
G01Y496321D01*
X1760077Y496237D01*
G02X1759588Y495284I-1502J169D01*
G03X1759555Y494724I268J-297D01*
G02X1757206Y494340I-1055J-924D01*
G03X1756837Y494894I-369J154D01*
G01X1753575D01*
G37*
G36*
G01X1729602Y498574D02*
G03X1729310Y497901I0J-400D01*
G02X1726932Y495754I-1171J-1094D01*
G03X1726418Y495829I-301J-263D01*
G02X1723965Y497144I-852J1357D01*
G03X1723570Y497533I-400J-11D01*
G02X1723600Y500737I21J1602D01*
G03X1724002Y501110I3J400D01*
G02X1727187Y501222I1598J-110D01*
G03X1727531Y501113I198J27D01*
G02X1727586Y501169I1105J-1031D01*
G03X1727617Y501710I-278J287D01*
G02X1730021Y502130I1083J890D01*
G03X1730398Y501596I377J-134D01*
G01X1732151D01*
G03X1732523Y502142I0J400D01*
G02X1734798Y501636I1307J508D01*
G03X1734774Y501083I277J-289D01*
G02X1735150Y500095I-1135J-998D01*
G01Y500000D01*
X1735141Y499916D01*
G02X1733639Y498574I-1502J169D01*
G01X1729602D01*
G37*
G36*
G01X1764059Y520415D02*
G02X1764044Y521785I-1344J670D01*
G03X1764756Y521794I354J187D01*
G02X1767258Y522081I1344J-670D01*
G03X1767862Y522067I308J255D01*
G02Y520181I1038J-943D01*
G03X1767258Y520167I-296J-269D01*
G02X1764771Y520424I-1158J957D01*
G03X1764059Y520415I-354J-187D01*
G37*
G36*
G01X1672054Y611661D02*
G02X1670566Y614749I-1676J1095D01*
G03X1671000Y615200I38J398D01*
G02X1675404Y616622I2331J312D01*
G01X1676872Y613881D01*
G03X1677560Y613851I353J188D01*
G02X1679424Y614749I1676J-1095D01*
G03X1679859Y615200I38J398D01*
G02X1684261Y616623I2330J312D01*
G01X1685730Y613881D01*
G03X1686418Y613851I353J188D01*
G02X1688541Y614707I1676J-1095D01*
G03X1689025Y615165I90J390D01*
G02X1690561Y613518I2023J346D01*
G03X1690072Y613067I-94J-388D01*
G02X1687906Y610763I-1978J-311D01*
G03X1687472Y610312I-37J-398D01*
G02X1683070Y608889I-2330J-312D01*
G01X1681600Y611632D01*
G03X1680913Y611662I-352J-189D01*
G02X1679048Y610763I-1677J1094D01*
G03X1678614Y610312I-38J-398D01*
G02X1674210Y608890I-2331J-312D01*
G01X1672742Y611631D01*
G03X1672054Y611661I-353J-188D01*
G37*
G36*
G01Y596700D02*
G02X1670566Y599788I-1676J1095D01*
G03X1671000Y600239I38J398D01*
G02X1675404Y601661I2331J312D01*
G01X1676872Y598920D01*
G03X1677560Y598890I353J188D01*
G02X1679424Y599788I1676J-1095D01*
G03X1679859Y600239I38J398D01*
G02X1684261Y601662I2330J312D01*
G01X1685730Y598920D01*
G03X1686418Y598890I353J188D01*
G02X1688541Y599746I1676J-1095D01*
G03X1689025Y600204I90J390D01*
G02X1690561Y598557I2023J346D01*
G03X1690072Y598106I-94J-388D01*
G02X1687906Y595802I-1978J-311D01*
G03X1687472Y595351I-37J-398D01*
G02X1683070Y593928I-2330J-312D01*
G01X1681600Y596671D01*
G03X1680913Y596701I-352J-189D01*
G02X1679048Y595802I-1677J1094D01*
G03X1678614Y595351I-38J-398D01*
G02X1674210Y593929I-2331J-312D01*
G01X1672742Y596670D01*
G03X1672054Y596700I-353J-188D01*
G37*
G36*
G01X1653605Y592919D02*
G03X1653632Y592348I293J-272D01*
G02X1651621Y592195I-932J-1048D01*
G03X1651561Y592764I-308J255D01*
G02X1650988Y593948I939J1185D01*
G01Y597951D01*
G02X1651672Y599215I1511J-1D01*
G03X1651729Y599838I-220J334D01*
G02X1653522Y599714I971J1012D01*
G03X1653493Y599089I234J-324D01*
G02X1654010Y597960I-994J-1138D01*
G01Y593865D01*
X1654001Y593781D01*
G02X1653605Y592919I-1502J168D01*
G37*
G36*
G01X1659880Y602849D02*
G03X1660485Y602506I400J1D01*
G02X1659876Y600839I715J-1206D01*
G03X1659262Y601030I-378J-131D01*
G02X1656858Y602250I-892J1220D01*
G01Y606251D01*
G02X1659241Y607484I1511J-1D01*
G03X1659856Y607698I231J327D01*
G02X1660485Y606094I1344J-398D01*
G03X1659880Y605751I-205J-344D01*
G01Y602849D01*
G37*
G36*
G01X1701203Y618481D02*
G02X1700252Y616202I4569J-3244D01*
G03X1699700Y616638I-394J69D01*
G02X1700504Y618566I-594J1379D01*
G03X1701203Y618481I372J146D01*
G37*
G36*
G01X1677560Y568969D02*
G02X1679424Y569867I1676J-1095D01*
G03X1679858Y570318I37J398D01*
G02X1684289Y571689I2331J312D01*
G01X1684290Y571687D01*
X1685730Y568999D01*
G03X1686418Y568969I353J188D01*
G02X1688541Y569825I1676J-1095D01*
G03X1689025Y570283I90J390D01*
G02X1690561Y568636I2023J346D01*
G03X1690072Y568185I-94J-388D01*
G02X1687907Y565881I-1978J-311D01*
G03X1687473Y565430I-37J-398D01*
G02X1683042Y564059I-2331J-312D01*
G01X1683041Y564061D01*
X1681600Y566750D01*
G03X1680913Y566780I-352J-189D01*
G02X1679048Y565881I-1677J1094D01*
G03X1678614Y565430I-37J-398D01*
G02X1674191Y564044I-2331J-311D01*
G01X1674190Y564045D01*
X1672742Y566749D01*
G03X1672054Y566779I-353J-188D01*
G02X1670566Y569867I-1676J1095D01*
G03X1671000Y570318I37J398D01*
G02X1675423Y571704I2331J311D01*
G01X1675424Y571703D01*
X1676872Y568999D01*
G03X1677560Y568969I353J188D01*
G37*
G36*
G01X1655997Y562874D02*
G03X1655426Y562604I-181J-357D01*
G02X1653519Y564366I-1466J326D01*
G03X1653743Y564956I-118J382D01*
G02X1655997Y562874I4784J2918D01*
G37*
G36*
G01X1659719Y549009D02*
G02X1657567Y549455I-1253J-629D01*
G03X1657614Y550023I-257J307D01*
G02X1659237Y552422I1141J977D01*
G01X1659269Y552412D01*
X1663239D01*
X1663271Y552422D01*
G02X1664917Y550050I483J-1422D01*
G03X1664980Y549482I310J-253D01*
G02X1662860Y549009I-867J-1102D01*
G03X1662503Y549588I-357J179D01*
G01X1660076D01*
G03X1659719Y549009I0J-400D01*
G37*
G36*
G01X1681661Y549032D02*
G03X1681294Y548474I0J-400D01*
G02X1679893Y546520I-1287J-557D01*
G03X1679469Y546037I-33J-399D01*
G02X1671633Y548350I-4548J-978D01*
G03X1671350Y549032I-283J282D01*
G01X1670777D01*
G03X1670410Y548475I0J-400D01*
G02X1668308Y549065I-1289J-552D01*
G03X1668395Y549632I-232J326D01*
G02X1669600Y552056I1205J912D01*
G01X1674600D01*
G02X1675852Y551390I-1J-1512D01*
G03X1676431Y551301I331J225D01*
G02X1678169I869J-1101D01*
G03X1678748Y551390I248J314D01*
G02X1680000Y552056I1253J-846D01*
G01X1685000D01*
G02X1686512Y550554I0J-1512D01*
G01Y550459D01*
X1686502Y550375D01*
G02X1686419Y550023I-1502J168D01*
G03X1686626Y549523I376J-137D01*
G02X1684666Y548548I-590J-1272D01*
G03X1684275Y549032I-391J84D01*
G01X1681661D01*
G37*
G36*
G01X1707204Y533780D02*
G02X1704820Y534952I0J3011D01*
G03X1704207Y534977I-317J-244D01*
G02X1700203Y534976I-2002J1814D01*
G03X1699590Y534952I-296J-268D01*
G02X1697206Y533780I-2384J1839D01*
G01X1692204D01*
G02X1689820Y534952I0J3011D01*
G03X1689207Y534977I-317J-244D01*
G02Y538605I-2002J1814D01*
G03X1689820Y538630I296J269D01*
G02X1692204Y539802I2384J-1839D01*
G01X1697206D01*
G02X1699590Y538630I0J-3011D01*
G03X1700203Y538606I317J244D01*
G02X1704207Y538605I2002J-1815D01*
G03X1704820Y538630I296J269D01*
G02X1707204Y539802I2384J-1839D01*
G01X1712206D01*
G02X1714590Y538630I0J-3011D01*
G03X1715203Y538606I317J244D01*
G02Y534976I2002J-1815D01*
G03X1714590Y534952I-296J-268D01*
G02X1712206Y533780I-2384J1839D01*
G01X1707204D01*
G37*
G36*
G01X1705350Y548144D02*
G02X1706227Y547863I-1J-1511D01*
G03X1706832Y548044I232J325D01*
G02X1707378Y546361I1308J-506D01*
G03X1706781Y546153I-218J-335D01*
G02X1705348Y545122I-1433J480D01*
G01X1700347D01*
G02X1699636Y545300I1J1511D01*
G03X1699091Y545127I-188J-353D01*
G02X1698427Y547032I-1252J632D01*
G03X1698962Y547235I168J363D01*
G02X1700348Y548144I1386J-602D01*
G01X1705350D01*
G37*
G36*
G01X1678614Y580391D02*
G02X1674191Y579005I-2331J-311D01*
G01X1674190Y579006D01*
X1672742Y581710D01*
G03X1672054Y581740I-353J-188D01*
G02X1670566Y584828I-1676J1095D01*
G03X1671000Y585279I37J398D01*
G02X1675423Y586665I2331J311D01*
G01X1675424Y586664D01*
X1676872Y583960D01*
G03X1677560Y583930I353J188D01*
G02X1679424Y584828I1676J-1095D01*
G03X1679858Y585279I37J398D01*
G02X1684289Y586650I2331J312D01*
G01X1684290Y586648D01*
X1685730Y583960D01*
G03X1686418Y583930I353J188D01*
G02X1688585Y584776I1676J-1095D01*
G03X1689077Y585235I98J388D01*
G02X1690556Y583650I1970J356D01*
G03X1690064Y583191I-98J-388D01*
G02X1687907Y580842I-1970J-356D01*
G03X1687473Y580391I-37J-398D01*
G02X1683042Y579020I-2331J-312D01*
G01X1683041Y579022D01*
X1681600Y581711D01*
G03X1680913Y581741I-352J-189D01*
G02X1679048Y580842I-1677J1094D01*
G03X1678614Y580391I-37J-398D01*
G37*
G36*
G01X1662170Y585272D02*
G02X1660696Y584651I-290J-1372D01*
G03X1660426Y585260I-337J215D01*
G02X1659168Y586750I253J1490D01*
G01Y590751D01*
G02X1660825Y592255I1512J-1D01*
G03X1661244Y592774I38J398D01*
G02X1662500Y591800I1336J426D01*
G03X1662101Y591265I-23J-399D01*
G02X1662192Y590760I-1421J-517D01*
G01Y586665D01*
X1662182Y586581D01*
G02X1661923Y585891I-1502J170D01*
G03X1662170Y585272I329J-227D01*
G37*
G36*
G01X1698834Y519096D02*
G03X1698288I-273J-292D01*
G02Y521288I-1027J1096D01*
G03X1698834I273J292D01*
G02Y519096I1027J-1096D01*
G37*
G36*
G01X1705728Y500548D02*
G03X1705739Y499999I296J-269D01*
G02X1703425Y497782I-1143J-1123D01*
G03X1702908Y497840I-292J-273D01*
G02X1700748Y500156I-903J1323D01*
G03X1700722Y500682I-314J248D01*
G02X1703017Y502917I1152J1113D01*
G03X1703551Y502884I285J280D01*
G02X1705728Y500548I993J-1257D01*
G37*
G36*
G01X1672146Y482573D02*
G03Y482027I292J-273D01*
G02X1669954I-1096J-1027D01*
G03Y482573I-292J273D01*
G02X1672146I1096J1027D01*
G37*
G36*
G01X1666643Y466179D02*
G03X1666090Y466176I-275J-291D01*
G02X1666078Y468349I-1043J1081D01*
G03X1666631Y468352I275J291D01*
G02X1666643Y466179I1043J-1081D01*
G37*
G36*
G01X1653019Y483227D02*
G02X1650787Y483176I-1093J-1030D01*
G03X1650774Y483711I-304J260D01*
G02X1651066Y486012I1093J1030D01*
G03X1651042Y486702I-213J338D01*
G02X1652555Y486754I712J1323D01*
G03X1652579Y486064I213J-338D01*
G02X1653006Y483762I-712J-1323D01*
G03X1653019Y483227I304J-260D01*
G37*
G36*
G01X1688287Y485279D02*
G02X1686668Y485250I-787J-1279D01*
G03X1686656Y485924I-222J333D01*
G02X1688430Y488335I786J1280D01*
G03X1688956I263J302D01*
G02X1690905Y488357I987J-1132D01*
G03X1691431Y488368I257J307D01*
G02X1693827Y487842I1012J-1109D01*
G03X1694520Y487764I368J156D01*
G02X1696680Y487905I1138J-819D01*
G03X1697262Y487904I291J274D01*
G02X1697209Y485901I1092J-1031D01*
G03X1696627Y485932I-306J-258D01*
G02X1694383Y486361I-969J1013D01*
G03X1693688Y486419I-364J-166D01*
G02X1691481Y486105I-1245J840D01*
G03X1690955Y486094I-257J-307D01*
G02X1688956Y486071I-1012J1109D01*
G03X1688430I-263J-302D01*
G02X1688275Y485953I-985J1133D01*
G03X1688287Y485279I222J-333D01*
G37*
G36*
G01X1672992Y495292D02*
G02X1671448Y495365I-833J-1250D01*
G03X1671480Y496050I-190J352D01*
G02X1671378Y498475I833J1250D01*
G03X1671457Y499017I-249J313D01*
G02X1673541Y498775I1149J803D01*
G03X1673493Y498229I266J-299D01*
G02X1673024Y495977I-1180J-929D01*
G03X1672992Y495292I190J-352D01*
G37*
G36*
G01X1694025Y501178D02*
G02X1693013Y499711I385J-1348D01*
G03X1692505Y500062I-399J-34D01*
G02X1690835Y501971I-385J1348D01*
G03X1690389Y502523I-367J160D01*
G02X1688650Y503572I-298J1472D01*
G03X1688105Y503825I-384J-113D01*
G02X1686375Y504205I-605J1375D01*
G03X1685775I-300J-265D01*
G02Y506195I-1125J995D01*
G03X1686375I300J265D01*
G02X1688941Y505623I1125J-995D01*
G03X1689486Y505370I384J113D01*
G02X1691450Y503356I605J-1375D01*
G03X1691880Y502791I362J-171D01*
G02X1693517Y501529I240J-1381D01*
G03X1694025Y501178I399J34D01*
G37*
G36*
G01X1653282Y353673D02*
G03Y353127I292J-273D01*
G02X1651090I-1096J-1027D01*
G03Y353673I-292J273D01*
G02X1653282I1096J1027D01*
G37*
G36*
G01X1654038Y325466D02*
G03X1654016Y324898I270J-295D01*
G02X1652044Y324975I-1025J-957D01*
G03X1652066Y325543I-270J295D01*
G02X1652015Y327399I1025J957D01*
G03X1651978Y327950I-307J256D01*
G02Y330168I1013J1109D01*
G03X1652015Y330719I-270J295D01*
G02X1654094Y330638I1076J899D01*
G03X1654088Y330085I286J-280D01*
G02Y328033I-1097J-1026D01*
G03X1654094Y327480I292J-273D01*
G02X1654038Y325466I-1003J-980D01*
G37*
G36*
G01X1591944Y619849D02*
G03X1592499Y619838I283J283D01*
G02X1592456Y617675I1020J-1102D01*
G03X1591901Y617686I-283J-283D01*
G02X1591944Y619849I-1020J1102D01*
G37*
G36*
G01X1602523Y617154D02*
G03X1601977I-273J-292D01*
G02Y619346I-1027J1096D01*
G03X1602523I273J292D01*
G02Y617154I1027J-1096D01*
G37*
G36*
G01X1652380Y609115D02*
X1652371Y609031D01*
G02X1649358Y609200I-1502J169D01*
G01Y614201D01*
G02X1652380Y614210I1511J-1D01*
G01Y609115D01*
G37*
G36*
G01X1624810Y611661D02*
G02X1623322Y614749I-1676J1095D01*
G03X1623756Y615200I37J398D01*
G02X1628179Y616586I2331J311D01*
G01X1628180Y616585D01*
X1629628Y613881D01*
G03X1630316Y613851I353J188D01*
G02X1632180Y614749I1676J-1095D01*
G03X1632614Y615200I37J398D01*
G02X1637045Y616571I2331J312D01*
G01X1637046Y616569D01*
X1638486Y613881D01*
G03X1639174Y613851I353J188D01*
G02X1641297Y614707I1676J-1095D01*
G03X1641781Y615165I90J390D01*
G02X1643317Y613518I2023J346D01*
G03X1642828Y613067I-94J-388D01*
G02X1640663Y610763I-1978J-311D01*
G03X1640229Y610312I-37J-398D01*
G02X1635798Y608941I-2331J-312D01*
G01X1635797Y608943D01*
X1634356Y611632D01*
G03X1633669Y611662I-352J-189D01*
G02X1631804Y610763I-1677J1094D01*
G03X1631370Y610312I-37J-398D01*
G02X1626947Y608926I-2331J-311D01*
G01X1626946Y608927D01*
X1625498Y611631D01*
G03X1624810Y611661I-353J-188D01*
G37*
G36*
G01X1603405Y603012D02*
G03X1602884Y602671I-123J-381D01*
G02X1602083Y604082I-1395J141D01*
G03X1602367Y604285I85J181D01*
G02X1602358Y604449I1502J165D01*
G01Y608451D01*
G02X1602404Y608824I1512J3D01*
G03X1602046Y609322I-387J99D01*
G02X1603524Y610441I104J1398D01*
G03X1603906Y609961I392J-80D01*
G02X1605380Y608460I-37J-1511D01*
G01Y604365D01*
X1605371Y604281D01*
G02X1603405Y603012I-1502J169D01*
G37*
G36*
G01X1614804Y598842D02*
G03X1615081Y598349I385J-108D01*
G02X1613330Y597298I-381J-1349D01*
G03X1613025Y597774I-391J85D01*
G02X1611838Y599250I324J1476D01*
G01Y603251D01*
G02X1614860Y603260I1511J-1D01*
G01Y599165D01*
X1614851Y599081D01*
G02X1614804Y598842I-1502J171D01*
G37*
G36*
G01X1630316Y598890D02*
G02X1632180Y599788I1676J-1095D01*
G03X1632614Y600239I37J398D01*
G02X1637045Y601610I2331J312D01*
G01X1637046Y601608D01*
X1638486Y598920D01*
G03X1639174Y598890I353J188D01*
G02X1641297Y599746I1676J-1095D01*
G03X1641781Y600204I90J390D01*
G02X1643317Y598557I2023J346D01*
G03X1642828Y598106I-94J-388D01*
G02X1640663Y595802I-1978J-311D01*
G03X1640229Y595351I-37J-398D01*
G02X1635798Y593980I-2331J-312D01*
G01X1635797Y593982D01*
X1634356Y596671D01*
G03X1633669Y596701I-352J-189D01*
G02X1631804Y595802I-1677J1094D01*
G03X1631370Y595351I-37J-398D01*
G02X1626947Y593965I-2331J-311D01*
G01X1626946Y593966D01*
X1625498Y596670D01*
G03X1624810Y596700I-353J-188D01*
G02X1623322Y599788I-1676J1095D01*
G03X1623756Y600239I37J398D01*
G02X1628179Y601625I2331J311D01*
G01X1628180Y601624D01*
X1629628Y598920D01*
G03X1630316Y598890I353J188D01*
G37*
G36*
G01X1603365Y591344D02*
G03X1602838Y591095I-146J-372D01*
G02X1601896Y592872I-1334J431D01*
G03X1602408Y593256I112J384D01*
G01Y595556D01*
G03X1601844Y595921I-400J0D01*
G02X1602409Y598017I-574J1279D01*
G03X1602982Y597936I325J233D01*
G02X1605430Y596760I937J-1186D01*
G01Y592665D01*
X1605421Y592581D01*
G02X1603365Y591344I-1502J169D01*
G37*
G36*
G01X1619461Y618783D02*
G02X1618281Y617791I239J-1483D01*
G03X1617839Y618317I-378J131D01*
G02X1619019Y619309I-239J1483D01*
G03X1619461Y618783I378J-131D01*
G37*
G36*
G01X1630316Y568969D02*
G02X1632180Y569867I1676J-1095D01*
G03X1632614Y570318I37J398D01*
G02X1637045Y571689I2331J312D01*
G01X1637046Y571687D01*
X1638486Y568999D01*
G03X1639174Y568969I353J188D01*
G02X1641297Y569825I1676J-1095D01*
G03X1641781Y570283I90J390D01*
G02X1643317Y568636I2023J346D01*
G03X1642828Y568185I-94J-388D01*
G02X1640663Y565881I-1978J-311D01*
G03X1640229Y565430I-37J-398D01*
G02X1635798Y564059I-2331J-312D01*
G01X1635797Y564061D01*
X1634356Y566750D01*
G03X1633669Y566780I-352J-189D01*
G02X1631804Y565881I-1677J1094D01*
G03X1631370Y565430I-37J-398D01*
G02X1626947Y564044I-2331J-311D01*
G01X1626946Y564045D01*
X1625498Y566749D01*
G03X1624810Y566779I-353J-188D01*
G02X1623322Y569867I-1676J1095D01*
G03X1623756Y570318I37J398D01*
G02X1628179Y571704I2331J311D01*
G01X1628180Y571703D01*
X1629628Y568999D01*
G03X1630316Y568969I353J188D01*
G37*
G36*
G01X1651158Y581915D02*
G03X1650567Y582267I-400J0D01*
G02X1651255Y583859I-667J1233D01*
G03X1651857Y583625I387J103D01*
G02X1654180Y582360I812J-1275D01*
G01Y578265D01*
X1654171Y578181D01*
G02X1653580Y577144I-1502J169D01*
G03X1653528Y576553I241J-319D01*
G02X1651596Y576672I-1028J-953D01*
G03X1651617Y577265I-258J306D01*
G02X1651158Y578350I1053J1085D01*
G01Y581915D01*
G37*
G36*
G01X1604482Y581437D02*
G03X1603856Y581766I-400J-1D01*
G02X1604272Y583625I-796J1154D01*
G03X1604906Y583549I346J201D01*
G02X1607506Y582510I1088J-1049D01*
G01Y578415D01*
X1607496Y578331D01*
G02X1604953Y577404I-1502J169D01*
G03X1604332Y577315I-275J-290D01*
G02X1603869Y579205I-1212J705D01*
G03X1604482Y579543I213J338D01*
G01Y581437D01*
G37*
G36*
G01X1631370Y580391D02*
G02X1626947Y579005I-2331J-311D01*
G01X1626946Y579006D01*
X1625498Y581710D01*
G03X1624810Y581740I-353J-188D01*
G02X1623322Y584828I-1676J1095D01*
G03X1623756Y585279I37J398D01*
G02X1628179Y586665I2331J311D01*
G01X1628180Y586664D01*
X1629628Y583960D01*
G03X1630316Y583930I353J188D01*
G02X1632180Y584828I1676J-1095D01*
G03X1632614Y585279I37J398D01*
G02X1637045Y586650I2331J312D01*
G01X1637046Y586648D01*
X1638486Y583960D01*
G03X1639174Y583930I353J188D01*
G02X1641341Y584776I1676J-1095D01*
G03X1641833Y585235I98J388D01*
G02X1643312Y583650I1970J356D01*
G03X1642820Y583191I-98J-388D01*
G02X1640663Y580842I-1970J-356D01*
G03X1640229Y580391I-37J-398D01*
G02X1635798Y579020I-2331J-312D01*
G01X1635797Y579022D01*
X1634356Y581711D01*
G03X1633669Y581741I-352J-189D01*
G02X1631804Y580842I-1677J1094D01*
G03X1631370Y580391I-37J-398D01*
G37*
G36*
G01X1614021Y585835D02*
G02X1613992Y585667I-1501J173D01*
G03X1614293Y585452I195J-45D01*
G02X1613628Y584236I737J-1193D01*
G03X1613080Y584600I-400J-7D01*
G02X1611008Y586003I-561J1404D01*
G01Y590005D01*
G02X1612097Y591455I1511J-1D01*
G03X1612371Y591947I-111J384D01*
G02X1614192Y591004I1350J378D01*
G03X1613948Y590497I134J-377D01*
G02X1614030Y590014I-1429J-491D01*
G01Y585919D01*
X1614021Y585835D01*
G37*
G36*
G01X1638820Y528684D02*
G03X1639021Y528123I352J-190D01*
G02X1636529Y527668I-890J-2177D01*
G03X1636518Y528263I-273J293D01*
G02X1638820Y528684I982J1137D01*
G37*
G36*
G01X1629241Y519549D02*
G03X1628648Y519472I-262J-302D01*
G02X1628444Y521404I-1241J846D01*
G03X1629040Y521453I276J289D01*
G02X1629241Y519549I1119J-844D01*
G37*
G36*
G01X1650104Y503802D02*
G03X1649565Y503689I-210J-340D01*
G02X1649048Y505863I-1235J855D01*
G03X1649579Y506005I190J352D01*
G02X1650104Y503802I1365J-839D01*
G37*
G36*
G01X1642145Y488084D02*
G02X1640987Y489147I-1364J-324D01*
G03X1641432Y489648I59J395D01*
G02X1642607Y488570I1448J399D01*
G03X1642145Y488084I-73J-393D01*
G37*
G36*
G01X1641020Y497133D02*
G02X1640560Y495429I943J-1169D01*
G03X1639948Y495608I-374J-143D01*
G02X1640401Y497287I-835J1126D01*
G03X1641020Y497133I368J157D01*
G37*
G36*
G01X1643598Y506571D02*
G02X1643192Y505142I1053J-1071D01*
G03X1642523Y505332I-388J-95D01*
G02X1640001Y506092I-1053J1071D01*
G03X1639562Y506406I-391J-83D01*
G02X1640746Y508169I-168J1392D01*
G03X1641203Y507881I386J106D01*
G02X1642929Y506761I267J-1478D01*
G03X1643598Y506571I388J95D01*
G37*
G36*
G01X1644636Y515562D02*
G02X1644608Y514234I1333J-692D01*
G03X1643896Y514259I-362J-169D01*
G02X1643923Y515567I-1226J680D01*
G03X1644636Y515562I358J179D01*
G37*
G36*
G01X1641076Y458558D02*
G03X1641055Y457969I260J-304D01*
G02X1639024Y458042I-1055J-1069D01*
G03X1639045Y458631I-260J304D01*
G02X1641076Y458558I1055J1069D01*
G37*
G36*
G01X1647623Y449128D02*
G03X1647634Y448602I307J-257D01*
G02X1645371Y448552I-1110J-1012D01*
G03X1645360Y449078I-307J257D01*
G02X1645330Y451069I1109J1012D01*
G03X1645326Y451595I-303J261D01*
G02X1647590Y451611I1125J995D01*
G03X1647594Y451085I303J-261D01*
G02X1647623Y449128I-1125J-995D01*
G37*
G36*
G01X1640632Y434713D02*
G03Y434187I302J-263D01*
G02X1638368I-1132J-987D01*
G03Y434713I-302J263D01*
G02X1640632I1132J987D01*
G37*
G36*
G01X1613619Y410798D02*
G03X1613687Y410204I298J-267D01*
G02X1611706Y409976I-862J-1230D01*
G03X1611638Y410570I-298J267D01*
G02X1613619Y410798I862J1230D01*
G37*
G36*
G01X1600934Y399614D02*
G03X1600499Y399190I-36J-399D01*
G02X1599226Y400496I-1399J-90D01*
G03X1599661Y400920I36J399D01*
G02X1600934Y399614I1399J90D01*
G37*
G36*
G01X1629507Y379446D02*
G03X1629356Y380043I-323J236D01*
G02X1631249Y380565I644J1357D01*
G03X1631425Y379975I333J-222D01*
G02X1631825Y377269I-625J-1475D01*
G03X1631819Y376659I256J-308D01*
G02X1629911Y376593I-919J-1059D01*
G03X1629862Y377201I-283J283D01*
G02X1629507Y379446I938J1299D01*
G37*
G36*
G01X1597266Y379733D02*
G03X1596708Y380100I-400J0D01*
G02X1597452Y381908I-557J1286D01*
G03X1598033Y381716I371J149D01*
G02X1600490Y380354I845J-1372D01*
G01Y376261D01*
X1600480Y376176D01*
G02X1598084Y374944I-1602J170D01*
G03X1597506Y374715I-196J-348D01*
G02X1596711Y376427I-1338J419D01*
G03X1597266Y376795I155J369D01*
G01Y379733D01*
G37*
G36*
G01X1609758Y376870D02*
G03X1610265Y376485I400J0D01*
G02X1611178Y373839I377J-1350D01*
G03X1610982Y373273I152J-370D01*
G02X1609225Y373880I-1221J-689D01*
G03X1609421Y374446I-152J370D01*
G02X1609377Y374530I1219J692D01*
G03X1608843Y374718I-361J-172D01*
G02X1606534Y376171I-697J1453D01*
G01Y380322D01*
G02X1608956Y381715I1612J0D01*
G03X1609528Y381911I201J346D01*
G02X1610306Y380086I1300J-524D01*
G03X1609758Y379715I-148J-371D01*
G01Y376870D01*
G37*
G36*
G01X1631437Y356650D02*
G03X1631479Y356068I293J-271D01*
G02X1629485Y355975I-945J-1168D01*
G03X1629472Y356559I-280J286D01*
G02X1629371Y358547I936J1044D01*
G03X1629370Y359087I-296J269D01*
G02X1629291Y361026I1106J1016D01*
G03X1629262Y361551I-315J246D01*
G02X1629168Y363543I1075J1049D01*
G03X1629147Y364068I-312J250D01*
G02X1629140Y366121I1093J1030D01*
G03X1629131Y366675I-293J272D01*
G02X1631300Y366708I1069J1055D01*
G03X1631309Y366154I293J-272D01*
G02X1631409Y364156I-1069J-1055D01*
G03X1631430Y363631I312J-250D01*
G02X1631522Y361677I-1093J-1031D01*
G03X1631551Y361152I315J-246D01*
G02X1631525Y359028I-1075J-1049D01*
G03X1631494Y358489I279J-286D01*
G02X1631437Y356650I-1086J-887D01*
G37*
G36*
G01X1644262Y349701D02*
G02X1642472Y350032I-1112J-1009D01*
G03X1642588Y350658I-180J357D01*
G02X1644378Y350327I1112J1009D01*
G03X1644262Y349701I180J-357D01*
G37*
G36*
G01X1609421Y356560D02*
G02X1608269Y357880I-1401J-60D01*
G03X1608739Y358290I71J394D01*
G02X1609891Y356970I1401J60D01*
G03X1609421Y356560I-71J-394D01*
G37*
G36*
G01X1651914Y358434D02*
G02X1650451Y359275I-1290J-550D01*
G03X1650756Y359857I-50J397D01*
G02X1650574Y360600I1430J744D01*
G01Y365601D01*
G02X1650714Y366255I1612J-3D01*
G03X1650378Y366817I-366J163D01*
G02X1651801Y367745I102J1398D01*
G03X1652180Y367212I377J-133D01*
G02X1653798Y365610I6J-1612D01*
G01Y360515D01*
X1653788Y360430D01*
G02X1652263Y358990I-1602J170D01*
G03X1651914Y358434I19J-399D01*
G37*
G36*
G01X1642113Y359296D02*
G02X1640804Y358362I13J-1402D01*
G03X1640395Y358894I-377J133D01*
G02X1638654Y360500I-130J1606D01*
G01Y365501D01*
G02X1640396Y367106I1612J-1D01*
G03X1640803Y367646I33J399D01*
G02X1640821Y368685I1311J497D01*
G03X1640362Y369229I-369J155D01*
G02X1641443Y370091I-361J1561D01*
G03X1641872Y369523I360J-174D01*
G02X1642098Y366740I242J-1381D01*
G03X1641730Y366173I-5J-400D01*
G02X1641878Y365510I-1464J-675D01*
G01Y360415D01*
X1641868Y360330D01*
G02X1641743Y359856I-1602J169D01*
G03X1642113Y359296I367J-160D01*
G37*
G36*
G01X1608786Y360618D02*
G02X1608339Y361947I-1374J277D01*
G03X1608996Y362167I265J300D01*
G02X1609443Y360838I1374J-277D01*
G03X1608786Y360618I-265J-300D01*
G37*
G36*
G01X1631043Y393157D02*
G02X1629681Y393119I-644J-1357D01*
G03X1629651Y393835I-192J351D01*
G02X1629663Y396770I649J1465D01*
G03X1629703Y397484I-159J367D01*
G02X1629433Y399715I697J1216D01*
G03X1629450Y400277I-276J290D01*
G02X1631525Y400157I1100J1023D01*
G03X1631477Y399597I260J-304D01*
G02X1631025Y397445I-1077J-897D01*
G03X1631023Y396730I178J-358D01*
G02X1631031Y393875I-723J-1430D01*
G03X1631043Y393157I183J-356D01*
G37*
G36*
G01X1621029Y337649D02*
G03Y337123I302J-263D01*
G02X1618765I-1132J-987D01*
G03Y337649I-302J263D01*
G02Y339623I1132J987D01*
G03Y340149I-302J263D01*
G02X1621029I1132J987D01*
G03Y339623I302J-263D01*
G02Y337649I-1132J-987D01*
G37*
G36*
G01X1640545Y311748D02*
G03Y311222I302J-263D01*
G02X1638281I-1132J-987D01*
G03Y311748I-302J263D01*
G02X1640545I1132J987D01*
G37*
G36*
G01X1638016Y304130D02*
G03X1638028Y303604I307J-256D01*
G02X1635767Y303549I-1106J-1016D01*
G03X1635755Y304075I-307J256D01*
G02X1638016Y304130I1106J1016D01*
G37*
G36*
G01X1637954Y293959D02*
G03Y293433I302J-263D01*
G02X1635690I-1132J-987D01*
G03Y293959I-302J263D01*
G02X1635732Y295979I1132J987D01*
G03X1635753Y296504I-291J275D01*
G02X1638015Y296411I1172J940D01*
G03X1637994Y295886I291J-275D01*
G02X1637954Y293959I-1172J-940D01*
G37*
G36*
G01X1625181Y272297D02*
G03X1624583Y272290I-296J-269D01*
G02X1624557Y274285I-1136J983D01*
G03X1625155Y274292I296J269D01*
G02X1625181Y272297I1136J-983D01*
G37*
G36*
G01X1621207Y256511D02*
G03X1621209Y255897I257J-306D01*
G02X1619283Y255890I-959J-1156D01*
G03X1619281Y256504I-257J306D01*
G02X1621207Y256511I959J1156D01*
G37*
G36*
G01X1597653Y247276D02*
G03X1598245Y247267I300J264D01*
G02X1598217Y245384I1025J-957D01*
G03X1597625Y245393I-300J-264D01*
G02X1597653Y247276I-1025J957D01*
G37*
G36*
G01X1603806Y269550D02*
G02X1602781Y268530I416J-1443D01*
G03X1602286Y269027I-384J113D01*
G02X1603311Y270047I-416J1443D01*
G03X1603806Y269550I384J-113D01*
G37*
G36*
G01X1637746Y275730D02*
G02X1635622I-1062J-915D01*
G03X1635606Y276269I-303J261D01*
G02X1635552Y278302I1078J1046D01*
G03Y278828I-302J263D01*
G02X1635955Y281128I1132J987D01*
G03Y281828I-194J350D01*
G02X1637413I729J1313D01*
G03Y281128I194J-350D01*
G02X1637816Y278828I-729J-1313D01*
G03Y278302I302J-263D01*
G02X1637762Y276269I-1132J-987D01*
G03X1637746Y275730I287J-278D01*
G37*
G36*
G01X1553606Y608496D02*
G03X1554131Y608390I321J238D01*
G02X1553694Y606204I769J-1290D01*
G03X1553169Y606310I-321J-238D01*
G02X1553606Y608496I-769J1290D01*
G37*
G36*
G01X1589031Y604486D02*
G03X1588477I-277J-288D01*
G02X1586494Y606469I-973J1010D01*
G03Y607023I-288J277D01*
G02X1588477Y609006I1010J973D01*
G03X1589031I277J288D01*
G02X1589159Y609114I966J-1016D01*
G03X1589240Y609671I-241J319D01*
G02X1591355Y609247I1290J949D01*
G03X1591215Y608702I206J-343D01*
G02X1591014Y607023I-1211J-707D01*
G03Y606469I288J-277D01*
G02X1589031Y604486I-1010J-973D01*
G37*
G36*
G01X1545196Y606629D02*
G03X1545556Y606208I399J-23D01*
G02X1543908Y604803I-149J-1495D01*
G03X1543548Y605224I-399J23D01*
G02X1542265Y606265I149J1495D01*
G03X1541732Y606513I-381J-122D01*
G02X1542594Y608357I-570J1390D01*
G03X1543127Y608109I381J122D01*
G02X1545196Y606629I570J-1390D01*
G37*
G36*
G01X1572237Y600367D02*
G03X1571718Y600360I-255J-308D01*
G02X1571683Y602796I-1058J1203D01*
G03X1572202Y602803I255J308D01*
G02X1572237Y600367I1058J-1203D01*
G37*
G36*
G01X1554589Y590129D02*
G03X1554011I-289J-277D01*
G02Y592071I-1011J971D01*
G03X1554589I289J277D01*
G02Y590129I1011J-971D01*
G37*
G36*
G01X1539519Y600344D02*
G02X1539431Y601974I-1182J754D01*
G03X1540088Y602022I312J250D01*
G02X1540300Y602302I1295J-761D01*
G03X1538917Y603050I-1300J-752D01*
G02X1538496Y603424I-22J399D01*
G03X1537852Y605357I-3994J-257D01*
G03X1537920Y605944I-3931J753D01*
G03X1538053Y606144I-1180J929D01*
G02X1538744Y606157I349J-195D01*
G03X1540834Y605667I1285J778D01*
G02X1541444Y605273I214J-338D01*
G03X1541776Y603029I3963J-560D01*
G03X1541399Y602764I723J-1430D01*
G02X1540178Y600367I-15J-1502D01*
G03X1539519Y600344I-322J-238D01*
G37*
G36*
G01X1545453Y616069D02*
G02X1544319Y616875I-1403J-773D01*
G03X1544742Y617454I68J394D01*
G02X1545860Y616658I1334J690D01*
G03X1545453Y616069I-57J-396D01*
G37*
G36*
G01X1544173Y584628D02*
G03X1543627I-273J-292D01*
G02Y586820I-1027J1096D01*
G03X1544173I273J292D01*
G02Y584628I1027J-1096D01*
G37*
G36*
G01X1586703Y396411D02*
G03X1586141Y396408I-279J-286D01*
G02X1586130Y398403I-991J992D01*
G03X1586692Y398406I279J286D01*
G02X1586703Y396411I991J-992D01*
G37*
G36*
G01X1571657Y384060D02*
G03X1571944Y383585I390J-89D01*
G02X1570217Y382538I-359J-1355D01*
G03X1569930Y383013I-390J89D01*
G02X1571657Y384060I359J1355D01*
G37*
G36*
G01X1568092Y364806D02*
G03Y364228I277J-289D01*
G02X1566150I-971J-1011D01*
G03Y364806I-277J289D01*
G02X1568092I971J1011D01*
G37*
G36*
G01X1544362Y362485D02*
G03X1544378Y361946I303J-261D01*
G02X1542222I-1078J-1046D01*
G03X1542238Y362485I-287J278D01*
G02X1544362I1062J915D01*
G37*
G36*
G01X1534878Y361828D02*
G03X1534893Y361302I309J-254D01*
G02X1532631Y361238I-1103J-1019D01*
G03X1532616Y361764I-309J254D01*
G02X1534878Y361828I1103J1019D01*
G37*
G36*
G01X1559984Y361960D02*
G03X1560003Y361362I275J-291D01*
G02X1557931Y361341I-1024J-1232D01*
G03X1557939Y361939I-261J303D01*
G02X1557998Y364212I1011J1111D01*
G03X1558022Y364809I-254J309D01*
G02X1559936Y364777I974J1008D01*
G03X1559940Y364179I268J-297D01*
G02X1559984Y361960I-990J-1130D01*
G37*
G36*
G01X1571900Y361457D02*
G03X1572073Y360906I350J-193D01*
G02X1570222Y360327I-623J-1256D01*
G03X1570049Y360878I-350J193D01*
G02X1571900Y361457I623J1256D01*
G37*
G36*
G01X1539569Y360921D02*
G03X1539590Y360396I312J-250D01*
G02X1537328Y360303I-1090J-1033D01*
G03X1537307Y360828I-312J250D01*
G02X1537382Y362968I1090J1033D01*
G03X1537354Y363582I-270J295D01*
G02X1539193Y363710I846J1118D01*
G03X1539249Y363098I283J-283D01*
G02X1539569Y360921I-852J-1237D01*
G37*
G36*
G01X1588073Y357304D02*
G03X1587527I-273J-292D01*
G02Y359496I-1027J1096D01*
G03X1588073I273J292D01*
G02Y357304I1027J-1096D01*
G37*
G36*
G01X1539574Y352267D02*
G03Y351721I292J-273D01*
G02X1537382I-1096J-1027D01*
G03Y352267I-292J273D01*
G02Y354321I1096J1027D01*
G03Y354867I-292J273D01*
G02X1539574I1096J1027D01*
G03Y354321I292J-273D01*
G02Y352267I-1096J-1027D01*
G37*
G36*
G01X1588960Y351816D02*
G02Y350175I1258J-820D01*
G03X1588290I-335J-219D01*
G02Y351816I-1258J821D01*
G03X1588960I335J219D01*
G37*
G36*
G01X1543995Y353874D02*
G02X1542591Y353620I-467J-1428D01*
G03X1542465Y354312I-250J312D01*
G02X1544285Y356393I467J1428D01*
G03X1544968Y356331I360J174D01*
G02X1544829Y354793I1214J-885D01*
G03X1544146Y354855I-360J-174D01*
G02X1543869Y354566I-1213J886D01*
G03X1543995Y353874I250J-312D01*
G37*
G36*
G01X1576954Y360938D02*
G02X1575455Y361078I-881J-1338D01*
G03X1575541Y361767I-154J369D01*
G02X1576998Y361632I839J1123D01*
G03X1576954Y360938I176J-360D01*
G37*
G36*
G01X1556464Y340062D02*
G03X1555886I-289J-276D01*
G02Y342138I-1086J1038D01*
G03X1556464I289J276D01*
G02Y340062I1086J-1038D01*
G37*
G36*
G01X1564815Y340077D02*
G03X1564185I-315J-246D01*
G02Y341923I-1185J923D01*
G03X1564815I315J246D01*
G02Y340077I1185J-923D01*
G37*
G36*
G01X1582772Y337666D02*
G03X1582218Y337657I-272J-293D01*
G02X1579665Y339528I-1129J1137D01*
G03X1579532Y340043I-355J183D01*
G02X1581738Y340684I833J1250D01*
G03X1581901Y340177I365J-162D01*
G02X1582241Y339909I-813J-1381D01*
G03X1582795Y339888I288J278D01*
G02X1582772Y337666I999J-1121D01*
G37*
G36*
G01X1570307Y333115D02*
G03Y332569I292J-273D01*
G02X1568115I-1096J-1027D01*
G03Y333115I-292J273D01*
G02X1570307I1096J1027D01*
G37*
G36*
G01X1548685Y333048D02*
G03X1548799Y332513I342J-207D01*
G02X1546759Y332014I-799J-1152D01*
G03X1546614Y332542I-354J187D01*
G02X1546275Y332825I783J1282D01*
G03X1545738Y332881I-299J-265D01*
G02X1545895Y334999I-834J1127D01*
G03X1546435Y334975I283J283D01*
G02X1548685Y333048I963J-1152D01*
G37*
G36*
G01X1543599Y324505D02*
G03X1543935Y324083I399J-27D01*
G02X1542210Y322790I-235J-1483D01*
G03X1541899Y323231I-397J50D01*
G02X1543599Y324505I301J1369D01*
G37*
G36*
G01X1590861Y323534D02*
G03X1591415Y323334I369J154D01*
G02X1590725Y321421I695J-1332D01*
G03X1590171Y321621I-369J-154D01*
G02X1590861Y323534I-695J1332D01*
G37*
G36*
G01X1549220Y318524D02*
G03X1549475Y318025I382J-120D01*
G02X1547593Y317126I-475J-1425D01*
G03X1547366Y317638I-374J140D01*
G02X1549220Y318524I516J1304D01*
G37*
G36*
G01X1568271Y314778D02*
G03X1568629Y314283I388J-96D01*
G02X1567163Y313224I-105J-1398D01*
G03X1566805Y313719I-388J96D01*
G02X1565900Y314144I104J1398D01*
G03X1565346Y314165I-288J-277D01*
G02X1565421Y316183I-935J1045D01*
G03X1565975Y316162I288J277D01*
G02X1568271Y314778I935J-1045D01*
G37*
G36*
G01X1565403Y310076D02*
G03X1565412Y309493I278J-287D01*
G02X1563411Y309513I-1012J-1110D01*
G03X1563431Y310096I-264J301D01*
G02X1565403Y310076I996J987D01*
G37*
G36*
G01X1561216Y309439D02*
G03X1561300Y308885I324J-234D01*
G02X1559181Y308561I-900J-1202D01*
G03X1559097Y309115I-324J234D01*
G02X1561216Y309439I900J1202D01*
G37*
G36*
G01X1537484Y305414D02*
G03X1537946Y305119I388J98D01*
G02X1536868Y303322I260J-1378D01*
G03X1536390Y303590I-381J-120D01*
G02X1537484Y305414I-363J1458D01*
G37*
G36*
G01X1566255Y302632D02*
G03X1566257Y302043I272J-294D01*
G02X1564224Y302036I-1013J-1109D01*
G03X1564222Y302625I-272J294D01*
G02X1566255Y302632I1013J1109D01*
G37*
G36*
G01X1584611Y302109D02*
G03Y301571I296J-269D01*
G02X1582389I-1111J-1011D01*
G03Y302109I-296J269D01*
G02X1584611I1111J1011D01*
G37*
G36*
G01X1579694Y292517D02*
G03X1579730Y291960I304J-260D01*
G02X1577726Y291833I-940J-1040D01*
G03X1577690Y292390I-304J260D01*
G02X1579694Y292517I940J1040D01*
G37*
G36*
G01X1534897Y287640D02*
G03X1534898Y287072I282J-284D01*
G02X1532874Y287013I-984J-999D01*
G03X1532843Y287581I-296J269D01*
G02X1534897Y287640I996J1125D01*
G37*
G36*
G01X1548006Y287663D02*
G03X1548358Y287223I398J-43D01*
G02X1546805Y285979I-159J-1393D01*
G03X1546453Y286419I-398J43D01*
G02X1548006Y287663I159J1393D01*
G37*
G36*
G01X1580173Y283753D02*
G03X1579634Y283732I-258J-306D01*
G02X1579611Y285888I-1057J1067D01*
G03X1580151Y285878I275J290D01*
G02X1580173Y283753I926J-1053D01*
G37*
G36*
G01X1572936Y283783D02*
G03X1572398Y283737I-244J-317D01*
G02X1570684Y286128I-1105J1018D01*
G03X1570903Y286613I-163J365D01*
G02X1573802Y286738I1433J450D01*
G03X1574103Y286262I391J-86D01*
G02X1572936Y283783I-313J-1367D01*
G37*
G36*
G01X1588951Y251113D02*
G03X1588396Y250860I-170J-362D01*
G02X1587591Y252626I-1446J407D01*
G03X1588146Y252879I170J362D01*
G02X1588951Y251113I1446J-407D01*
G37*
G36*
G01X1548542Y245073D02*
G03X1548652Y244519I333J-222D01*
G02X1546702Y244133I-783J-1163D01*
G03X1546592Y244687I-333J222D01*
G02X1548542Y245073I783J1163D01*
G37*
G36*
G01X1592716Y258175D02*
G02X1590523Y255841I-1118J-1147D01*
G03X1590003Y255856I-269J-297D01*
G02X1587961Y255884I-1004J1248D01*
G03X1587442Y255883I-259J-305D01*
G02X1585039Y256252I-1043J1216D01*
G03X1584369Y256267I-340J-211D01*
G02X1581977Y258363I-1323J903D01*
G03X1581983Y258953I-267J298D01*
G02X1584496Y260867I1095J1169D01*
G03X1585166Y260808I354J186D01*
G02X1587478Y261035I1264J-984D01*
G03X1587998Y261032I262J303D01*
G02X1590015Y261071I1033J-1225D01*
G03X1590534Y261094I246J315D01*
G02X1592722Y258754I1094J-1170D01*
G03X1592716Y258175I273J-292D01*
G37*
G36*
G01X1515380Y611807D02*
G03X1514854I-263J-302D01*
G02X1512846Y611837I-987J1132D01*
G03X1512317Y611850I-272J-293D01*
G02X1512371Y614102I-967J1150D01*
G03X1512900Y614089I272J293D01*
G02X1514854Y614071I966J-1150D01*
G03X1515380I263J302D01*
G02Y611807I987J-1132D01*
G37*
G36*
G01X1479322Y612798D02*
G03X1479833Y612784I264J300D01*
G02X1479767Y610475I927J-1182D01*
G03X1479256Y610489I-264J-300D01*
G02X1477308Y610569I-927J1182D01*
G03X1476779Y610582I-272J-293D01*
G02X1476833Y612834I-967J1150D01*
G03X1477362Y612821I272J293D01*
G02X1479322Y612798I967J-1150D01*
G37*
G36*
G01X1535833Y611603D02*
G02X1534793Y609137I-905J-1071D01*
G02X1529389Y611608I-2523J1627D01*
G03X1529159Y612089I-384J112D01*
G02X1528864Y612257I541J1293D01*
G03X1528294Y612159I-238J-322D01*
G02X1528149Y614024I-1244J841D01*
G03X1528470Y614063I146J136D01*
G02X1528563Y614209I1227J-679D01*
G03X1528485Y614509I-161J118D01*
G02X1530356Y616335I582J1275D01*
G03X1530893Y616129I368J157D01*
G02X1534869Y614702I1267J-2721D01*
G02X1535992Y614238I79J-1400D01*
G03X1536605Y614259I298J267D01*
G02X1537141Y614678I1106J-862D01*
G03X1537356Y615176I-162J365D01*
G02X1540080Y615601I1323J465D01*
G03X1540526Y615192I400J-12D01*
G02X1539558Y612725I174J-1492D01*
G03X1538911Y612672I-304J-260D01*
G02X1536667Y612461I-1200J725D01*
G03X1536054Y612440I-298J-267D01*
G02X1535837Y612218I-1105J863D01*
G03X1535833Y611603I254J-309D01*
G37*
G36*
G01X1505796Y610073D02*
G03Y609527I292J-273D01*
G02X1503604I-1096J-1027D01*
G03Y610073I-292J273D01*
G02X1505796I1096J1027D01*
G37*
G36*
G01X1468314Y608922D02*
G03X1468293Y609542I-263J301D01*
G02X1470187Y609607I907J1197D01*
G03X1470208Y608987I263J-301D01*
G02X1468314Y608922I-907J-1197D01*
G37*
G36*
G01X1520505Y597038D02*
G03X1520268Y596884I-41J-196D01*
G02X1517342Y596839I-1468J316D01*
G03X1516921Y597142I-388J-96D01*
G02X1516432Y597183I-121J1497D01*
G03X1515948Y596901I-98J-388D01*
G02X1513027Y597008I-1448J399D01*
G03X1512792Y597166I-196J-38D01*
G02X1512319Y597148I-293J1473D01*
G03X1511888Y596866I-48J-397D01*
G02X1509463Y596168I-1438J434D01*
G03X1508937I-263J-302D01*
G02X1506895Y598369I-986J1133D01*
G03X1506912Y598920I-281J284D01*
G02X1508609Y601308I1119J1002D01*
G03X1509117Y601493I153J369D01*
G02X1511937Y600590I1333J-693D01*
G03X1512368Y600135I396J-56D01*
G02X1513973Y598931I132J-1496D01*
G03X1514208Y598773I196J38D01*
G02X1514868Y598756I292J-1473D01*
G03X1515352Y599038I98J388D01*
G02X1518258Y599000I1448J-399D01*
G03X1518679Y598697I388J96D01*
G02X1519108Y598670I121J-1497D01*
G03X1519345Y598824I41J196D01*
G02X1522265Y598892I1468J-316D01*
G03X1522510Y598751I193J52D01*
G02X1523086Y598790I388J-1451D01*
G03X1523310Y598964I25J199D01*
G02X1526268Y599095I1490J-187D01*
G03X1526720Y598784I391J84D01*
G02X1525482Y596983I230J-1484D01*
G03X1525030Y597294I-391J-84D01*
G02X1524614Y597288I-229J1484D01*
G03X1524390Y597114I-25J-199D01*
G02X1521448Y596916I-1490J186D01*
G03X1521203Y597057I-193J-52D01*
G02X1520505Y597038I-389J1451D01*
G37*
G36*
G01X1473925Y594900D02*
G03X1473399I-263J-302D01*
G02X1471191Y595158I-987J1132D01*
G03X1470622Y595242I-325J-233D01*
G02X1469098Y597585I-855J1111D01*
G03X1469083Y598295I-191J351D01*
G02X1470710Y600527I618J1259D01*
G03X1471296Y600537I288J277D01*
G02X1473399Y600664I1116J-1005D01*
G03X1473925I263J302D01*
G02X1476414Y599532I987J-1132D01*
G01Y599531D01*
G03X1476880Y599137I400J1D01*
G02X1478601Y597954I249J-1481D01*
G03X1479001Y597634I392J80D01*
G02X1479303Y597609I28J-1502D01*
G03X1479766Y597911I74J393D01*
G02X1482721Y597741I1463J-340D01*
G03X1482942Y597565I199J23D01*
G02X1483463Y597530I161J-1493D01*
G03X1483952Y597846I96J388D01*
G02X1486903Y597857I1477J-275D01*
G03X1487303Y597534I393J77D01*
G02X1487355I26J-1502D01*
G03X1487755Y597857I7J400D01*
G02X1490707Y597837I1474J-287D01*
G03X1491166Y597514I394J72D01*
G02X1489934Y595766I246J-1482D01*
G03X1489475Y596089I-394J-72D01*
G02X1489203Y596069I-246J1482D01*
G03X1488803Y595746I-7J-400D01*
G02X1485855I-1474J286D01*
G03X1485455Y596069I-393J-77D01*
G02X1485070Y596113I-23J1502D01*
G03X1484581Y595797I-96J-388D01*
G02X1481612Y595902I-1477J275D01*
G03X1481391Y596078I-199J-23D01*
G02X1480955Y596094I-164J1493D01*
G03X1480492Y595792I-74J-393D01*
G02X1477557Y595834I-1463J340D01*
G03X1477157Y596154I-392J-80D01*
G02X1476867Y596177I-27J1502D01*
G03X1476401Y595835I-69J-394D01*
G02X1473925Y594900I-1489J197D01*
G37*
G36*
G01X1498208Y611341D02*
G02X1496845Y611026I-408J-1341D01*
G03X1496689Y611702I-272J293D01*
G02X1495870Y612364I407J1342D01*
G03X1495205Y612417I-350J-193D01*
G02X1493563Y611985I-1105J863D01*
G03X1493011Y611640I-153J-370D01*
G02X1490718Y613007I-1499J92D01*
G03X1490770Y613647I-212J339D01*
G02X1495193Y614158I1980J2256D01*
G02X1495327Y613959I-1092J-880D01*
G03X1495992Y613906I350J193D01*
G02X1498052Y612017I1105J-862D01*
G03X1498208Y611341I272J-293D01*
G37*
G36*
G01X1517373Y618790D02*
G02X1515315Y618912I-973J1010D01*
G03X1514716Y618934I-309J-254D01*
G02X1512666Y618953I-1016J966D01*
G03X1512112Y618988I-295J-270D01*
G02X1510259Y619021I-908J1068D01*
G03X1509670Y618966I-269J-296D01*
G02X1507346Y619092I-1120J844D01*
G03X1506708Y619159I-344J-204D01*
G02X1504673Y619135I-1029J952D01*
G03X1504080Y619114I-287J-279D01*
G02X1502035Y619009I-1072J904D01*
G03X1501466Y618995I-278J-288D01*
G02X1501418Y620965I-1021J961D01*
G03X1501987Y620979I278J288D01*
G02X1504014Y620994I1021J-961D01*
G03X1504607Y621015I287J279D01*
G02X1506883Y620829I1072J-904D01*
G03X1507521Y620762I344J204D01*
G02X1509495Y620845I1029J-952D01*
G03X1510084Y620900I269J296D01*
G02X1512238Y621003I1120J-844D01*
G03X1512792Y620968I295J270D01*
G02X1514785Y620788I908J-1068D01*
G03X1515384Y620766I309J254D01*
G02X1517373Y620810I1016J-966D01*
G03X1517927I277J288D01*
G02Y618790I973J-1010D01*
G03X1517373I-277J-288D01*
G37*
G36*
G01X1475833Y571394D02*
G02Y573236I-1057J921D01*
G03X1476436I301J263D01*
G02X1478427Y573361I1057J-921D01*
G03X1478959I266J298D01*
G02X1480827I934J-1046D01*
G03X1481359I266J298D01*
G02X1483227I934J-1046D01*
G03X1483759I266J298D01*
G02X1485627I934J-1046D01*
G03X1486159I266J298D01*
G02X1488027I934J-1046D01*
G03X1488559I266J298D01*
G02X1489914Y573652I933J-1046D01*
G03X1490421Y573931I120J382D01*
G02X1492655Y574663I1355J-360D01*
G03X1493243Y574758I251J311D01*
G02X1495386Y575018I1179J-758D01*
G03X1495936I275J290D01*
G02X1498067Y574777I964J-1018D01*
G03X1498733I333J222D01*
G02Y573223I1167J-777D01*
G03X1498067I-333J-222D01*
G02X1495936Y572982I-1167J777D01*
G03X1495386I-275J-290D01*
G02X1493543Y572908I-964J1018D01*
G03X1492955Y572813I-251J-311D01*
G02X1491355Y572234I-1179J758D01*
G03X1490848Y571955I-120J-382D01*
G02X1488559Y571269I-1355J360D01*
G03X1488027I-266J-298D01*
G02X1486159I-934J1046D01*
G03X1485627I-266J-298D01*
G02X1483759I-934J1046D01*
G03X1483227I-266J-298D01*
G02X1481359I-934J1046D01*
G03X1480827I-266J-298D01*
G02X1478959I-934J1046D01*
G03X1478427I-266J-298D01*
G02X1476436Y571394I-934J1046D01*
G03X1475833I-302J-263D01*
G37*
G36*
G01X1469246Y411044D02*
G03X1468646Y410912I-245J-316D01*
G02X1468261Y412665I-1245J645D01*
G03X1468861Y412797I245J316D01*
G02X1471147Y413091I1245J-645D01*
G03X1471720Y413069I297J268D01*
G02X1471647Y411116I968J-1014D01*
G03X1471074Y411138I-297J-268D01*
G02X1469246Y411044I-969J1014D01*
G37*
G36*
G01X1483330Y395541D02*
G03X1483907Y395319I380J126D01*
G02X1483270Y393657I693J-1219D01*
G03X1482693Y393879I-380J-126D01*
G02X1483330Y395541I-693J1219D01*
G37*
G36*
G01X1479711Y360646D02*
G03X1479710Y360102I293J-273D01*
G02X1477508Y360106I-1103J-1020D01*
G03X1477509Y360650I-293J273D01*
G02X1479711Y360646I1103J1020D01*
G37*
G36*
G01X1489450Y359356D02*
G03Y358778I277J-289D01*
G02X1487508I-971J-1011D01*
G03Y359356I-277J289D01*
G02Y361378I971J1011D01*
G03Y361956I-277J289D01*
G02X1487437Y363905I971J1011D01*
G03X1487418Y364460I-297J268D01*
G02X1489436Y364528I976J1006D01*
G03X1489455Y363973I297J-268D01*
G02X1489450Y361956I-976J-1006D01*
G03Y361378I277J-289D01*
G02Y359356I-971J-1011D01*
G37*
G36*
G01X1521344Y356119D02*
G03X1521384Y355539I294J-271D01*
G02X1519378Y355452I-955J-1160D01*
G03X1519368Y356033I-280J286D01*
G02X1521344Y356119I945J1036D01*
G37*
G36*
G01X1525756Y355744D02*
G03Y355190I288J-277D01*
G02X1523736I-1010J-973D01*
G03Y355744I-288J277D01*
G02Y357690I1010J973D01*
G03Y358244I-288J277D01*
G02X1525756I1010J973D01*
G03Y357690I288J-277D01*
G02Y355744I-1010J-973D01*
G37*
G36*
G01X1508090Y354790D02*
G03X1508067Y354164I237J-322D01*
G02X1506276Y354193I-913J-1064D01*
G03X1506272Y354819I-251J311D01*
G02X1506142Y357066I928J1181D01*
G03Y357634I-282J284D01*
G02X1508258I1058J1066D01*
G03Y357066I282J-284D01*
G02X1508090Y354790I-1058J-1066D01*
G37*
G36*
G01X1482962Y350420D02*
G03X1482502Y350019I-60J-395D01*
G02X1481293Y351473I-1502J-19D01*
G03X1481771Y351852I78J392D01*
G02X1482962Y350420I1401J-46D01*
G37*
G36*
G01X1526799Y351103D02*
G03X1527355Y350999I330J226D01*
G02X1527035Y348987I791J-1157D01*
G03X1526475Y349061I-317J-244D01*
G02X1526799Y351103I-914J1192D01*
G37*
G36*
G01X1491025Y351625D02*
G03Y351087I296J-269D01*
G02X1488716Y351155I-1187J-1076D01*
G03X1488747Y351692I-280J286D01*
G02X1491025Y351625I1168J945D01*
G37*
G36*
G01X1497437Y350438D02*
G02X1496400Y351448I-1437J-438D01*
G03X1496893Y351938I107J385D01*
G02X1497221Y353261I1353J367D01*
G03X1497205Y353822I-293J272D01*
G02X1497150Y355932I1041J1083D01*
G03Y356478I-292J273D01*
G02X1497139Y358521I1096J1027D01*
G03X1497153Y359046I-294J271D01*
G02X1497227Y361046I1156J959D01*
G03X1497213Y361614I-289J277D01*
G02X1497220Y363802I1033J1091D01*
G03X1497221Y364385I-273J292D01*
G02X1499191Y364431I962J1020D01*
G03X1499220Y363849I288J-277D01*
G02X1499328Y361664I-974J-1143D01*
G03X1499342Y361096I289J-277D01*
G02X1499416Y358989I-1033J-1091D01*
G03X1499402Y358464I294J-271D01*
G02X1499342Y356478I-1156J-959D01*
G03Y355932I292J-273D01*
G02X1499287Y353822I-1096J-1027D01*
G03X1499271Y353261I277J-289D01*
G02X1497914Y350943I-1025J-956D01*
G03X1497437Y350438I-94J-389D01*
G37*
G36*
G01X1484833Y357904D02*
G02X1482801Y357811I-965J-1151D01*
G03X1482774Y358399I-284J282D01*
G02X1483010Y360862I966J1150D01*
G03X1482994Y361570I-195J350D01*
G02X1482553Y363925I670J1344D01*
G03X1482534Y364484I-295J270D01*
G02X1484587Y364615I966J1016D01*
G03X1484638Y364058I310J-252D01*
G02X1484394Y361602I-974J-1143D01*
G03X1484410Y360894I195J-350D01*
G02X1484806Y358492I-670J-1344D01*
G03X1484833Y357904I284J-282D01*
G37*
G36*
G01X1488901Y339331D02*
G03X1488924Y338735I278J-288D01*
G02X1486845Y338702I-1020J-1235D01*
G03X1486850Y339299I-264J301D01*
G02X1488901Y339331I1008J1113D01*
G37*
G36*
G01X1473398Y336467D02*
G03X1473409Y335868I270J-295D01*
G02X1471552Y335833I-909J-1068D01*
G03X1471541Y336432I-270J295D01*
G02X1473398Y336467I909J1068D01*
G37*
G36*
G01X1526831Y328837D02*
G03X1526297Y328715I-202J-345D01*
G02X1525881Y330805I-1246J838D01*
G03X1526421Y330896I222J333D01*
G02X1526831Y328837I1116J-848D01*
G37*
G36*
G01X1527274Y310894D02*
G03X1526703Y310879I-278J-287D01*
G02X1526653Y312841I-1026J955D01*
G03X1527224Y312856I278J287D01*
G02X1527274Y310894I1026J-955D01*
G37*
G36*
G01X1513194Y294288D02*
G03X1513757Y294274I289J277D01*
G02X1513710Y292286I965J-1017D01*
G03X1513147Y292300I-289J-277D01*
G02X1513194Y294288I-965J1017D01*
G37*
G36*
G01X1527833Y294544D02*
G03X1527887Y293999I317J-244D01*
G02X1525765Y293849I-986J-1133D01*
G03X1525742Y294397I-302J262D01*
G02X1527833Y294544I980J1003D01*
G37*
G36*
G01X1494802Y282343D02*
G03X1495428Y282340I314J247D01*
G02X1495381Y280523I1172J-939D01*
G03X1494755Y280553I-325J-234D01*
G02X1494802Y282343I-1055J923D01*
G37*
G36*
G01X1514254Y281476D02*
G02X1514234Y280160I1228J-677D01*
G03X1513528Y280171I-356J-182D01*
G02X1513548Y281487I-1228J677D01*
G03X1514254Y281476I356J182D01*
G37*
G36*
G01X1506795Y307781D02*
G02X1505065Y307774I-861J-1107D01*
G03X1505063Y308403I-248J314D01*
G02X1506793Y308410I861J1107D01*
G03X1506795Y307781I248J-314D01*
G37*
G36*
G01X1517258Y311593D02*
G02X1515138Y311731I-1119J-844D01*
G03X1515157Y312271I-286J280D01*
G02X1514885Y313745I1144J973D01*
G03X1514410Y314267I-377J134D01*
G02X1515402Y315196I-342J1360D01*
G03X1515891Y314689I381J-122D01*
G02X1517309Y312130I410J-1445D01*
G03X1517258Y311593I268J-296D01*
G37*
G36*
G01X1502911Y319322D02*
G02X1502139Y318167I627J-1254D01*
G03X1501551Y318547I-399J28D01*
G02X1502334Y319720I-711J1323D01*
G03X1502911Y319322I398J-40D01*
G37*
G36*
G01X1469827Y324466D02*
G02X1469558Y325886I-1428J465D01*
G03X1470243Y326005I309J254D01*
G02X1470508Y324606I1319J-475D01*
G03X1469827Y324466I-301J-264D01*
G37*
G36*
G01X1514759Y328814D02*
G02X1513140Y328685I-709J-1324D01*
G03X1513087Y329356I-242J318D01*
G02X1512491Y329936I709J1324D01*
G03X1511798Y329938I-347J-198D01*
G02X1511780Y331372I-1214J702D01*
G03X1512473Y331391I341J209D01*
G02X1515243Y331083I1323J-711D01*
G03X1515941Y330942I385J108D01*
G02X1515668Y329602I1174J-937D01*
G03X1514970Y329743I-385J-108D01*
G02X1514706Y329485I-1174J937D01*
G03X1514759Y328814I242J-318D01*
G37*
G36*
G01X1498346Y336280D02*
G02X1497117Y334564I254J-1480D01*
G03X1496654Y334896I-395J-62D01*
G02X1494986Y336881I-254J1480D01*
G03X1494785Y337375I-377J135D01*
G02X1494532Y339917I660J1349D01*
G03X1494626Y340449I-243J317D01*
G02X1496726Y340139I1184J751D01*
G03X1496663Y339602I262J-303D01*
G02X1496692Y339561I-1211J-888D01*
G03X1497000Y339532I166J112D01*
G02X1498123Y339942I996J-986D01*
G03X1498510Y340532I36J399D01*
G02X1501330Y341199I1319J718D01*
G03X1501697Y340786I400J-14D01*
G02X1500181Y339358I-114J-1397D01*
G03X1499791Y339748I-400J-10D01*
G02X1499651Y339759I48J1501D01*
G03X1499247Y339180I-47J-397D01*
G02X1498203Y337159I-1250J-634D01*
G03X1497870Y336682I59J-396D01*
G02X1497883Y336612I-1470J-309D01*
G03X1498346Y336280I395J62D01*
G37*
G36*
G01X1478173Y294968D02*
G02X1476266Y296874I-1225J681D01*
G03Y297573I-194J350D01*
G02X1476268Y300024I682J1225D01*
G03Y300723I-194J350D01*
G02X1475723Y301268I681J1226D01*
G03X1475024I-349J-194D01*
G02X1472573Y301266I-1226J680D01*
G03X1471874I-349J-194D01*
G02X1469968Y303173I-1225J682D01*
G03Y303873I-194J350D01*
G02X1469967Y306323I681J1225D01*
G03Y307022I-194J350D01*
G02X1469968Y309472I682J1225D01*
G03Y310172I-194J350D01*
G02X1469967Y312622I681J1225D01*
G03Y313321I-194J350D01*
G02X1471874Y315228I682J1225D01*
G03X1472573I350J194D01*
G02X1474480Y313321I1225J-682D01*
G03Y312622I194J-350D01*
G02X1475023Y312078I-683J-1224D01*
G03X1475723I350J194D01*
G02X1478173I1225J-681D01*
G03X1478873I350J194D01*
G02X1479416Y312622I1226J-680D01*
G03Y313321I-194J350D01*
G02X1481323Y315228I682J1225D01*
G03X1482022I350J194D01*
G02X1484472Y315227I1225J-682D01*
G03X1485172I350J194D01*
G02X1485715Y315771I1226J-680D01*
G03Y316470I-194J349D01*
G02X1487621Y318377I681J1226D01*
G03X1488321I350J194D01*
G02X1490227Y316471I1225J-681D01*
G03Y315771I194J-350D01*
G02X1490228Y313321I-681J-1225D01*
G03Y312622I194J-350D01*
G02X1490777Y312067I-683J-1224D01*
G03X1491478Y312062I352J191D01*
G02X1493855Y312171I1222J-686D01*
G03X1494510Y312165I330J226D01*
G02X1495022Y312603I1141J-815D01*
G03X1495033Y313312I-179J357D01*
G02X1496328Y313293I666J1234D01*
G03X1496317Y312584I179J-357D01*
G02X1494496Y310555I-666J-1234D01*
G03X1493841Y310561I-330J-226D01*
G02X1491469Y310706I-1141J815D01*
G03X1490768Y310711I-352J-191D01*
G02X1490227Y310172I-1222J686D01*
G03Y309472I194J-350D01*
G02X1488321Y307565I-681J-1225D01*
G03X1487622I-349J-194D01*
G02X1487079Y307022I-1225J682D01*
G03Y306323I194J-350D01*
G02X1487078Y303873I-682J-1225D01*
G03Y303173I194J-350D01*
G02X1487622Y302630I-680J-1226D01*
G03X1488321I350J194D01*
G02Y301266I1225J-682D01*
G03X1487622I-349J-194D01*
G02X1487078Y300723I-1224J683D01*
G03Y300023I194J-350D01*
G02X1487079Y297573I-681J-1225D01*
G03Y296874I194J-349D01*
G02X1485715I-682J-1225D01*
G03Y297573I-194J350D01*
G02X1485172Y298117I683J1224D01*
G03X1484472I-350J-194D01*
G02X1482022Y298116I-1225J681D01*
G03X1481323I-349J-194D01*
G02X1480780Y297573I-1225J682D01*
G03Y296874I194J-349D01*
G02X1478873Y294968I-682J-1225D01*
G03X1478173I-350J-194D01*
G37*
G36*
G01X1494339Y254529D02*
G02X1494020Y256765I-1140J978D01*
G03X1494542Y256839I219J335D01*
G02X1494610Y256913I1139J-979D01*
G03X1494629Y257452I-286J280D01*
G02X1496753Y257440I1067J909D01*
G03X1496766Y256901I302J-262D01*
G02X1497005Y256572I-1085J-1039D01*
G03X1497718Y256587I353J189D01*
G02X1497747Y255223I1352J-654D01*
G03X1497034Y255208I-353J-189D01*
G02X1494861Y254603I-1353J653D01*
G03X1494339Y254529I-219J-335D01*
G37*
G36*
G01X1481323Y266622D02*
G02X1479417Y268529I-1225J682D01*
G03Y269229I-194J350D01*
G02X1478873Y269773I681J1225D01*
G03X1478173I-350J-194D01*
G02X1475723I-1225J681D01*
G03X1475023I-350J-194D01*
G02X1472573Y269772I-1225J681D01*
G03X1471874I-349J-194D01*
G02X1469967Y271679I-1225J682D01*
G03Y272378I-194J350D01*
G02X1469968Y274828I682J1225D01*
G03Y275528I-194J350D01*
G02X1469967Y277978I681J1225D01*
G03Y278677I-194J350D01*
G02X1469968Y281127I682J1225D01*
G03Y281827I-194J350D01*
G02X1471874Y283734I681J1225D01*
G03X1472573I350J194D01*
G02X1475024Y283732I1225J-682D01*
G03X1475723I350J194D01*
G02X1476268Y284277I1226J-681D01*
G03Y284976I-194J349D01*
G02X1476266Y287427I680J1226D01*
G03Y288126I-194J350D01*
G02X1477630I682J1225D01*
G03Y287427I194J-350D01*
G02X1478173Y286883I-683J-1224D01*
G03X1478873I350J194D01*
G02X1481323Y286884I1225J-681D01*
G03X1482022I350J194D01*
G02X1482565Y287427I1225J-682D01*
G03Y288126I-194J350D01*
G02X1483929I682J1225D01*
G03Y287427I194J-350D01*
G02X1484472Y286883I-683J-1224D01*
G03X1485172I350J194D01*
G02X1487622Y286884I1225J-681D01*
G03X1488321I350J194D01*
G02Y285520I1225J-682D01*
G03X1487622I-349J-194D01*
G02X1487078Y284977I-1224J683D01*
G03Y284277I194J-350D01*
G02X1485172Y282371I-681J-1225D01*
G03X1484472I-350J-194D01*
G02X1482022Y282370I-1225J681D01*
G03X1481323I-349J-194D01*
G02X1478873I-1225J682D01*
G03X1478174I-349J-195D01*
G02X1477630Y281826I-1225J681D01*
G03Y281127I195J-350D01*
G02Y278677I-682J-1225D01*
G03Y277978I194J-350D01*
G02X1477629Y275528I-682J-1225D01*
G03Y274828I194J-350D01*
G02X1478173Y274284I-681J-1225D01*
G03X1478873I350J194D01*
G02X1481323Y274285I1225J-681D01*
G03X1482022I350J194D01*
G02X1482566Y274828I1224J-683D01*
G03Y275528I-194J350D01*
G02X1483928I681J1225D01*
G03Y274828I194J-350D01*
G02X1484472Y274284I-681J-1225D01*
G03X1485172I350J194D01*
G02X1487079Y272378I1225J-681D01*
G03Y271679I194J-350D01*
G02X1487622Y271136I-682J-1225D01*
G03X1488321I350J194D01*
G02Y269772I1225J-682D01*
G03X1487622I-349J-194D01*
G02X1485172Y269773I-1225J682D01*
G03X1484472I-350J-194D01*
G02X1483928Y269229I-1225J681D01*
G03Y268529I194J-350D01*
G02X1482022Y266622I-681J-1225D01*
G03X1481323I-349J-194D01*
G37*
G36*
G01X1498579Y278110D02*
G02X1497638Y279382I-1497J-123D01*
G03X1498184Y279787I147J372D01*
G02X1499125Y278515I1497J123D01*
G03X1498579Y278110I-147J-372D01*
G37*
G36*
G01X1472321Y617759D02*
G03X1471780Y617521I-162J-366D01*
G02X1468983Y617391I-1424J479D01*
G03X1468454Y617594I-366J-162D01*
G02X1466961Y617745I-616J1370D01*
G03X1466418Y617675I-234J-324D01*
G02X1466087Y619747I-1084J889D01*
G03X1466625Y619848I215J337D01*
G02X1469212Y619573I1214J-884D01*
G03X1469741Y619370I366J162D01*
G02X1470967Y619372I615J-1370D01*
G03X1471508Y619610I162J366D01*
G02X1474070Y620112I1424J-479D01*
G03X1474690Y620130I303J261D01*
G02X1476882Y620339I1193J-913D01*
G03X1477432Y620356I266J299D01*
G02X1479140Y620659I1068J-1056D01*
G03X1479661Y620827I171J362D01*
G02X1482334Y620740I1314J-727D01*
G03X1482818Y620530I362J171D01*
G02X1481920Y618460I461J-1430D01*
G03X1481436Y618670I-362J-171D01*
G02X1480335Y618741I-461J1430D01*
G03X1479814Y618573I-171J-362D01*
G02X1477501Y618178I-1314J727D01*
G03X1476951Y618161I-266J-299D01*
G02X1474745Y618236I-1068J1056D01*
G03X1474125Y618218I-303J-261D01*
G02X1472321Y617759I-1193J913D01*
G37*
G36*
G01X1443641Y571089D02*
G03X1443199Y570735I-44J-398D01*
G02X1441961Y572280I-1394J152D01*
G03X1442403Y572634I44J398D01*
G02X1443954Y573875I1394J-152D01*
G03X1444398Y574279I44J398D01*
G02X1446028Y575683I1402J21D01*
G03X1446483Y575991I65J395D01*
G02X1447624Y574304I1369J-304D01*
G03X1447169Y573996I-65J-395D01*
G02X1445643Y572907I-1369J304D01*
G03X1445199Y572503I-44J-398D01*
G02X1443641Y571089I-1402J-21D01*
G37*
G36*
G01X1440629Y538649D02*
G02X1439047Y538669I-807J-1267D01*
G03X1439067Y539341I-206J342D01*
G02X1438516Y540891I794J1155D01*
G03X1438272Y541378I-384J112D01*
G02X1437814Y543919I527J1407D01*
G03X1437883Y544447I-262J303D01*
G02X1440108Y544160I1240J847D01*
G03X1440039Y543632I262J-303D01*
G02X1440213Y542280I-1240J-847D01*
G03X1440428Y541779I377J-135D01*
G02X1440625Y539322I-567J-1282D01*
G03X1440629Y538649I218J-335D01*
G37*
G36*
G01X1451897Y571203D02*
G02X1450403I-747J-1303D01*
G03Y571897I-199J347D01*
G02X1451897I747J1303D01*
G03Y571203I199J-347D01*
G37*
G36*
G01X1467688Y571033D02*
G02X1467410Y569355I961J-1021D01*
G03X1466772Y569448I-353J-188D01*
G02X1467054Y571151I-1072J1052D01*
G03X1467688Y571033I360J173D01*
G37*
G36*
G01X1438204Y525685D02*
G03X1437755Y525255I-50J-397D01*
G02X1436471Y526539I-1397J-113D01*
G03X1436900Y526988I32J399D01*
G02X1438204Y525685I1490J187D01*
G37*
G36*
G01X1419200Y522044D02*
G03X1419712Y521814I373J145D01*
G02X1418923Y519921I488J-1314D01*
G03X1418399Y520123I-364J-165D01*
G02X1416646Y520538I-600J1377D01*
G03X1416015Y520517I-307J-256D01*
G02X1415954Y522362I-1215J883D01*
G03X1416585Y522383I307J256D01*
G02X1419200Y522044I1215J-883D01*
G37*
G36*
G01X1414585Y488498D02*
G03X1414024Y488482I-272J-293D01*
G02Y490564I-1083J1041D01*
G03X1414585Y490548I289J277D01*
G02X1416538Y490509I956J-1025D01*
G03X1417121Y490523I285J281D01*
G02Y488523I1120J-1000D01*
G03X1416538Y488537I-298J-267D01*
G02X1414585Y488498I-997J986D01*
G37*
G36*
G01X1416805Y478478D02*
G03X1417354Y478455I287J279D01*
G02X1417207Y476338I987J-1132D01*
G03X1416659Y476392I-302J-262D01*
G02X1414806Y476512I-859J1108D01*
G03X1414211Y476481I-284J-282D01*
G02X1414156Y478429I-1170J942D01*
G03X1414752Y478431I297J268D01*
G02X1416805Y478478I1048J-931D01*
G37*
G36*
G01X1417874Y483914D02*
G02X1417053Y481948I567J-1391D01*
G03X1416554Y482174I-370J-153D01*
G02X1415269Y482371I-454J1326D01*
G03X1414646Y482150I-236J-323D01*
G02X1414127Y483709I-1453J382D01*
G03X1414758Y483906I248J313D01*
G02X1417362Y484110I1342J-406D01*
G03X1417874Y483914I360J174D01*
G37*
G36*
G01X1414214Y493929D02*
G02X1413771Y495317I-1473J295D01*
G03X1414434Y495517I274J291D01*
G02X1417030Y495873I1366J-317D01*
G03X1417583Y495720I351J192D01*
G02X1416987Y493772I758J-1297D01*
G03X1416443Y493954I-360J-173D01*
G02X1414871Y494150I-643J1246D01*
G03X1414214Y493929I-265J-300D01*
G37*
G36*
G01X1410106Y527885D02*
G02X1408748Y528920I-1353J-367D01*
G03X1409133Y529425I-1J400D01*
G02X1410491Y528390I1353J367D01*
G03X1410106Y527885I1J-400D01*
G37*
G36*
G01X1430776Y452503D02*
G03X1430171Y452496I-299J-265D01*
G02X1430104Y454378I-1071J904D01*
G03X1430708Y454414I286J279D01*
G02X1430776Y452503I1192J-914D01*
G37*
G36*
G01X1430078Y448896D02*
G03X1430704Y448909I308J255D01*
G02Y447091I1196J-909D01*
G03X1430078Y447104I-318J-242D01*
G02Y448896I-1078J896D01*
G37*
G36*
G01X1440542Y407638D02*
G02X1438498Y408013I-1192J-738D01*
G03X1438583Y408561I-243J318D01*
G02X1438852Y410576I1230J861D01*
G03X1438818Y411216I-256J307D01*
G02X1440612Y411312I833J1250D01*
G03X1440646Y410672I256J-307D01*
G02X1440657Y408180I-833J-1250D01*
G03X1440542Y407638I225J-331D01*
G37*
G36*
G01X1439722Y402344D02*
G03X1439270Y402030I-60J-395D01*
G02X1438109Y403701I-1373J285D01*
G03X1438561Y404015I60J395D01*
G02X1439722Y402344I1373J-285D01*
G37*
G36*
G01X1465489Y384283D02*
G03X1465497Y383746I300J-264D01*
G02X1463272Y383712I-1097J-1026D01*
G03X1463264Y384249I-300J264D01*
G02X1465489Y384283I1097J1026D01*
G37*
G36*
G01X1419006Y374775D02*
G03X1419614Y374659I351J191D01*
G02X1419282Y372917I901J-1074D01*
G03X1418674Y373033I-351J-191D01*
G02X1419006Y374775I-901J1074D01*
G37*
G36*
G01X1416557Y352133D02*
G03X1416547Y351576I282J-284D01*
G02X1414393Y351617I-1097J-1026D01*
G03X1414403Y352174I-282J284D01*
G02X1416557Y352133I1097J1026D01*
G37*
G36*
G01X1447471Y350639D02*
G03X1447011Y350262I-61J-395D01*
G02X1445811Y351799I-1501J65D01*
G03X1446289Y352154I80J392D01*
G02X1447471Y350639I1396J-129D01*
G37*
G36*
G01X1464895Y358225D02*
G02X1462630Y358521I-1278J-966D01*
G03X1462730Y359037I-246J315D01*
G02X1462660Y359174I1212J705D01*
G03X1462306Y359195I-182J-81D01*
G02X1462289Y360762I-1290J770D01*
G03X1462919Y360701I339J213D01*
G02X1464932Y358749I1023J-959D01*
G03X1464895Y358225I282J-283D01*
G37*
G36*
G01X1419025Y367244D02*
G02X1418512Y368658I-1369J303D01*
G03X1419146Y368888I244J317D01*
G02X1419659Y367474I1369J-303D01*
G03X1419025Y367244I-244J-317D01*
G37*
G36*
G01X1444328Y369627D02*
G02X1442884Y370335I-1228J-677D01*
G03X1443172Y370923I-62J395D01*
G02X1444616Y370215I1228J677D01*
G03X1444328Y369627I62J-395D01*
G37*
G36*
G01X1419168Y379444D02*
G02X1418759Y377893I907J-1069D01*
G03X1418124Y378060I-376J-138D01*
G02X1416499Y380333I-907J1069D01*
G03X1416528Y381001I-205J344D01*
G02X1418087Y383329I821J1136D01*
G03X1418692Y383604I210J340D01*
G02X1419337Y382183I1383J-229D01*
G03X1418732Y381908I-210J-340D01*
G02X1418067Y380933I-1383J229D01*
G03X1418038Y380265I205J-344D01*
G02X1418533Y379611I-821J-1136D01*
G03X1419168Y379444I376J138D01*
G37*
G36*
G01X1457806Y382773D02*
G02X1455865Y382938I-1056J-923D01*
G03X1455901Y383526I-252J311D01*
G02X1456042Y385742I1080J1044D01*
G03X1456025Y386379I-250J312D01*
G02X1457839Y386427I875J1221D01*
G03X1457856Y385790I250J-312D01*
G02X1457870Y383358I-875J-1221D01*
G03X1457806Y382773I237J-322D01*
G37*
G36*
G01X1419527Y386552D02*
G02X1418256Y387758I-1389J-191D01*
G03X1418686Y388211I34J399D01*
G02X1419957Y387005I1389J191D01*
G03X1419527Y386552I-34J-399D01*
G37*
G36*
G01X1470953Y393463D02*
G02X1469582Y393653I-853J-1113D01*
G03X1469737Y394285I-148J371D01*
G02X1469538Y395811I1063J915D01*
G03X1469332Y396354I-360J174D01*
G02X1468754Y396803I541J1294D01*
G03X1468106Y396791I-320J-241D01*
G02X1467179Y396177I-1234J856D01*
G03X1466869Y395700I81J-392D01*
G02X1465142Y396755I-1369J-300D01*
G03X1465425Y397249I-103J387D01*
G02X1468106Y398505I1448J399D01*
G03X1468754Y398493I328J229D01*
G02X1470966Y398526I1119J-845D01*
G03X1471560Y398493I312J250D01*
G02X1472536Y396098I990J-993D01*
G03X1472147Y395588I-4J-400D01*
G02X1472183Y395433I-1346J-394D01*
G03X1472689Y395116I394J67D01*
G02X1471700Y393537I394J-1346D01*
G03X1471194Y393854I-394J-67D01*
G02X1471040Y393819I-387J1348D01*
G03X1470953Y393463I34J-197D01*
G37*
G36*
G01X1420951Y394497D02*
G02X1419219Y394512I-876J-1095D01*
G03X1419225Y395141I-244J317D01*
G02X1420957Y395126I876J1095D01*
G03X1420951Y394497I244J-317D01*
G37*
G36*
G01X1442198Y559256D02*
G03X1441717Y559647I-400J-1D01*
G02Y562587I-308J1470D01*
G03X1442198Y562978I81J392D01*
G01Y563115D01*
X1445773Y566690D01*
X1514615D01*
X1514857Y566447D01*
G03X1515198Y566588I141J142D01*
G01Y569115D01*
X1519285Y573202D01*
X1521648D01*
G03X1522040Y573679I0J400D01*
G02X1524063Y575193I1376J270D01*
G03X1524600Y575360I184J355D01*
G02X1524936Y575774I1237J-660D01*
G03X1524861Y576436I-257J306D01*
G02X1524490Y578657I639J1248D01*
G03Y579211I-288J277D01*
G02X1524486Y581153I1010J973D01*
G03Y581705I-289J276D01*
G02X1526514I1014J969D01*
G03Y581153I289J-276D01*
G02X1526861Y580520I-1015J-968D01*
G03X1527349Y580228I388J95D01*
G02X1528158Y580194I348J-1358D01*
G03X1528656Y580412I131J378D01*
G02X1528798Y580664I1286J-559D01*
G03X1528722Y581207I-326J231D01*
G02X1530689Y583183I878J1093D01*
G03X1531311I311J252D01*
G02X1533514Y581449I1089J-883D01*
G03X1533568Y580906I318J-243D01*
G02X1533500Y578744I-926J-1053D01*
G03X1533436Y578174I245J-316D01*
G02X1531372Y576282I-1082J-891D01*
G03X1530826Y576295I-280J-286D01*
G02X1530724Y576212I-935J1045D01*
G03X1530731Y575886I119J-161D01*
G02X1531040Y573851I-787J-1160D01*
G03X1531353Y573202I313J-249D01*
G01X1564530D01*
X1564560Y573366D01*
G02X1565035Y574191I1380J-245D01*
G03X1565049Y574790I-258J306D01*
G02X1566905Y574749I951J1030D01*
G03X1566891Y574150I258J-306D01*
G02X1567320Y573366I-951J-1030D01*
G01X1567350Y573202D01*
X1567723D01*
X1578215Y562709D01*
G03X1578898Y562994I283J283D01*
G02X1579323Y564006I1402J6D01*
G03X1579336Y564566I-279J287D01*
G02X1579357Y566504I1024J958D01*
G03X1579366Y567053I-286J279D01*
G02X1581403Y567020I1034J947D01*
G03X1581394Y566471I286J-279D01*
G02X1581337Y564518I-1034J-947D01*
G03X1581324Y563958I279J-287D01*
G02X1581310Y562027I-1024J-958D01*
G03Y561473I288J-277D01*
G02X1581453Y559703I-1010J-972D01*
G01X1581359Y559566D01*
X1589216Y551709D01*
G03X1589898Y551991I282J283D01*
G01Y565615D01*
X1589948Y565665D01*
Y570465D01*
X1591885Y572402D01*
X1597369D01*
G03X1597768Y572797I-1J400D01*
G02X1600313Y573592I1402J-17D01*
G03X1600887Y573510I326J232D01*
G02X1603331Y572452I938J-1185D01*
G01X1603337Y572379D01*
X1605569Y570147D01*
G03X1606214Y570260I283J283D01*
G02X1613669Y562804I5070J-2386D01*
G03X1613557Y562160I171J-361D01*
G01X1620225Y555492D01*
G03X1620848Y555564I283J283D01*
G02X1622929Y555911I1192J-737D01*
G03X1623582Y556220I253J309D01*
G01Y559200D01*
G02X1623787Y559959I1512J-1D01*
G03X1623630Y560512I-346J200D01*
G02X1625544Y561114I663J1235D01*
G03X1625732Y560570I357J-181D01*
G02X1626606Y559210I-638J-1371D01*
G01Y555115D01*
X1626596Y555031D01*
G02X1623934Y554231I-1502J169D01*
G03X1623275Y554163I-307J-257D01*
G02X1622181Y553432I-1235J664D01*
G01X1622002Y553414D01*
Y526530D01*
G03X1622643Y526212I400J1D01*
G02Y523818I908J-1197D01*
G03X1622002Y523500I-241J-319D01*
G01Y513115D01*
X1624960Y510156D01*
G03X1625640Y510392I283J283D01*
G02X1626000Y511175I1392J-166D01*
G03X1626008Y511708I-294J271D01*
G02X1628100Y511677I1060J918D01*
G03X1628092Y511144I294J-271D01*
G02X1627198Y508834I-1060J-918D01*
G03X1626962Y508154I47J-397D01*
G01X1627649Y507468D01*
G03X1628320Y507654I283J283D01*
G02X1630138Y505836I1458J-360D01*
G03X1629952Y505165I97J-388D01*
G01X1634402Y500715D01*
Y474075D01*
G02Y471643I-1043J-1216D01*
G01Y471074D01*
X1634432Y471025D01*
G02X1634402Y469276I-1357J-851D01*
G01Y456885D01*
X1631566Y454050D01*
X1631551Y454019D01*
G02X1631343Y453701I-1351J656D01*
G03X1631365Y453160I305J-259D01*
G02X1631393Y451070I-1065J-1059D01*
G03X1631388Y450527I291J-274D01*
G02X1629183Y450547I-1112J-1010D01*
G03X1629188Y451090I-291J274D01*
G02X1629076Y451230I1115J1007D01*
G01X1629066Y451243D01*
X1628913Y451397D01*
X1622628Y445112D01*
Y445028D01*
G02X1621224Y443624I-1402J-2D01*
G01X1621140D01*
X1613551Y436035D01*
X1613588Y435920D01*
G02X1611830Y434162I-1338J-420D01*
G01X1611715Y434199D01*
X1602672Y425155D01*
G03X1602964Y424473I283J-282D01*
G02X1601498Y423007I36J-1502D01*
G03X1600816Y423299I-400J9D01*
G01X1595140Y417623D01*
Y414396D01*
G03X1595323Y414197I200J0D01*
G02Y411203I-123J-1497D01*
G03X1595140Y411004I17J-199D01*
G01Y409792D01*
X1591371Y406023D01*
G03X1591428Y405410I283J-283D01*
G02X1589856Y402855I-847J-1240D01*
G03X1589306Y402686I-193J-350D01*
G02X1586505Y403708I-1338J682D01*
G03X1586116Y404198I-389J90D01*
G01X1584397D01*
G02X1582019I-1189J743D01*
G01X1570788D01*
X1570740Y404068D01*
G02X1568110I-1315J486D01*
G01X1568062Y404198D01*
X1565585D01*
X1563202Y406582D01*
X1563155Y406596D01*
G02X1562237Y407514I420J1338D01*
G01X1562223Y407561D01*
X1561750Y408033D01*
G03X1561070Y407791I-282J-283D01*
G02X1559532Y409329I-1395J143D01*
G03X1559774Y410009I-41J398D01*
G01X1557885Y411898D01*
X1542585D01*
X1540685Y413798D01*
X1538952D01*
Y413599D01*
G02X1536346Y412881I-1402J1D01*
G03X1535647Y412859I-343J-205D01*
G02X1533364Y412556I-1247J641D01*
G03X1532785Y412569I-296J-270D01*
G01X1532002Y411785D01*
Y406485D01*
X1531115Y405598D01*
X1528207D01*
G03X1527834Y405055I0J-400D01*
G02X1526403Y405951I-1310J-501D01*
G03X1526652Y406632I-34J398D01*
G01X1522798Y410485D01*
Y418315D01*
X1523712Y419228D01*
X1523659Y419352D01*
G02X1523572Y419644I1292J544D01*
G03X1523178I-197J-37D01*
G02X1520575Y419219I-1378J256D01*
G03X1519875I-350J-194D01*
G02X1518782Y418504I-1226J681D01*
G01X1518710Y418497D01*
X1517750Y417537D01*
Y415331D01*
G03X1518261Y414947I400J0D01*
G02X1517726Y412546I389J-1347D01*
G01X1517585Y412669D01*
X1516849Y411932D01*
G03X1517036Y411261I283J-283D01*
G02X1515317Y410132I-336J-1361D01*
G03X1514923Y410598I-394J66D01*
G01X1513757D01*
X1513751Y410405D01*
G02X1511125Y409769I-1401J45D01*
G03X1510425I-350J-194D01*
G02X1507799Y410405I-1225J681D01*
G01X1507793Y410598D01*
X1500431D01*
G02X1498019I-1206J716D01*
G01X1496531D01*
G02X1494119I-1206J716D01*
G01X1492631D01*
G02X1490219I-1206J716D01*
G01X1488731D01*
G02X1486319I-1206J716D01*
G01X1483388D01*
X1483346Y410454D01*
G02X1480654I-1346J392D01*
G01X1480612Y410598D01*
X1477708D01*
X1472508Y415798D01*
X1467915D01*
X1462702Y410585D01*
Y406246D01*
G03X1463367Y405947I400J0D01*
G02X1464441Y406295I933J-1047D01*
G03X1464881Y406710I41J398D01*
G02X1467615Y407630I1501J63D01*
G03X1468263Y407618I328J229D01*
G02X1470311Y407823I1119J-845D01*
G03X1470870Y407851I265J299D01*
G02X1470971Y405850I1030J-951D01*
G03X1470412Y405822I-265J-299D01*
G02X1468263Y405928I-1030J951D01*
G03X1467615Y405916I-320J-241D01*
G02X1466161Y405287I-1234J857D01*
G03X1465702Y404894I-59J-395D01*
G02X1465545Y404255I-1402J6D01*
G03X1465721Y403713I355J-184D01*
G02X1466233Y403293I-673J-1343D01*
G03X1466863I315J246D01*
G02X1469230Y403296I1185J-923D01*
G03X1469824Y403256I315J247D01*
G02X1469740Y401333I976J-1006D01*
G03X1469145Y401344I-302J-262D01*
G02X1466863Y401447I-1097J1026D01*
G03X1466233I-315J-246D01*
G02X1463753Y403131I-1185J923D01*
G03X1463606Y403682I-345J203D01*
G02X1463367Y403853I692J1220D01*
G03X1462702Y403554I-265J-299D01*
G01Y403485D01*
X1459715Y400498D01*
X1447185D01*
X1442710Y404973D01*
X1442642Y404982D01*
G02X1441912Y407661I188J1490D01*
G03X1442001Y408198I-245J316D01*
G02X1442198Y410100I1251J832D01*
G01Y475927D01*
G03X1442015Y476126I-200J0D01*
G02X1440940Y476721I126J1497D01*
G03X1440330Y476757I-320J-240D01*
G02X1438238Y476824I-1016J966D01*
G03X1437608Y476804I-307J-256D01*
G02X1437588Y478604I-1212J887D01*
G03X1438218Y478598I317J243D01*
G02X1440396Y478615I1096J-875D01*
G03X1441006Y478607I308J254D01*
G02X1442015Y479120I1135J-984D01*
G03X1442198Y479319I-17J199D01*
G01Y481023D01*
G03X1441808Y481422I-400J-1D01*
G02X1440538Y482179I34J1502D01*
G03X1440015Y482340I-347J-198D01*
G02X1438578Y482464I-615J1260D01*
G03X1437977Y482300I-234J-324D01*
G02X1437533Y484077I-1377J600D01*
G03X1438140Y484215I248J314D01*
G02X1440575Y484364I1260J-615D01*
G03X1441107Y484234I335J218D01*
G02X1441808Y484426I736J-1310D01*
G03X1442198Y484825I-10J400D01*
G01Y487522D01*
G03X1442004Y487721I-200J-1D01*
G02X1440884Y488265I37J1502D01*
G03X1440302Y488302I-308J-255D01*
G02X1438263Y488427I-961J1021D01*
G03X1437637Y488414I-308J-255D01*
G02Y490232I-1196J909D01*
G03X1438263Y490219I318J242D01*
G02X1440375Y490270I1078J-896D01*
G03X1440958Y490264I294J271D01*
G02X1442004Y490725I1083J-1041D01*
G03X1442198Y490924I-6J200D01*
G01Y492722D01*
G03X1442004Y492921I-200J-1D01*
G02X1440837Y493525I37J1502D01*
G03X1440269Y493600I-321J-239D01*
G02X1438425Y493692I-869J1100D01*
G03X1437810Y493619I-278J-288D01*
G02X1437632Y495456I-1269J804D01*
G03X1438250Y495502I290J275D01*
G02X1440478Y495596I1150J-802D01*
G03X1441050Y495551I308J256D01*
G02X1442004Y495925I992J-1127D01*
G03X1442198Y496124I-6J200D01*
G01Y546809D01*
G03X1441684Y547192I-400J0D01*
G02Y550070I-432J1439D01*
G03X1442198Y550453I114J383D01*
G01Y559256D01*
G37*
G36*
G01X1417025Y334544D02*
G03X1417041Y333983I293J-272D01*
G02X1414959I-1041J-1083D01*
G03X1414975Y334544I-277J289D01*
G02X1415029Y336511I1025J956D01*
G03Y337089I-277J289D01*
G02X1416971I971J1011D01*
G03Y336511I277J-289D01*
G02X1417025Y334544I-971J-1011D01*
G37*
G36*
G01X1412363Y315134D02*
G03X1411804Y315121I-273J-292D01*
G02X1411698Y317177I-1004J979D01*
G03X1412255Y317221I256J307D01*
G02X1412363Y315134I1132J-988D01*
G37*
G36*
G01X1414835Y302989D02*
G02X1412823Y303188I-1115J-1006D01*
G03X1412895Y303761I-239J321D01*
G02X1413044Y305686I1088J884D01*
G03X1412974Y306330I-268J297D01*
G02X1412958Y308928I746J1304D01*
G03X1413019Y309574I-203J345D01*
G02X1414701Y309448I925J1054D01*
G03X1414665Y308801I216J-337D01*
G02X1414682Y306480I-945J-1167D01*
G03X1414726Y305834I256J-307D01*
G02X1414877Y303565I-743J-1189D01*
G03X1414835Y302989I255J-308D01*
G37*
G36*
G01X1420292Y303036D02*
G02X1418201Y303086I-1071J-1053D01*
G03X1418230Y303644I-271J294D01*
G02X1418473Y305714I1053J926D01*
G03X1418471Y306368I-231J326D01*
G02X1418510Y308854I862J1230D01*
G03X1418524Y309514I-219J335D01*
G02X1420154Y309508I819J1138D01*
G03X1420164Y308849I232J-326D01*
G02X1420154Y306340I-831J-1251D01*
G03X1420131Y305687I219J-335D01*
G02X1420290Y303594I-848J-1117D01*
G03X1420292Y303036I287J-278D01*
G37*
G36*
G01X1409667D02*
G02X1407593Y303214I-1130J-990D01*
G03X1407657Y303772I-251J311D01*
G02X1407835Y305691I1103J865D01*
G03X1407774Y306336I-264J300D01*
G02X1407699Y308876I763J1294D01*
G03X1407721Y309524I-223J332D01*
G02X1409407Y309500I859J1108D01*
G03X1409411Y308852I236J-323D01*
G02X1409483Y306463I-874J-1222D01*
G03X1409518Y305816I252J-311D01*
G02X1409699Y303596I-758J-1179D01*
G03X1409667Y303036I269J-296D01*
G37*
G36*
G01X1412451Y321208D02*
G02X1411987Y319490I936J-1175D01*
G03X1411378Y319668I-373J-145D01*
G02X1411835Y321361I-828J1132D01*
G03X1412451Y321208I367J160D01*
G37*
G36*
G01X1409839Y336253D02*
G02X1408638Y337910I-1491J183D01*
G03X1409108Y338233I76J392D01*
G02X1409130Y338332I1379J-254D01*
G03X1408866Y338568I-194J49D01*
G02X1409775Y339789I-490J1314D01*
G03X1410244Y339368I399J-27D01*
G02X1410292Y336600I246J-1380D01*
G03X1409839Y336253I-56J-396D01*
G37*
G36*
G01X1412460Y270222D02*
G03X1412796Y269759I394J-67D01*
G02X1411098Y268524I-217J-1486D01*
G03X1410762Y268987I-394J67D01*
G02X1412460Y270222I217J1486D01*
G37*
G36*
G01X1455263Y261007D02*
G03X1455172Y260470I243J-317D01*
G02X1452695Y260212I-1172J-770D01*
G03X1452223Y260745I-373J146D01*
G02X1452837Y263332I-373J1455D01*
G03X1453363I263J302D01*
G02X1455263Y261007I987J-1133D01*
G37*
G36*
G01X1453595Y267493D02*
G02X1452725Y265728I461J-1324D01*
G03X1452214Y265980I-380J-126D01*
G02X1450528Y266623I-461J1324D01*
G03X1449828I-350J-194D01*
G02X1447378Y266622I-1225J681D01*
G03X1446679I-350J-194D01*
G02X1444773Y268529I-1225J682D01*
G03Y269229I-194J350D01*
G02X1444228Y269774I681J1226D01*
G03X1443529I-350J-195D01*
G02X1441622Y271679I-1226J680D01*
G03Y272378I-195J350D01*
G02X1443529Y274284I682J1225D01*
G03X1444229I350J194D01*
G02X1444773Y274828I1225J-681D01*
G03Y275528I-194J350D01*
G02X1444772Y277978I681J1225D01*
G03Y278677I-194J350D01*
G02X1444229Y279221I683J1224D01*
G03X1443529I-350J-194D01*
G02Y280583I-1225J681D01*
G03X1444229I350J194D01*
G02X1446679Y280584I1225J-681D01*
G03X1447378I349J194D01*
G02X1447923Y281128I1225J-682D01*
G03Y281827I-195J349D01*
G02X1447921Y284278I680J1226D01*
G03Y284977I-194J350D01*
G02Y287427I682J1225D01*
G03Y288126I-194J350D01*
G02X1447378Y288669I682J1225D01*
G03X1446679I-350J-194D01*
G02X1444229I-1225J682D01*
G03X1443530I-350J-194D01*
G02X1441622Y290575I-1226J681D01*
G03Y291274I-194J349D01*
G02X1443513Y293209I682J1225D01*
G03X1444206Y293215I345J203D01*
G02X1444711Y293731I1221J-689D01*
G03Y294419I-205J344D01*
G02X1444774Y296864I716J1205D01*
G03X1444780Y297569I-187J354D01*
G02X1444773Y300023I674J1229D01*
G03Y300723I-194J350D01*
G02Y303173I681J1225D01*
G03Y303873I-194J350D01*
G02X1444229Y304417I681J1225D01*
G03X1443529I-350J-194D01*
G02X1441622Y306323I-1225J681D01*
G03Y307022I-194J350D01*
G02X1441623Y309472I682J1225D01*
G03Y310172I-194J350D01*
G02X1443529Y312078I681J1225D01*
G03X1444229I350J194D01*
G02X1446679Y312079I1225J-681D01*
G03X1447378I349J194D01*
G02X1447921Y312622I1225J-682D01*
G03Y313321I-194J350D01*
G02X1447922Y315771I682J1225D01*
G03Y316471I-194J350D01*
G02X1449828Y318377I681J1225D01*
G03X1450528I350J194D01*
G02X1452982Y318370I1225J-681D01*
G03X1453687Y318376I351J192D01*
G02X1455580Y316482I1241J-653D01*
G03X1455574Y315776I185J-355D01*
G02X1456127Y315227I-672J-1230D01*
G03X1456827I350J194D01*
G02X1459277I1225J-681D01*
G03X1459977I350J194D01*
G02X1461884Y313321I1225J-681D01*
G03Y312622I194J-350D01*
G02X1462427Y312079I-682J-1225D01*
G03X1463126I349J194D01*
G02X1465032Y310171I1225J-682D01*
G03Y309472I194J-350D01*
G02Y307022I-682J-1225D01*
G03Y306323I195J-350D01*
G02Y303873I-681J-1225D01*
G03Y303173I194J-350D01*
G02X1463126Y301266I-681J-1225D01*
G03X1462427I-350J-194D01*
G02X1459976Y301268I-1225J682D01*
G03X1459277I-350J-194D01*
G02X1458732Y300723I-1226J681D01*
G03Y300024I194J-350D01*
G02X1458734Y297573I-680J-1226D01*
G03Y296874I194J-349D01*
G02X1456827Y294968I-682J-1225D01*
G03X1456127I-350J-194D01*
G02X1455618Y294444I-1225J681D01*
G03X1455585Y293778I204J-344D01*
G02X1454035Y293856I-834J-1127D01*
G03X1454068Y294522I-204J344D01*
G02X1453676Y294969I834J1127D01*
G03X1452977I-350J-195D01*
G02X1450521Y294975I-1226J680D01*
G03X1449817Y294970I-351J-192D01*
G02X1447352Y294943I-1240J654D01*
G03X1446652I-350J-194D01*
G02X1446143Y294419I-1225J681D01*
G03Y293731I205J-344D01*
G02X1446101Y291297I-716J-1205D01*
G03X1446107Y290592I192J-351D01*
G02X1446679Y290033I-653J-1241D01*
G03X1447378I349J194D01*
G02X1449828Y290032I1225J-682D01*
G03X1450528I350J194D01*
G02X1452978Y290033I1225J-681D01*
G03X1453677I349J194D01*
G02X1456127Y290032I1225J-682D01*
G03X1456827I350J194D01*
G02X1458734Y288126I1225J-681D01*
G03Y287427I194J-350D01*
G02X1458732Y284976I-682J-1225D01*
G03Y284277I194J-350D01*
G02X1459277Y283732I-681J-1226D01*
G03X1459976I349J194D01*
G02X1462427Y283734I1226J-680D01*
G03X1463126I349J194D01*
G02X1465032Y281827I1225J-682D01*
G03Y281127I194J-350D01*
G02X1465033Y278677I-681J-1225D01*
G03Y277978I194J-350D01*
G02X1465109Y275573I-682J-1225D01*
G03X1465125Y274890I216J-337D01*
G02X1463666Y274856I-702J-1214D01*
G03X1463650Y275539I-216J337D01*
G02X1463126Y276071I701J1214D01*
G03X1462427I-350J-194D01*
G02X1461883Y275528I-1224J683D01*
G03Y274828I194J-350D01*
G02X1459977Y272922I-681J-1225D01*
G03X1459277I-350J-194D01*
G02X1458715Y272368I-1225J681D01*
G03X1458726Y271657I189J-353D01*
G02X1459346Y271048I-624J-1255D01*
G03X1460056Y271047I355J184D01*
G02Y269754I1244J-646D01*
G03X1459346Y269755I-355J-184D01*
G02X1456847Y269778I-1244J647D01*
G03X1456136Y269789I-358J-178D01*
G02X1453677Y269772I-1234J665D01*
G03X1452978I-350J-194D01*
G02X1452434Y269229I-1224J683D01*
G03Y268529I194J-350D01*
G02X1453084Y267745I-681J-1226D01*
G03X1453595Y267493I380J126D01*
G37*
G36*
G01X1404765Y509727D02*
G03X1404135I-315J-246D01*
G02Y511573I-1185J923D01*
G03X1404765I315J246D01*
G02X1406063Y512148I1185J-923D01*
G03X1406491Y512592I31J399D01*
G02X1407841Y511350I1393J159D01*
G03X1407433Y510887I-13J-400D01*
G02X1404765Y509727I-1483J-237D01*
G37*
G36*
G01X1390389Y388000D02*
G03X1390877Y387664I396J53D01*
G02X1389821Y386045I323J-1364D01*
G03X1389317Y386357I-393J-72D01*
G02X1390389Y388000I-417J1443D01*
G37*
G36*
G01X1347898Y322736D02*
G03X1348462Y322488I385J110D01*
G02X1347673Y320797I672J-1343D01*
G03X1347121Y321070I-389J-93D01*
G02X1347898Y322736I-571J1280D01*
G37*
G36*
G01X1402557Y320058D02*
G03X1402014Y319787I-155J-369D01*
G02X1401204Y321513I-1456J370D01*
G03X1401759Y321758I172J361D01*
G02X1402557Y320058I1341J-408D01*
G37*
G36*
G01X1390804Y320819D02*
G03X1391374Y320695I343J205D01*
G02X1390899Y318754I852J-1237D01*
G03X1390336Y318907I-353J-188D01*
G02X1390804Y320819I-736J1193D01*
G37*
G36*
G01X1399769Y315079D02*
G03X1399226Y314962I-211J-340D01*
G02X1398731Y316975I-1164J781D01*
G03X1399266Y317123I191J352D01*
G02X1399769Y315079I1292J-766D01*
G37*
G36*
G01X1382261Y316591D02*
G03X1382848Y316432I361J171D01*
G02X1382401Y314616I791J-1158D01*
G03X1381808Y314747I-353J-189D01*
G02X1382261Y316591I-904J1200D01*
G37*
G36*
G01X1391309Y314468D02*
G03X1390740Y314384I-244J-317D01*
G02X1390397Y316354I-1140J816D01*
G03X1390961Y316467I227J329D01*
G02X1391309Y314468I1265J-810D01*
G37*
G36*
G01X1350557Y316957D02*
G03X1350873Y316434I379J-128D01*
G02X1349302Y315436I-223J-1384D01*
G03X1348963Y315944I-384J111D01*
G02X1350557Y316957I171J1492D01*
G37*
G36*
G01X1361610Y315749D02*
G03X1362204Y315625I350J193D01*
G02X1361863Y313782I855J-1111D01*
G03X1361264Y313878I-341J-209D01*
G02X1361610Y315749I-970J1147D01*
G37*
G36*
G01X1370774Y313927D02*
G03X1370303Y313637I-84J-391D01*
G02X1369164Y315378I-1356J356D01*
G03X1369618Y315694I62J395D01*
G02X1370774Y313927I1472J-299D01*
G37*
G36*
G01X1399674Y283320D02*
G03X1399796Y282806I353J-188D01*
G02X1397599Y282285I-870J-1224D01*
G03X1397477Y282799I-353J188D01*
G02X1399674Y283320I870J1224D01*
G37*
G36*
G01X1405610Y282190D02*
G02X1402927Y282075I-1324J-461D01*
G03X1402446Y282562I-387J98D01*
G02X1403439Y284686I-354J1460D01*
G03X1404152Y284676I359J176D01*
G02X1405856Y282699I1240J-654D01*
G03X1405610Y282190I132J-378D01*
G37*
G36*
G01X1357762Y285750D02*
G02X1357711Y284129I1238J-850D01*
G03X1357038Y284150I-343J-206D01*
G02X1354457Y284326I-1239J850D01*
G03X1353743I-357J-179D01*
G02Y285674I-1343J674D01*
G03X1354457I357J179D01*
G02X1357089Y285771I1343J-674D01*
G03X1357762Y285750I343J206D01*
G37*
G36*
G01X1359537Y301915D02*
G02X1357727Y302094I-1023J-1100D01*
G03X1357802Y302716I-210J341D01*
G02X1357863Y304743I998J984D01*
G03X1357796Y305388I-267J298D01*
G02X1357836Y308015I748J1302D01*
G03X1357902Y308677I-188J353D01*
G02X1359497Y308548I890J1083D01*
G03X1359455Y307884I201J-346D01*
G02X1359503Y305534I-911J-1194D01*
G03X1359546Y304887I255J-308D01*
G02X1359586Y302539I-746J-1187D01*
G03X1359537Y301915I224J-331D01*
G37*
G36*
G01X1365010Y301939D02*
G02X1363182Y302066I-996J-1124D01*
G03X1363238Y302686I-222J333D01*
G02X1363307Y304764I975J1008D01*
G03X1363258Y305410I-258J305D01*
G02X1363187Y307924I786J1280D01*
G03X1363200Y308572I-228J329D01*
G02X1364888I844J1119D01*
G03X1364901Y307924I241J-319D01*
G02X1364969Y305507I-857J-1234D01*
G03X1364993Y304859I246J-315D01*
G02X1365040Y302562I-780J-1165D01*
G03X1365010Y301939I235J-324D01*
G37*
G36*
G01X1370305Y302353D02*
G02X1368516Y302488I-985J-1134D01*
G03X1368577Y303116I-214J338D01*
G02X1368624Y305196I963J1019D01*
G03X1368568Y305842I-262J303D01*
G02Y308418I772J1288D01*
G03X1368624Y309064I-206J343D01*
G02X1370307Y308952I916J1061D01*
G03X1370277Y308304I219J-335D01*
G02Y305956I-937J-1174D01*
G03X1370307Y305308I249J-313D01*
G02X1370339Y302983I-767J-1173D01*
G03X1370305Y302353I229J-328D01*
G37*
G36*
G01X1375805D02*
G02X1374016Y302488I-985J-1134D01*
G03X1374077Y303116I-214J338D01*
G02X1374124Y305196I963J1019D01*
G03X1374068Y305842I-262J303D01*
G02X1374008Y308380I772J1288D01*
G03X1374033Y309028I-222J333D01*
G02X1375722Y308994I867J1102D01*
G03X1375721Y308346I234J-324D01*
G02X1375777Y305956I-881J-1216D01*
G03X1375807Y305308I249J-313D01*
G02X1375839Y302983I-767J-1173D01*
G03X1375805Y302353I229J-328D01*
G37*
G36*
G01X1381684Y302506D02*
G02X1379929Y302808I-1083J-1041D01*
G03X1380050Y303431I-179J358D01*
G02X1380065Y305305I1050J929D01*
G03X1379933Y305940I-296J270D01*
G02X1379852Y308641I615J1370D01*
G03X1379943Y309285I-185J355D01*
G02X1381607Y309084I967J1015D01*
G03X1381541Y308437I199J-347D01*
G02X1381617Y306255I-993J-1127D01*
G03X1381724Y305616I285J-281D01*
G02X1381779Y303133I-624J-1256D01*
G03X1381684Y302506I193J-350D01*
G37*
G36*
G01X1387101Y302586D02*
G02X1385237Y302693I-999J-1121D01*
G03X1385286Y303307I-230J327D01*
G02X1385346Y305369I979J1003D01*
G03X1385286Y306015I-263J301D01*
G02X1385191Y308543I762J1294D01*
G03X1385203Y309191I-229J328D01*
G02X1386893I845J1119D01*
G03X1386905Y308543I241J-320D01*
G02X1386988Y306138I-857J-1234D01*
G03X1387022Y305490I250J-312D01*
G02X1387122Y303201I-757J-1180D01*
G03X1387101Y302586I245J-316D01*
G37*
G36*
G01X1404179Y303021D02*
G02X1402114Y303231I-1142J-975D01*
G03X1402186Y303789I-246J315D01*
G02X1402361Y305681I1114J851D01*
G03X1402292Y306326I-267J298D01*
G02X1402274Y308924I745J1304D01*
G03X1402335Y309569I-203J345D01*
G02X1404018Y309444I924J1054D01*
G03X1403983Y308797I217J-336D01*
G02X1403998Y306476I-946J-1167D01*
G03X1404042Y305829I256J-308D01*
G02X1404221Y303583I-742J-1189D01*
G03X1404179Y303021I262J-302D01*
G37*
G36*
G01X1393273Y303031D02*
G02X1391201Y303227I-1138J-980D01*
G03X1391269Y303785I-249J313D01*
G02X1391447Y305686I1111J855D01*
G03X1391381Y306331I-266J299D01*
G02X1391365Y308920I754J1299D01*
G03X1391422Y309565I-205J343D01*
G02X1393105Y309450I918J1060D01*
G03X1393073Y308803I218J-335D01*
G02X1393090Y306471I-938J-1173D01*
G03X1393130Y305824I254J-309D01*
G02X1393311Y303591I-750J-1185D01*
G03X1393273Y303031I265J-299D01*
G37*
G36*
G01X1398773D02*
G02X1396701Y303227I-1138J-980D01*
G03X1396769Y303785I-249J313D01*
G02X1396947Y305686I1111J855D01*
G03X1396881Y306331I-266J299D01*
G02X1396780Y308865I754J1299D01*
G03X1396794Y309513I-227J329D01*
G02X1398482Y309510I846J1118D01*
G03X1398494Y308862I240J-320D01*
G02X1398590Y306471I-859J-1232D01*
G03X1398630Y305824I254J-309D01*
G02X1398811Y303591I-750J-1185D01*
G03X1398773Y303031I265J-299D01*
G37*
G36*
G01X1354120Y304944D02*
G02X1352436Y304822I-761J-1177D01*
G03X1352377Y305468I-263J302D01*
G02X1352285Y307994I765J1293D01*
G03X1352298Y308642I-228J329D01*
G02X1353986I844J1119D01*
G03X1353999Y307994I241J-319D01*
G02X1354086Y305592I-857J-1234D01*
G03X1354120Y304944I251J-312D01*
G37*
G36*
G01X1348816Y305065D02*
G02X1347155Y304756I-626J-1255D01*
G03X1347025Y305391I-295J270D01*
G02X1347027Y308130I617J1369D01*
G03X1347134Y308791I-163J366D01*
G02X1348699Y308567I947J1034D01*
G03X1348616Y307903I176J-359D01*
G02X1348710Y305704I-974J-1143D01*
G03X1348816Y305065I284J-281D01*
G37*
G36*
G01X1359301Y319952D02*
G02X1358943Y318168I993J-1127D01*
G03X1358333Y318304I-359J-175D01*
G02X1356112Y319807I-881J1091D01*
G03X1355634Y320313I-382J118D01*
G02X1356640Y321263I-334J1362D01*
G03X1357118Y320757I382J-118D01*
G02X1358685Y320062I334J-1362D01*
G03X1359301Y319952I352J190D01*
G37*
G36*
G01X1371785Y320527D02*
G02X1370322Y320486I-695J-1332D01*
G03X1370313Y321178I-205J343D01*
G02X1371755Y321218I688J1222D01*
G03X1371785Y320527I215J-337D01*
G37*
G36*
G01X1382298Y319187D02*
G02X1382066Y320699I-1394J560D01*
G03X1382741Y320791I309J253D01*
G02X1382970Y319301I1283J-565D01*
G03X1382298Y319187I-301J-263D01*
G37*
G36*
G01X1381031Y264088D02*
X1377522D01*
G02X1376399Y264588I0J1511D01*
G03X1375828Y264611I-297J-268D01*
G02X1375850Y266626I-964J1018D01*
G03X1376422Y266636I281J285D01*
G02X1377522Y267112I1101J-1036D01*
G01X1381032D01*
G02X1382185Y266576I-2J-1512D01*
G03X1382771Y266549I306J258D01*
G02X1382733Y264586I982J-1001D01*
G03X1382147Y264581I-291J-275D01*
G02X1381031Y264088I-1117J1019D01*
G37*
G36*
G01X1366314Y267036D02*
G02X1367481Y266484I-1J-1512D01*
G03X1368081Y266463I309J253D01*
G02X1368064Y264556I1019J-963D01*
G03X1367463Y264546I-296J-269D01*
G02X1366312Y264014I-1151J979D01*
G01X1362803D01*
G02Y267036I1J1511D01*
G01X1366314D01*
G37*
G36*
G01X1388307Y232175D02*
G02X1387178Y230376I211J-1386D01*
G03X1386713Y230649I-382J-118D01*
G02X1385462Y233291I-313J1469D01*
G03X1385476Y233905I-249J313D01*
G02X1385525Y236054I924J1054D01*
G03X1385511Y236689I-250J312D01*
G02X1387289I889J1211D01*
G03X1387275Y236054I236J-323D01*
G02X1387324Y233905I-875J-1095D01*
G03X1387338Y233291I263J-301D01*
G02X1387859Y232475I-938J-1173D01*
G03X1388307Y232175I388J95D01*
G37*
G36*
G01X1348838Y233291D02*
G02X1346962I-938J-1173D01*
G03X1346976Y233905I-249J313D01*
G02X1347025Y236054I924J1054D01*
G03X1347011Y236689I-250J312D01*
G02X1348789I889J1211D01*
G03X1348775Y236054I236J-323D01*
G02X1348824Y233905I-875J-1095D01*
G03X1348838Y233291I263J-301D01*
G37*
G36*
G01X1354338D02*
G02X1352462I-938J-1173D01*
G03X1352476Y233905I-249J313D01*
G02X1352525Y236054I924J1054D01*
G03X1352511Y236689I-250J312D01*
G02X1354289I889J1211D01*
G03X1354275Y236054I236J-323D01*
G02X1354324Y233905I-875J-1095D01*
G03X1354338Y233291I263J-301D01*
G37*
G36*
G01X1359838D02*
G02X1357962I-938J-1173D01*
G03X1357976Y233905I-249J313D01*
G02X1358025Y236054I924J1054D01*
G03X1358011Y236689I-250J312D01*
G02X1359789I889J1211D01*
G03X1359775Y236054I236J-323D01*
G02X1359824Y233905I-875J-1095D01*
G03X1359838Y233291I263J-301D01*
G37*
G36*
G01X1365338D02*
G02X1363462I-938J-1173D01*
G03X1363476Y233905I-249J313D01*
G02X1363525Y236054I924J1054D01*
G03X1363511Y236689I-250J312D01*
G02X1365289I889J1211D01*
G03X1365275Y236054I236J-323D01*
G02X1365324Y233905I-875J-1095D01*
G03X1365338Y233291I263J-301D01*
G37*
G36*
G01X1370838D02*
G02X1368962I-938J-1173D01*
G03X1368976Y233905I-249J313D01*
G02X1369025Y236054I924J1054D01*
G03X1369011Y236689I-250J312D01*
G02X1370789I889J1211D01*
G03X1370775Y236054I236J-323D01*
G02X1370824Y233905I-875J-1095D01*
G03X1370838Y233291I263J-301D01*
G37*
G36*
G01X1376267Y233344D02*
G02X1374533I-867J-1226D01*
G03X1374546Y233988I-231J327D01*
G02X1374457Y236138I854J1112D01*
G03X1374443Y236742I-269J296D01*
G02X1376357I957J1158D01*
G03X1376343Y236138I255J-308D01*
G02X1376254Y233988I-943J-1038D01*
G03X1376267Y233344I244J-317D01*
G37*
G36*
G01X1381838Y233291D02*
G02X1379962I-938J-1173D01*
G03X1379976Y233905I-249J313D01*
G02X1380025Y236054I924J1054D01*
G03X1380011Y236689I-250J312D01*
G02X1381789I889J1211D01*
G03X1381775Y236054I236J-323D01*
G02X1381824Y233905I-875J-1095D01*
G03X1381838Y233291I263J-301D01*
G37*
G36*
G01X1392838D02*
G02X1390962I-938J-1173D01*
G03X1390976Y233905I-249J313D01*
G02X1391025Y236054I924J1054D01*
G03X1391011Y236689I-250J312D01*
G02X1392789I889J1211D01*
G03X1392775Y236054I236J-323D01*
G02X1392824Y233905I-875J-1095D01*
G03X1392838Y233291I263J-301D01*
G37*
G36*
G01X1398902Y232107D02*
G02X1396462Y233291I-1502J11D01*
G03X1396476Y233905I-249J313D01*
G02X1396525Y236054I924J1054D01*
G03X1396511Y236689I-250J312D01*
G02X1398902Y237905I889J1211D01*
G03X1399472Y237544I400J1D01*
G02X1401041Y235266I594J-1270D01*
G03X1401021Y234712I278J-287D01*
G02X1399452Y232475I-1043J-937D01*
G03X1398902Y232107I-150J-371D01*
G37*
G36*
G01X1339545Y320535D02*
G03X1340165Y320565I298J267D01*
G02X1340213Y318723I1210J-890D01*
G03X1339592Y318721I-310J-253D01*
G02X1339545Y320535I-1092J879D01*
G37*
G36*
G01X1335519Y293051D02*
G03X1336108Y293043I298J267D01*
G02X1336081Y291011I1092J-1031D01*
G03X1335492Y291019I-298J-267D01*
G02X1335519Y293051I-1092J1031D01*
G37*
G36*
G01X1321261Y296163D02*
G02X1320120Y294957I339J-1463D01*
G03X1319636Y295415I-394J68D01*
G02X1320777Y296621I-339J1463D01*
G03X1321261Y296163I394J-68D01*
G37*
G36*
G01X1337487Y302080D02*
G02X1335453Y302523I-1247J-837D01*
G03X1335588Y303068I-209J341D01*
G02X1335771Y304743I1205J716D01*
G03X1335639Y305384I-292J274D01*
G02X1335487Y308059I601J1376D01*
G03X1335551Y308705I-201J346D01*
G02X1337230Y308570I929J1050D01*
G03X1337191Y307923I214J-338D01*
G02X1337295Y305691I-951J-1163D01*
G03X1337403Y305047I282J-284D01*
G02X1337592Y302632I-610J-1263D01*
G03X1337487Y302080I227J-329D01*
G37*
G36*
G01X1343005Y302053D02*
G02X1341089Y302597I-1265J-810D01*
G03X1341263Y303156I-173J360D01*
G02X1341386Y304729I1217J696D01*
G03X1341214Y305353I-312J250D01*
G02X1340958Y308043I526J1407D01*
G03X1341010Y308688I-208J341D01*
G02X1341136Y310917I910J1067D01*
G03X1341264Y311438I-224J331D01*
G02X1341223Y312679I1236J662D01*
G03X1340967Y313229I-364J165D01*
G02X1342713Y313992I408J1446D01*
G03X1342943Y313430I356J-182D01*
G02X1343284Y310938I-443J-1330D01*
G03X1343156Y310417I224J-331D01*
G02X1342696Y308587I-1236J-662D01*
G03X1342670Y307940I221J-333D01*
G02X1342875Y305776I-930J-1180D01*
G03X1343022Y305145I302J-262D01*
G02X1343150Y302621I-542J-1293D01*
G03X1343005Y302053I191J-351D01*
G37*
G36*
G01X1321324Y233905D02*
G03X1321338Y233291I263J-301D01*
G02X1319462I-938J-1173D01*
G03X1319476Y233905I-249J313D01*
G02X1319380Y235921I924J1054D01*
G03X1319341Y236506I-291J274D01*
G02X1321329Y236587I948J1165D01*
G03X1321338Y236001I277J-289D01*
G02X1321324Y233905I-938J-1042D01*
G37*
G36*
G01X1315824D02*
G03X1315838Y233291I263J-301D01*
G02X1313962I-938J-1173D01*
G03X1313976Y233905I-249J313D01*
G02X1313988Y236024I924J1054D01*
G03X1314017Y236605I-260J304D01*
G02X1316017Y236456I1083J1040D01*
G03X1315960Y235877I245J-316D01*
G02X1315824Y233905I-1060J-918D01*
G37*
G36*
G01X1326838Y233291D02*
G02X1324962I-938J-1173D01*
G03X1324976Y233905I-249J313D01*
G02X1325025Y236054I924J1054D01*
G03X1325011Y236689I-250J312D01*
G02X1326789I889J1211D01*
G03X1326775Y236054I236J-323D01*
G02X1326824Y233905I-875J-1095D01*
G03X1326838Y233291I263J-301D01*
G37*
G36*
G01X1332338D02*
G02X1330462I-938J-1173D01*
G03X1330476Y233905I-249J313D01*
G02X1330525Y236054I924J1054D01*
G03X1330511Y236689I-250J312D01*
G02X1332289I889J1211D01*
G03X1332275Y236054I236J-323D01*
G02X1332324Y233905I-875J-1095D01*
G03X1332338Y233291I263J-301D01*
G37*
G36*
G01X1337838D02*
G02X1335962I-938J-1173D01*
G03X1335976Y233905I-249J313D01*
G02X1336025Y236054I924J1054D01*
G03X1336011Y236689I-250J312D01*
G02X1337789I889J1211D01*
G03X1337775Y236054I236J-323D01*
G02X1337824Y233905I-875J-1095D01*
G03X1337838Y233291I263J-301D01*
G37*
G36*
G01X1343338D02*
G02X1341462I-938J-1173D01*
G03X1341476Y233905I-249J313D01*
G02X1341525Y236054I924J1054D01*
G03X1341511Y236689I-250J312D01*
G02X1343289I889J1211D01*
G03X1343275Y236054I236J-323D01*
G02X1343324Y233905I-875J-1095D01*
G03X1343338Y233291I263J-301D01*
G37*
G36*
G01X1309929Y256611D02*
G02X1309831Y254805I1021J-961D01*
G03X1309221Y254839I-319J-241D01*
G02X1306892Y256305I-1021J961D01*
G03X1306534Y256849I-373J144D01*
G02X1307893Y257745I51J1401D01*
G03X1308251Y257201I373J-144D01*
G02X1309319Y256645I-51J-1401D01*
G03X1309929Y256611I319J241D01*
G37*
G36*
G01X1343668Y266584D02*
G02X1342283Y267491I0J1511D01*
G03X1341683Y267656I-367J-160D01*
G02X1339726Y269611I-817J1139D01*
G03X1339401Y270244I-325J233D01*
G01X1336448D01*
G02X1334967Y271453I0J1511D01*
G03X1334473Y271760I-392J-80D01*
G02X1332951Y273900I-360J1355D01*
G03X1332620Y274524I-331J224D01*
G01X1330170D01*
G02X1329128Y274941I0J1511D01*
G03X1328580Y274944I-276J-290D01*
G02X1328527Y277044I-955J1027D01*
G03X1329074Y277075I257J307D01*
G02X1330170Y277546I1096J-1040D01*
G01X1333681D01*
G02X1335192Y276045I0J-1512D01*
G01Y275950D01*
X1335182Y275866D01*
G02X1334740Y274957I-1502J168D01*
G03X1334819Y274326I280J-285D01*
G02X1335469Y273471I-706J-1211D01*
G03X1335980Y273192I387J101D01*
G02X1336446Y273266I467J-1437D01*
G01X1340249D01*
G02X1341760Y271765I0J-1512D01*
G01Y271670D01*
X1341750Y271586D01*
G02X1341337Y270707I-1502J169D01*
G03X1341457Y270067I288J-277D01*
G02X1342123Y269416I-592J-1271D01*
G03X1342730Y269280I358J177D01*
G02X1343667Y269606I938J-1185D01*
G01X1347469D01*
G02X1348980Y268105I0J-1512D01*
G01Y268010D01*
X1348970Y267926D01*
G02X1348834Y267447I-1502J168D01*
G03X1349263Y266882I361J-171D01*
G02X1350545Y266435I237J-1382D01*
G03X1351183Y266491I298J267D01*
G02X1352468Y267206I1285J-797D01*
G01X1356269D01*
G02X1357476Y266603I-1J-1511D01*
G03X1358085Y266568I319J241D01*
G02X1358023Y264703I1015J-967D01*
G03X1357413Y264708I-307J-256D01*
G02X1356269Y264184I-1144J987D01*
G01X1352467D01*
G02X1351298Y264738I0J1511D01*
G03X1350658Y264710I-310J-253D01*
G02X1348215Y266062I-1159J790D01*
G03X1347769Y266614I-366J160D01*
G02X1347471Y266584I-300J1481D01*
G01X1343668D01*
G37*
G36*
G01X1327244Y281174D02*
G02X1328422Y280609I0J-1511D01*
G03X1329023Y280584I311J251D01*
G02X1328993Y278685I1016J-966D01*
G03X1328390Y278679I-299J-266D01*
G02X1327243Y278152I-1147J984D01*
G01X1323734D01*
G02X1322936Y280946I0J1511D01*
G03X1322763Y281305I-106J170D01*
G02X1322260Y281218I-505J1425D01*
G01X1318751D01*
G02X1318025Y281404I0J1512D01*
G03X1317493Y281263I-192J-351D01*
G02X1314898Y281969I-1193J737D01*
G03X1314497Y282360I-400J-9D01*
G02X1313514Y285004I-7J1502D01*
G03X1313578Y285543I-260J304D01*
G02X1315768Y285285I1214J884D01*
G03X1315704Y284746I260J-304D01*
G02X1315991Y283813I-1214J-884D01*
G03X1316371Y283400I400J-13D01*
G02X1316896Y283269I-71J-1400D01*
G03X1317418Y283443I169J362D01*
G02X1318751Y284242I1333J-713D01*
G01X1322261D01*
G02X1323551Y283517I-1J-1512D01*
G03X1324205Y283475I342J208D01*
G02X1326453Y281802I1095J-876D01*
G03X1326782Y281174I329J-228D01*
G01X1327244D01*
G37*
G36*
G01X1967942Y73987D02*
G03X1967505Y73439I-68J-394D01*
G02X1965028Y73648I-1293J-542D01*
G03X1964910Y74197I-338J215D01*
G02X1964708Y76380I769J1172D01*
G03Y76958I-277J289D01*
G02X1964669Y78942I971J1011D01*
G03Y79496I-288J277D01*
G02Y81442I1010J973D01*
G03Y81996I-288J277D01*
G02X1966689I1010J973D01*
G03Y81442I288J-277D01*
G02X1966773Y81346I-1012J-970D01*
G03X1967085I156J125D01*
G02X1969152Y81479I1094J-877D01*
G03X1969706I277J288D01*
G02X1971689Y79496I973J-1010D01*
G03Y78942I288J-277D01*
G02X1971650Y76958I-1010J-973D01*
G03Y76380I277J-289D01*
G02X1969706Y74359I-972J-1010D01*
G03X1969152I-277J-288D01*
G02X1967942Y73987I-973J1010D01*
G37*
G36*
G01X1968220Y228637D02*
G03X1967580I-320J-240D01*
G02Y230563I-1280J963D01*
G03X1968220I320J240D01*
G02Y228637I1280J-963D01*
G37*
G36*
G01X1962867Y165901D02*
G02X1961207Y167137I-1395J-141D01*
G03X1961523Y167611I-75J393D01*
G02X1964688Y167794I1569J324D01*
G03X1965283Y167410I398J-36D01*
G02X1964572Y166237I690J-1220D01*
G03X1963956Y166587I-400J13D01*
G02X1963230Y166340I-864J1349D01*
G03X1962867Y165901I35J-398D01*
G37*
G36*
G01X1965972Y148420D02*
G03X1965767Y147900I164J-365D01*
G02X1962882Y147402I-1385J-582D01*
G03X1962550Y147819I-399J23D01*
G02X1963725Y150483I250J1481D01*
G03X1964289Y150555I246J315D01*
G02X1965043Y151056I1111J-855D01*
G03X1965293Y151634I-101J387D01*
G02X1966979Y150822I1407J766D01*
G03X1966682Y150267I69J-394D01*
G02X1965972Y148420I-1282J-567D01*
G37*
G36*
G01X1935796Y241766D02*
G03Y241234I298J-266D01*
G02X1933704I-1046J-934D01*
G03Y241766I-298J266D01*
G02X1935796I1046J934D01*
G37*
G36*
G01X1927049Y232850D02*
G03X1927104Y232317I323J-236D01*
G02X1924886Y232085I-1004J-1117D01*
G03X1924831Y232618I-323J236D01*
G02X1927049Y232850I1004J1117D01*
G37*
G36*
G01X1939229Y229179D02*
G03X1939773Y229172I276J290D01*
G02X1939745Y226821I1074J-1188D01*
G03X1939201Y226828I-276J-290D01*
G02X1939229Y229179I-1074J1188D01*
G37*
G36*
G01X1904020Y224655D02*
G03X1903981Y224099I266J-298D01*
G02X1901919Y224188I-1072J-904D01*
G03X1901927Y224745I-283J283D01*
G02X1901925Y226805I1093J1031D01*
G03X1901928Y227350I-291J274D01*
G02X1902025Y229482I1104J1018D01*
G03X1901999Y230098I-268J297D01*
G02X1903914Y230180I908J1196D01*
G03X1903940Y229564I268J-297D01*
G02X1904127Y227339I-908J-1197D01*
G03X1904124Y226794I291J-274D01*
G02X1904020Y224655I-1104J-1018D01*
G37*
G36*
G01X1946998Y228611D02*
G03X1946489Y228996I-400J0D01*
G02X1946228Y228947I-388J1347D01*
G03X1945863Y228529I34J-398D01*
G02X1945635Y227689I-1400J-71D01*
G03X1945738Y227143I334J-220D01*
G02X1945155Y224618I-813J-1142D01*
G03X1944843Y224093I66J-394D01*
G02X1944461Y222601I-1326J-455D01*
G03X1944413Y222063I270J-295D01*
G02X1942272Y222322I-1196J-909D01*
G03X1942353Y222856I-251J311D01*
G02X1943287Y225020I1164J781D01*
G03X1943599Y225545I-66J394D01*
G02X1943753Y226770I1326J455D01*
G03X1943650Y227316I-334J220D01*
G02X1944340Y229855I813J1142D01*
G03X1944705Y230273I-34J398D01*
G02X1947162Y231265I1400J71D01*
G03X1947762Y231261I302J263D01*
G02X1953002Y229261I2238J-2000D01*
G01Y228061D01*
G02X1946998I-3002J0D01*
G01Y228611D01*
G37*
G36*
G01X1944146Y216465D02*
G03X1944128Y215851I247J-315D01*
G02X1942284Y215862I-928J-1051D01*
G03X1942274Y216476I-261J303D01*
G02X1944146Y216465I943J1169D01*
G37*
G36*
G01X1927510Y211417D02*
G03X1926977Y211395I-254J-309D01*
G02X1926890Y213483I-977J1005D01*
G03X1927423Y213505I254J309D01*
G02X1927510Y211417I977J-1005D01*
G37*
G36*
G01X1910152Y203101D02*
G03X1910048Y202502I204J-344D01*
G02X1908253Y202815I-1081J-893D01*
G03X1908357Y203414I-204J344D01*
G02X1910152Y203101I1081J893D01*
G37*
G36*
G01X1910882Y218645D02*
G02X1909536Y218731I-759J-1296D01*
G03X1909581Y219445I-157J368D01*
G02X1909154Y221663I759J1296D01*
G03X1909114Y222198I-316J245D01*
G02X1909022Y224423I1105J1160D01*
G03X1909009Y224969I-299J266D01*
G02X1911350Y225025I1144J1121D01*
G03X1911363Y224479I299J-266D01*
G02X1911426Y222305I-1144J-1121D01*
G03X1911436Y221768I301J-263D01*
G02X1910927Y219359I-1096J-1027D01*
G03X1910882Y218645I157J-368D01*
G37*
G36*
G01X1910116Y210136D02*
G02X1908533Y210016I-695J-1331D01*
G03X1908494Y210687I-236J323D01*
G02X1910054Y210805I692J1219D01*
G03X1910116Y210136I247J-314D01*
G37*
G36*
G01X1949998Y204492D02*
G02X1946598Y207893I1J3401D01*
G01Y210293D01*
G02X1953251Y211294I3402J0D01*
G01X1953988D01*
Y211497D01*
G02X1955411Y214032I2902J38D01*
G03X1955563Y214558I-204J344D01*
G02X1956059Y216485I1338J683D01*
G03Y217147I-224J331D01*
G02X1957743I842J1244D01*
G03Y216485I224J-331D01*
G02X1958235Y214550I-842J-1244D01*
G03X1958384Y214023I355J-184D01*
G02X1959541Y212715I-1494J-2488D01*
G03X1960200Y212606I365J163D01*
G02X1959928Y209839I1690J-1563D01*
G03X1959260Y209861I-341J-209D01*
G02X1957785Y208775I-2370J1674D01*
G02X1954500Y204492I-3285J-882D01*
G01X1949998D01*
G37*
G36*
G01X1904485Y206330D02*
G02X1903176Y206122I-443J-1435D01*
G03X1903074Y206828I-230J327D01*
G02X1904363Y207033I450J1328D01*
G03X1904485Y206330I239J-321D01*
G37*
G36*
G01X1953785Y196804D02*
G02X1952253Y196564I-585J-1274D01*
G03X1952138Y197228I-270J295D01*
G02X1953692Y197472I579J1386D01*
G03X1953785Y196804I260J-304D01*
G37*
G36*
G01X1945311Y191443D02*
G02X1943548Y191614I-1010J-1243D01*
G03X1943623Y192269I-188J353D01*
G02X1945363Y192100I988J1131D01*
G03X1945311Y191443I200J-346D01*
G37*
G36*
G01X1932141Y176418D02*
G02X1930416Y176763I-1077J-898D01*
G03X1930527Y177386I-185J354D01*
G02X1930344Y177636I1114J1007D01*
G03X1929631Y177590I-345J-203D01*
G02X1929544Y178939I-1382J588D01*
G03X1930257Y178985I345J203D01*
G02X1932278Y177037I1382J-589D01*
G03X1932141Y176418I170J-362D01*
G37*
G36*
G01X1929290Y171119D02*
G02X1929132Y169372I1010J-972D01*
G03X1928510Y169428I-333J-221D01*
G02X1928668Y171175I-1010J972D01*
G03X1929290Y171119I333J221D01*
G37*
G36*
G01X1958054Y127860D02*
G02Y112456I0J-7702D01*
G01X1951554D01*
G02Y127860I0J7702D01*
G01X1958054D01*
G37*
G36*
G01X1945730Y150711D02*
G03X1945732Y150181I301J-264D01*
G02X1943479Y150173I-1123J-997D01*
G03X1943477Y150703I-301J264D01*
G02X1945730Y150711I1123J997D01*
G37*
G36*
G01X1952200Y142923D02*
G03X1952362Y142348I337J-215D01*
G02X1950434Y141807I-662J-1348D01*
G03X1950272Y142382I-337J215D01*
G02X1952200Y142923I662J1348D01*
G37*
G36*
G01X1930227Y157063D02*
G02X1928590Y154918I-516J-1304D01*
G03X1927993Y154966I-320J-240D01*
G02X1927254Y157520I-1041J1083D01*
G03X1927704Y158065I80J392D01*
G02X1930069Y157693I1296J535D01*
G03X1930227Y157063I305J-258D01*
G37*
G36*
G01X1901565Y-18175D02*
G03X1902176Y-18281I349J196D01*
G02X1901851Y-20152I984J-1135D01*
G03X1901240Y-20046I-349J-196D01*
G02X1901565Y-18175I-984J1135D01*
G37*
G36*
G01X1898528Y235808D02*
G02X1898508Y234297I1288J-773D01*
G03X1897817Y234307I-348J-196D01*
G02X1897837Y235818I-1288J773D01*
G03X1898528Y235808I348J196D01*
G37*
G36*
G01X1851554Y93382D02*
G03Y92818I283J-282D01*
G02X1847298I-2128J-2118D01*
G03Y93382I-283J282D01*
G02X1846827Y93998I2129J2116D01*
G02X1846720Y96800I-27J1402D01*
G02X1850888Y98122I2706J-1300D01*
G03X1851419Y98256I194J350D01*
G02X1852772Y96109I1181J-756D01*
G03X1852422Y95687I49J-397D01*
G02X1851554Y93382I-2996J-188D01*
G37*
G36*
G01X1891096Y61818D02*
G03X1890788Y61348I84J-391D01*
G02X1889051Y62623I-1570J-318D01*
G03X1889407Y63058I-42J398D01*
G02X1891096Y61818I1396J131D01*
G37*
G36*
G01X1849527Y55490D02*
G03X1848973I-277J-288D01*
G02Y57510I-973J1010D01*
G03X1849527I277J288D01*
G02Y55490I973J-1010D01*
G37*
G36*
G01X1890330Y52676D02*
G03X1890361Y52152I317J-244D01*
G02X1888075I-1143J-1122D01*
G03X1888106Y52676I-286J280D01*
G02Y54384I1112J854D01*
G03X1888075Y54908I-317J244D01*
G02X1890361I1143J1122D01*
G03X1890330Y54384I286J-280D01*
G02Y52676I-1112J-854D01*
G37*
G36*
G01X1890361Y44908D02*
G03X1890330Y44384I286J-280D01*
G02X1888106I-1112J-854D01*
G03X1888075Y44908I-317J244D01*
G02X1890361I1143J1122D01*
G37*
G36*
G01X1879948Y39232D02*
G03X1879989Y38673I306J-259D01*
G02X1877849Y38514I-992J-1127D01*
G03X1877808Y39073I-306J259D01*
G02X1879948Y39232I992J1127D01*
G37*
G36*
G01X1875325Y59682D02*
G02X1875072Y61305I-1369J618D01*
G03X1875734Y61408I297J267D01*
G02X1876168Y61967I1370J-616D01*
G03X1876219Y62545I-249J313D01*
G02X1878197Y62422I1051J928D01*
G03X1878176Y61842I265J-300D01*
G02X1875987Y59785I-1073J-1051D01*
G03X1875325Y59682I-297J-267D01*
G37*
G36*
G01X1870141Y12086D02*
G03X1869536Y12015I-272J-293D01*
G02X1869308Y13948I-1250J833D01*
G03X1869913Y14019I272J293D01*
G02X1870141Y12086I1250J-833D01*
G37*
G36*
G01X1894156Y-11057D02*
G03X1894172Y-11596I303J-261D01*
G02X1892016I-1078J-1046D01*
G03X1892032Y-11057I-287J278D01*
G02X1894156I1062J915D01*
G37*
G36*
G01X1878297Y23808D02*
G02X1879020Y21901I3298J160D01*
G03X1878324Y21763I-312J-250D01*
G02X1877684Y23451I-1443J418D01*
G03X1878297Y23808I214J338D01*
G37*
G36*
G01X1847302Y13825D02*
G02X1846954Y12104I1020J-1102D01*
G03X1846330Y12243I-364J-165D01*
G02X1846673Y13939I-910J1067D01*
G03X1847302Y13825I357J180D01*
G37*
G36*
G01X1842283Y10502D02*
G02X1842180Y8690I1143J-974D01*
G03X1841543Y8726I-332J-223D01*
G02X1839413Y8568I-1143J974D01*
G03X1838887I-263J-302D01*
G02Y10832I-987J1132D01*
G03X1839413I263J302D01*
G02X1841646Y10538I987J-1132D01*
G03X1842283Y10502I332J223D01*
G37*
G36*
G01X1794264Y164466D02*
G03X1794277Y163886I282J-284D01*
G02X1792209Y163839I-1009J-1112D01*
G03X1792196Y164419I-282J284D01*
G02X1794264Y164466I1009J1112D01*
G37*
G36*
G01X1833115Y144479D02*
G03X1832599Y144204I-130J-379D01*
G02X1831633Y146013I-1451J388D01*
G03X1832149Y146288I130J379D01*
G02X1833115Y144479I1451J-388D01*
G37*
G36*
G01X1817468Y132215D02*
G03X1816929Y132199I-261J-303D01*
G02Y134355I-1046J1078D01*
G03X1817468Y134339I278J287D01*
G02Y132215I915J-1062D01*
G37*
G36*
G01X1811279Y105590D02*
G03X1811804Y105567I276J290D01*
G02X1811709Y103305I939J-1172D01*
G03X1811184Y103328I-276J-290D01*
G02X1809199Y103422I-939J1172D01*
G03X1808660Y103438I-278J-287D01*
G02Y105562I-915J1062D01*
G03X1809199Y105578I261J303D01*
G02X1811279Y105590I1046J-1078D01*
G37*
G36*
G01X1789506Y100381D02*
G03X1789462Y99789I245J-316D01*
G02X1787590Y99929I-1014J-969D01*
G03X1787634Y100521I-245J316D01*
G02X1789506Y100381I1014J969D01*
G37*
G36*
G01X1834264Y152612D02*
G02Y154236I-1264J812D01*
G03X1834936I336J216D01*
G02Y152612I1264J-812D01*
G03X1834264I-336J-216D01*
G37*
G36*
G01X1829274Y151006D02*
G02X1827889Y151287I-933J-1046D01*
G03X1828026Y151964I-129J379D01*
G02X1829411Y151683I933J1046D01*
G03X1829274Y151006I129J-379D01*
G37*
G36*
G01X1822653Y142693D02*
G02X1822539Y144352I-1305J744D01*
G03X1823204Y144397I318J243D01*
G02X1825459Y144816I1305J-744D01*
G03X1826109Y145076I253J310D01*
G02X1826646Y143788I1391J-176D01*
G03X1826004Y143509I-244J-317D01*
G02X1823318Y142738I-1495J144D01*
G03X1822653Y142693I-318J-243D01*
G37*
G36*
G01X1814421Y127229D02*
G02Y128723I-1303J747D01*
G03X1815115I347J199D01*
G02Y127229I1303J-747D01*
G03X1814421I-347J-199D01*
G37*
G36*
G01X1799809Y81895D02*
G03X1800152Y81394I386J-104D01*
G02X1798645Y80361I-152J-1394D01*
G03X1798302Y80862I-386J104D01*
G02X1799809Y81895I152J1394D01*
G37*
G36*
G01X1795700Y70821D02*
G03X1796100Y70402I400J-19D01*
G01X1796101D01*
G02X1794500Y68877I-1J-1602D01*
G03X1794100Y69296I-400J19D01*
G01X1794099D01*
G02X1795700Y70821I1J1602D01*
G37*
G36*
G01X1845615Y66161D02*
G03X1845085I-265J-300D01*
G02X1842527Y67931I-1060J1201D01*
G03X1842226Y68466I-374J142D01*
G02X1841455Y68841I290J1576D01*
G03X1840925I-265J-300D01*
G02X1838834Y68816I-1060J1201D01*
G03X1838293Y68793I-258J-306D01*
G02X1835930Y70951I-1132J1133D01*
G03X1835924Y71471I-307J256D01*
G02X1835592Y72979I1205J1056D01*
G03X1835310Y73479I-384J113D01*
G02X1835250Y76562I404J1550D01*
G03X1835522Y77042I-116J383D01*
G02X1838205Y78566I1555J387D01*
G03X1838786Y78585I282J284D01*
G02X1841073Y78698I1199J-1063D01*
G03X1841632Y78713I272J293D01*
G02X1844328Y77177I1151J-1114D01*
G03X1844581Y76695I386J-105D01*
G02X1845132Y76364I-533J-1511D01*
G03X1845655Y76348I271J294D01*
G02X1847024Y73544I1012J-1242D01*
G03X1846724Y73062I89J-390D01*
G02X1846366Y71632I-1559J-370D01*
G03Y71102I300J-265D01*
G02X1846663Y69473I-1201J-1061D01*
G03X1846964Y68938I374J-142D01*
G02X1847735Y68563I-290J-1576D01*
G03X1848265I265J300D01*
G02Y66161I1060J-1201D01*
G03X1847735I-265J-300D01*
G02X1845615I-1060J1201D01*
G37*
G36*
G01X1785925Y65083D02*
G03X1786325Y64743I395J60D01*
G02X1784991Y62964I16J-1402D01*
G03X1784553Y63253I-385J-108D01*
G02X1785925Y65083I-212J1588D01*
G37*
G36*
G01X1798661Y63047D02*
G03X1798665Y62454I270J-295D01*
G02X1796606Y60268I-1001J-1120D01*
G03X1796044Y60270I-282J-284D01*
G02X1793953Y60258I-1052J1072D01*
G03X1793404Y60262I-277J-289D01*
G02X1791366Y62469I-1022J1101D01*
G03X1791362Y63062I-270J295D01*
G02X1793402Y65266I1001J1120D01*
G03X1793951Y65262I277J289D01*
G02X1796031Y65227I1022J-1101D01*
G03X1796593Y65225I282J284D01*
G02X1798661Y63047I1052J-1072D01*
G37*
G36*
G01X1817315Y55795D02*
G02X1817298Y53727I1081J-1043D01*
G03X1816718Y53732I-292J-273D01*
G02X1814148Y54972I-1081J1043D01*
G03X1813652Y55411I-397J52D01*
G02X1812212Y55808I-374J1455D01*
G03X1811644I-284J-282D01*
G02X1809515Y55805I-1066J1058D01*
G03X1808955Y55811I-283J-283D01*
G02X1806882Y55805I-1040J1084D01*
G03X1806328Y55802I-275J-290D01*
G02X1804111Y55940I-1046J1078D01*
G03X1803446Y55877I-312J-251D01*
G02X1803290Y57521I-1327J703D01*
G03X1803955Y57584I312J251D01*
G02X1804255Y57976I1327J-704D01*
G03X1804282Y58531I-274J291D01*
G02X1804296Y60528I1129J991D01*
G03X1804269Y61092I-297J268D01*
G02X1806320Y63285I1012J1109D01*
G03X1806869Y63281I277J289D01*
G02X1808949Y63246I1022J-1101D01*
G03X1809511Y63244I282J284D01*
G02X1811669Y63189I1052J-1072D01*
G03X1812257I294J270D01*
G02X1814441Y61126I1106J-1017D01*
G03X1814447Y60563I287J-278D01*
G02X1814432Y58408I-1054J-1070D01*
G03X1814408Y57856I277J-289D01*
G02X1814767Y56669I-1130J-990D01*
G03X1815263Y56230I397J-52D01*
G02X1816735Y55800I374J-1455D01*
G03X1817315Y55795I292J273D01*
G37*
G36*
G01X1808320Y27830D02*
G03X1808887Y27760I318J243D01*
G02X1808629Y25673I935J-1175D01*
G03X1808062Y25743I-318J-243D01*
G02X1808320Y27830I-935J1175D01*
G37*
G36*
G01X1824363Y22761D02*
G03X1824904Y22737I284J282D01*
G02X1824807Y20526I966J-1150D01*
G03X1824266Y20550I-284J-282D01*
G02X1824363Y22761I-966J1150D01*
G37*
G36*
G01X1809702Y10968D02*
G03X1809662Y10365I242J-319D01*
G02X1807696Y10497I-1059J-1065D01*
G03X1807736Y11100I-242J319D01*
G02X1809702Y10968I1059J1065D01*
G37*
G36*
G01X1786527Y9667D02*
G03X1786489Y9098I261J-303D01*
G02X1784448Y9289I-1123J-998D01*
G03X1784516Y9855I-245J316D01*
G02X1786527Y9667I1096J874D01*
G37*
G36*
G01X1837185Y2838D02*
G03X1836646Y2822I-261J-303D01*
G02Y4978I-1046J1078D01*
G03X1837185Y4962I278J287D01*
G02Y2838I915J-1062D01*
G37*
G36*
G01X1825926Y2808D02*
G03X1826086Y2294I363J-169D01*
G02X1823962Y1633I-762J-1294D01*
G03X1823802Y2147I-363J169D01*
G02X1825926Y2808I762J1294D01*
G37*
G36*
G01X1837002Y-1732D02*
G03X1837485Y-2131I400J-8D01*
G02X1836298Y-3568I315J-1469D01*
G03X1835815Y-3169I-400J8D01*
G02X1837002Y-1732I-315J1469D01*
G37*
G36*
G01X1815276Y11914D02*
G02X1814690Y13372I-1481J252D01*
G03X1815320Y13613I238J321D01*
G02X1815897Y12177I1373J-282D01*
G03X1815276Y11914I-227J-330D01*
G37*
G36*
G01X1833689Y11578D02*
G02X1831582Y9580I-789J-1278D01*
G03X1830948Y9671I-351J-192D01*
G02X1829091Y12008I-1060J1064D01*
G03X1829204Y12580I-212J339D01*
G02X1831214Y14496I1140J817D01*
G03X1831753Y14534I249J313D01*
G02X1833677Y12251I1089J-1034D01*
G03X1833689Y11578I222J-333D01*
G37*
G36*
G01X1805322Y10061D02*
G02X1803639Y10087I-861J-1231D01*
G03X1803662Y10740I-219J335D01*
G02X1805320Y10715I846J1118D01*
G03X1805322Y10061I231J-326D01*
G37*
G36*
G01X1799966Y10245D02*
G02X1798312Y9796I-504J-1415D01*
G03X1798154Y10425I-306J257D01*
G02X1799784Y10867I522J1301D01*
G03X1799966Y10245I316J-245D01*
G37*
G36*
G01X1760020Y118137D02*
G03X1759380I-320J-240D01*
G02Y120063I-1280J963D01*
G03X1760020I320J240D01*
G02Y118137I1280J-963D01*
G37*
G36*
G01X1746354Y113454D02*
G03X1746449Y112853I304J-260D01*
G02X1744778Y112589I-681J-1110D01*
G03X1744683Y113190I-304J260D01*
G02X1746354Y113454I681J1110D01*
G37*
G36*
G01X1715223Y148268D02*
G02Y149632I-1109J682D01*
G03X1715905I341J209D01*
G02Y148268I1109J-682D01*
G03X1715223I-341J-209D01*
G37*
G36*
G01X1727611Y123133D02*
G02X1727597Y124391I-1147J616D01*
G03X1728297Y124399I348J197D01*
G02X1728311Y123141I1147J-616D01*
G03X1727611Y123133I-348J-197D01*
G37*
G36*
G01X1724472Y101104D02*
G02X1724436Y102361I-1158J596D01*
G03X1725136Y102381I344J203D01*
G02X1725172Y101124I1158J-596D01*
G03X1724472Y101104I-344J-203D01*
G37*
G36*
G01X1745442Y96580D02*
G02X1745127Y95325I1049J-930D01*
G03X1744447Y95507I-389J-93D01*
G02X1742252Y96770I-947J893D01*
G03X1741949Y97275I-384J113D01*
G02X1743462Y98180I265J1275D01*
G03X1743765Y97675I384J-113D01*
G02X1743993Y97605I-267J-1274D01*
G03X1744241Y97891I75J185D01*
G02X1745191Y97260I1123J659D01*
G03X1744753Y96754I-53J-397D01*
G02X1744757Y96741I-1242J-389D01*
G03X1745442Y96580I386J104D01*
G37*
G36*
G01X1732931Y91186D02*
G03X1732365Y91173I-277J-289D01*
G02X1732319Y93154I-1015J967D01*
G03X1732885Y93167I277J289D01*
G02X1732931Y91186I1015J-967D01*
G37*
G36*
G01X1756536Y83562D02*
G03X1755952Y83415I-228J-329D01*
G02X1755449Y85240I-1249J638D01*
G03X1756027Y85413I214J338D01*
G02X1758461Y85852I1368J-619D01*
G03X1759085Y85924I284J282D01*
G02X1759298Y84078I1279J-788D01*
G03X1758674Y84006I-284J-282D01*
G02X1756536Y83562I-1279J788D01*
G37*
G36*
G01X1767426Y71421D02*
G03X1768043Y71404I316J246D01*
G02X1767945Y69421I1207J-1054D01*
G03X1767329Y69465I-326J-231D01*
G02X1767426Y71421I-1089J1034D01*
G37*
G36*
G01X1747577Y59845D02*
G03X1748119Y59727I332J223D01*
G02X1747734Y57690I735J-1194D01*
G03X1747186Y57778I-320J-240D01*
G02X1747577Y59845I-858J1233D01*
G37*
G36*
G01X1734177Y57140D02*
G03X1733623I-277J-288D01*
G02X1731640Y59123I-973J1010D01*
G03Y59677I-288J277D01*
G02X1733623Y61660I1010J973D01*
G03X1734177I277J288D01*
G02X1736160Y59677I973J-1010D01*
G03Y59123I288J-277D01*
G02X1734177Y57140I-1010J-973D01*
G37*
G36*
G01X1744121Y46096D02*
G03X1743567I-277J-288D01*
G02Y48116I-973J1010D01*
G03X1744121I277J288D01*
G02Y46096I973J-1010D01*
G37*
G36*
G01X1701968Y162401D02*
G03X1702523Y162390I283J283D01*
G02X1702478Y160081I1087J-1176D01*
G03X1701923Y160092I-283J-283D01*
G02X1701968Y162401I-1087J1176D01*
G37*
G36*
G01X1690118Y175069D02*
G02X1690081Y173713I1321J-715D01*
G03X1689367Y173732I-362J-171D01*
G02X1689404Y175088I-1321J715D01*
G03X1690118Y175069I362J171D01*
G37*
G36*
G01X1678525Y171043D02*
G02X1676379Y169307I-919J-1058D01*
G03X1675679Y169308I-350J-194D01*
G02X1673512Y171029I-1224J683D01*
G03Y171620I-269J295D01*
G02X1675669Y173359I943J1038D01*
G03X1676367Y173368I346J200D01*
G02X1678524Y171646I1233J-668D01*
G03X1678525Y171043I264J-301D01*
G37*
G36*
G01X1700076Y154255D02*
G03X1700357Y154249I144J140D01*
G02X1700306Y151967I1098J-1166D01*
G03X1700025Y151973I-144J-140D01*
G02X1700076Y154255I-1098J1166D01*
G37*
G36*
G01X1687956Y100006D02*
G03X1688480Y99961I288J278D01*
G02X1688288Y97706I888J-1211D01*
G03X1687764Y97751I-288J-278D01*
G02X1687956Y100006I-888J1211D01*
G37*
G36*
G01X1659322Y99975D02*
G03X1659840Y99785I359J177D01*
G02X1659108Y97957I560J-1285D01*
G03X1658601Y98177I-369J-155D01*
G02X1659322Y99975I-447J1223D01*
G37*
G36*
G01X1694787Y133808D02*
G02X1693649Y134522I-1162J-588D01*
G03X1694007Y135114I7J400D01*
G02X1694555Y137013I1229J674D01*
G03Y137713I-194J350D01*
G02X1695917I681J1225D01*
G03Y137013I194J-350D01*
G02X1695164Y134388I-681J-1225D01*
G03X1694787Y133808I-20J-399D01*
G37*
G36*
G01X1676462Y91763D02*
G03X1677015Y91552I372J146D01*
G02X1676369Y89729I634J-1251D01*
G03X1675806Y89914I-365J-163D01*
G02X1676462Y91763I-744J1305D01*
G37*
G36*
G01X1675907Y88007D02*
G03X1676501Y87982I308J255D01*
G02X1676415Y85973I1072J-1052D01*
G03X1675821Y85998I-308J-255D01*
G02X1675907Y88007I-1072J1052D01*
G37*
G36*
G01X1660143Y86878D02*
G03X1660112Y86354I286J-280D01*
G02X1657888I-1112J-854D01*
G03X1657857Y86878I-317J244D01*
G02X1660143I1143J1122D01*
G37*
G36*
G01X1667013Y80468D02*
G03X1666487I-263J-302D01*
G02Y82732I-987J1132D01*
G03X1667013I263J302D01*
G02X1669046Y82678I987J-1132D01*
G03X1669585Y82662I278J287D01*
G02X1671415I915J-1062D01*
G03X1671954Y82678I261J303D01*
G02X1673987Y82732I1046J-1078D01*
G03X1674513I263J302D01*
G02X1676487I987J-1132D01*
G03X1677013I263J302D01*
G02Y80468I987J-1132D01*
G03X1676487I-263J-302D01*
G02X1674513I-987J1132D01*
G03X1673987I-263J-302D01*
G02X1671954Y80522I-987J1132D01*
G03X1671415Y80538I-278J-287D01*
G02X1669585I-915J1062D01*
G03X1669046Y80522I-261J-303D01*
G02X1667013Y80468I-1046J1078D01*
G37*
G36*
G01X1695196Y79073D02*
G03X1695481Y79081I139J144D01*
G02Y76901I1174J-1090D01*
G03X1695196Y76909I-146J-136D01*
G02X1693168Y76859I-1041J1082D01*
G03X1692642I-263J-302D01*
G02X1690668I-987J1132D01*
G03X1690142I-263J-302D01*
G02Y79123I-987J1132D01*
G03X1690668I263J302D01*
G02X1692642I987J-1132D01*
G03X1693168I263J302D01*
G02X1695196Y79073I987J-1132D01*
G37*
G36*
G01X1675057Y76022D02*
G03X1675610Y75906I335J219D01*
G02X1675171Y73824I818J-1260D01*
G03X1674618Y73940I-335J-219D01*
G02X1675057Y76022I-818J1260D01*
G37*
G36*
G01X1671027Y50490D02*
G03X1670473I-277J-288D01*
G02Y52510I-973J1010D01*
G03X1671027I277J288D01*
G02Y50490I973J-1010D01*
G37*
G36*
G01X1693552Y93805D02*
G02X1693496Y95501I-1267J807D01*
G03X1694147Y95510I322J237D01*
G02X1696257Y95736I1153J-798D01*
G03X1696798Y95731I273J292D01*
G02X1698806Y95727I1002J-1119D01*
G03X1699346Y95731I268J297D01*
G02X1699424Y93609I954J-1027D01*
G03X1698885Y93573I-250J-312D01*
G02X1696711Y93577I-1085J1039D01*
G03X1696173Y93615I-290J-275D01*
G02X1694203Y93840I-873J1097D01*
G03X1693552Y93805I-313J-249D01*
G37*
G36*
G01X1669057Y88609D02*
G02X1669003Y87232I1193J-736D01*
G03X1668301Y87249I-356J-183D01*
G02X1668356Y88647I-1301J751D01*
G03X1669057Y88609I361J172D01*
G37*
G36*
G01X1665482Y70949D02*
G02X1663218I-1132J-987D01*
G03Y71475I-302J263D01*
G02X1663186Y71513I1133J986D01*
G03X1662848Y71467I-155J-126D01*
G02X1661123Y70697I-1285J561D01*
G03X1660598Y70311I-125J-380D01*
G02X1659636Y71622I-1402J-20D01*
G03X1660161Y72008I125J380D01*
G02X1660178Y72245I1402J19D01*
G03X1659870Y72443I-198J31D01*
G02X1658127Y72604I-771J1171D01*
G03X1657573I-277J-288D01*
G02Y74624I-973J1010D01*
G03X1658127I277J288D01*
G02X1660500Y73684I973J-1010D01*
G03X1661047Y73332I399J20D01*
G02X1662453Y73111I515J-1304D01*
G03X1663053Y73219I254J309D01*
G02X1665482Y71475I1297J-756D01*
G03Y70949I302J-263D01*
G37*
G36*
G01X1654869Y12118D02*
G03X1654492Y11670I20J-399D01*
G02X1653031Y12900I-1392J-170D01*
G03X1653408Y13348I-20J399D01*
G02X1654869Y12118I1392J170D01*
G37*
G36*
G01X1676428Y9870D02*
G02Y12892I0J1511D01*
G01X1681429D01*
G02X1682940Y11391I0J-1512D01*
G01Y11296D01*
X1682930Y11212D01*
G02X1681428Y9870I-1502J169D01*
G01X1676428D01*
G37*
G36*
G01X1663884Y10069D02*
X1663875Y9985D01*
G02X1662342Y8643I-1502J169D01*
G01X1657338Y8747D01*
G02X1657400Y11769I31J1511D01*
G01X1662403Y11665D01*
G02X1663884Y10164I-30J-1511D01*
G01Y10069D01*
G37*
G36*
G01X1666091Y5013D02*
G03X1665488Y4847I-235J-323D01*
G02X1664970Y6572I-1288J553D01*
G03X1665564Y6766I220J334D01*
G02X1666979Y7748I1416J-530D01*
G01X1671979D01*
G02X1673490Y6246I-1J-1512D01*
G01Y6151D01*
X1673481Y6067D01*
G02X1671979Y4724I-1502J168D01*
G01X1666979D01*
G02X1666091Y5013I1J1512D01*
G37*
G36*
G01X1714297Y9668D02*
G02X1712816Y11483I0J1512D01*
G03X1712300Y11944I-392J81D01*
G02X1711712Y11882I-438J1332D01*
G03X1711272Y11438I-43J-398D01*
G02X1711282Y11271I-1501J-174D01*
G01Y11176D01*
X1711273Y11092D01*
G02X1709771Y9750I-1502J169D01*
G01X1704771D01*
G02X1703270Y11439I0J1511D01*
G03X1702773Y11874I-397J48D01*
G02X1702176Y11851I-351J1357D01*
G03X1701707Y11427I-70J-394D01*
G02X1701712Y11327I-1506J-125D01*
G01Y11232D01*
X1701702Y11148D01*
G02X1700200Y9806I-1502J170D01*
G01X1695200D01*
G02Y12828I0J1511D01*
G01X1700201D01*
G02X1700532Y12792I3J-1511D01*
G03X1701020Y13193I88J390D01*
G02X1703819Y13122I1401J39D01*
G03X1704333Y12708I399J-31D01*
G02X1704771Y12772I435J-1447D01*
G01X1709772D01*
G02X1710004Y12754I-1J-1511D01*
G03X1710464Y13178I61J395D01*
G02X1713245Y13042I1399J98D01*
G03X1713777Y12599I394J-67D01*
G02X1714297Y12692I522J-1419D01*
G01X1719298D01*
G02X1719713Y12633I-3J-1512D01*
G03X1720208Y13125I110J385D01*
G02X1722949Y13316I1351J375D01*
G03X1723415Y12869I397J-53D01*
G02X1723677Y12892I263J-1488D01*
G01X1728681D01*
G02X1728906Y12875I-1J-1511D01*
G03X1729366Y13280I60J395D01*
G02X1730625Y11918I1402J33D01*
G03X1730186Y11491I-40J-398D01*
G02X1730190Y11391I-1508J-110D01*
G01Y11296D01*
X1730180Y11212D01*
G02X1728678Y9870I-1502J169D01*
G01X1723678D01*
G02X1722190Y11644I0J1511D01*
G03X1721743Y12110I-394J69D01*
G02X1721218Y12140I-184J1390D01*
G03X1720739Y11632I-97J-388D01*
G02X1720808Y11190I-1442J-452D01*
G01Y11095D01*
X1720799Y11011D01*
G02X1719297Y9668I-1502J169D01*
G01X1714297D01*
G37*
G36*
G01X1685948Y9214D02*
G02X1684677Y11543I0J1511D01*
G03X1684465Y12140I-336J217D01*
G02X1686144Y12822I437J1332D01*
G03X1686499Y12236I354J-186D01*
G01X1689838D01*
G03X1690216Y12767I0J400D01*
G02X1692338Y12073I1325J459D01*
G03X1692227Y11530I227J-329D01*
G02X1692460Y10735I-1279J-806D01*
G01Y10640D01*
X1692450Y10556D01*
G02X1690948Y9214I-1502J169D01*
G01X1685948D01*
G37*
G36*
G01X1681260Y1995D02*
G02X1681237Y3762I-1226J868D01*
G03X1681875Y3757I321J239D01*
G02X1683924Y3942I1110J-856D01*
G03X1684482Y3964I268J297D01*
G02X1686415Y4062I1018J-964D01*
G03X1686954Y4078I261J303D01*
G02X1689133Y3986I1046J-1078D01*
G03X1689748Y3999I302J262D01*
G02Y2001I1252J-999D01*
G03X1689133Y2014I-313J-249D01*
G02X1686954Y1922I-1133J986D01*
G03X1686415Y1938I-278J-287D01*
G02X1684561Y1959I-915J1062D01*
G03X1684003Y1937I-268J-297D01*
G02X1681897Y2017I-1018J964D01*
G03X1681260Y1995I-310J-253D01*
G37*
G36*
G01X1674935Y-17561D02*
G02X1674904Y-16078I-1435J712D01*
G03X1675602Y-16084I351J193D01*
G02X1675632Y-17526I1217J-696D01*
G03X1674935Y-17561I-339J-213D01*
G37*
G36*
G01X1595550Y128680D02*
G02X1594120Y127253I-28J-1402D01*
G03X1593728Y127646I-400J-7D01*
G02X1595158Y129073I28J1402D01*
G03X1595550Y128680I400J7D01*
G37*
G36*
G01X1597943Y109433D02*
G03X1597480Y109141I-76J-393D01*
G02X1594921Y109551I-1260J329D01*
G03X1594506Y109976I-399J25D01*
G02X1595845Y111217I-54J1401D01*
G03X1596237Y110772I397J-45D01*
G02X1596467Y110748I-20J-1302D01*
G03X1596930Y111040I76J393D01*
G02X1599047Y111691I1260J-329D01*
G03X1599587Y111704I263J301D01*
G02X1599633Y109786I903J-938D01*
G03X1599093Y109773I-263J-301D01*
G02X1597943Y109433I-903J938D01*
G37*
G36*
G01X1636380Y129379D02*
G02X1635149Y129395I-630J-1139D01*
G03X1635158Y130100I-185J355D01*
G02X1636389Y130084I630J1139D01*
G03X1636380Y129379I185J-355D01*
G37*
G36*
G01X1640008Y111617D02*
G02X1639990Y113019I-1106J687D01*
G03X1640664Y113028I334J220D01*
G02X1640682Y111626I1106J-687D01*
G03X1640008Y111617I-334J-220D01*
G37*
G36*
G01X1611921Y108539D02*
G02X1611920Y109841I-1128J650D01*
G03X1612613Y109842I346J200D01*
G02X1612614Y108540I1128J-650D01*
G03X1611921Y108539I-346J-200D01*
G37*
G36*
G01X1639706Y95785D02*
G02Y97215I-1206J715D01*
G03X1640394I344J204D01*
G02Y95785I1206J-715D01*
G03X1639706I-344J-204D01*
G37*
G36*
G01X1605005Y94753D02*
G03X1605585Y94714I308J255D01*
G02X1605465Y92931I885J-955D01*
G03X1604885Y92970I-308J-255D01*
G02X1605005Y94753I-885J955D01*
G37*
G36*
G01X1622615Y74417D02*
G03X1622096Y74216I-156J-369D01*
G02X1621318Y76230I-1363J631D01*
G03X1621837Y76431I156J369D01*
G02X1622615Y74417I1363J-631D01*
G37*
G36*
G01X1649856Y64134D02*
G03X1649309Y64131I-272J-293D01*
G02X1649296Y66324I-1033J1090D01*
G03X1649843Y66327I272J293D01*
G02X1649856Y64134I1033J-1090D01*
G37*
G36*
G01X1610356Y62550D02*
G03X1609844Y62326I-141J-374D01*
G02X1606956Y63026I-1392J564D01*
G03X1606608Y63459I-398J36D01*
G02X1608293Y64813I189J1490D01*
G03X1608641Y64380I398J-36D01*
G02X1609061Y64263I-189J-1490D01*
G03X1609585Y64458I162J366D01*
G02X1610356Y62550I1268J-597D01*
G37*
G36*
G01X1652014Y78733D02*
G02X1651538Y77257I986J-1133D01*
G03X1650886Y77467I-389J-92D01*
G02X1651362Y78943I-986J1133D01*
G03X1652014Y78733I389J92D01*
G37*
G36*
G01X1613998Y71634D02*
G02X1613900Y70086I1117J-848D01*
G03X1613227Y70117I-346J-200D01*
G02X1613327Y71688I-1227J867D01*
G03X1613998Y71634I353J188D01*
G37*
G36*
G01X1638865Y9594D02*
G02Y12616I0J1511D01*
G01X1643866D01*
G02X1645376Y11115I-1J-1511D01*
G01Y11020D01*
X1645367Y10936D01*
G02X1643865Y9594I-1502J169D01*
G01X1638865D01*
G37*
G36*
G01X1619798Y9244D02*
G02Y12266I0J1511D01*
G01X1624799D01*
G02X1625611Y12029I-1J-1511D01*
G03X1626197Y12219I214J338D01*
G02X1626805Y10483I1303J-518D01*
G03X1626228Y10265I-198J-347D01*
G02X1624799Y9244I-1430J490D01*
G01X1619798D01*
G37*
G36*
G01X1648747Y4814D02*
G02X1648055Y4982I0J1511D01*
G03X1647500Y4776I-184J-355D01*
G02X1646775Y6579I-1300J524D01*
G03X1647318Y6814I165J364D01*
G02X1648748Y7836I1430J-489D01*
G01X1653749D01*
G02X1654940Y7254I-1J-1511D01*
G03X1655554Y7234I315J246D01*
G02X1655538Y5385I1046J-934D01*
G03X1654924Y5375I-303J-261D01*
G02X1653750Y4814I-1175J950D01*
G01X1648747D01*
G37*
G36*
G01X1625485Y3538D02*
G03X1624946Y3522I-261J-303D01*
G02Y5678I-1046J1078D01*
G03X1625485Y5662I278J287D01*
G02Y3538I915J-1062D01*
G37*
G36*
G01X1600115Y-1732D02*
G03X1599589I-263J-302D01*
G02Y532I-987J1132D01*
G03X1600115I263J302D01*
G02Y-1732I987J-1132D01*
G37*
G36*
G01X1596517Y-18478D02*
G03X1595991I-263J-302D01*
G02Y-16214I-987J1132D01*
G03X1596517I263J302D01*
G02X1598491I987J-1132D01*
G03X1599017I263J302D01*
G02X1601050Y-16268I987J-1132D01*
G03X1601589Y-16284I278J287D01*
G02X1603419I915J-1062D01*
G03X1603958Y-16268I261J303D01*
G02X1605991Y-16214I1046J-1078D01*
G03X1606517I263J302D01*
G02X1608491I987J-1132D01*
G03X1609017I263J302D01*
G02Y-18478I987J-1132D01*
G03X1608491I-263J-302D01*
G02X1606517I-987J1132D01*
G03X1605991I-263J-302D01*
G02X1603958Y-18424I-987J1132D01*
G03X1603419Y-18408I-278J-287D01*
G02X1601589I-915J1062D01*
G03X1601050Y-18424I-261J-303D01*
G02X1599017Y-18478I-1046J1078D01*
G03X1598491I-263J-302D01*
G02X1596517I-987J1132D01*
G37*
G36*
G01X1600898Y9844D02*
G02Y12866I0J1511D01*
G01X1605899D01*
G02X1606234Y12829I3J-1511D01*
G03X1606723Y13237I89J390D01*
G02X1607873Y11922I1401J64D01*
G03X1607403Y11493I-72J-393D01*
G02X1607410Y11365I-1504J-146D01*
G01Y11270D01*
X1607400Y11186D01*
G02X1605898Y9844I-1502J169D01*
G01X1600898D01*
G37*
G36*
G01X1632677Y8336D02*
G03X1633015Y8950I0J400D01*
G02X1635094Y8620I1185J750D01*
G03X1635098Y8001I255J-308D01*
G02X1635660Y6835I-950J-1176D01*
G01Y6740D01*
X1635650Y6656D01*
G02X1635608Y6433I-1502J167D01*
G03X1636106Y5946I386J-103D01*
G02X1635135Y4918I395J-1345D01*
G03X1634620Y5389I-390J91D01*
G02X1634148Y5314I-470J1436D01*
G01X1629148D01*
G02Y8336I0J1511D01*
G01X1632677D01*
G37*
G36*
G01X1614834Y6936D02*
G02X1616344Y5435I-1J-1511D01*
G01Y5340D01*
X1616335Y5256D01*
G02X1614833Y3914I-1502J169D01*
G01X1609833D01*
G02X1608729Y4393I0J1511D01*
G03X1608051Y4226I-292J-273D01*
G02X1607692Y5591I-1351J374D01*
G03X1608364Y5780I283J282D01*
G02X1609833Y6936I1469J-355D01*
G01X1614834D01*
G37*
G36*
G01X1590983Y135717D02*
G02X1588569Y134355I-1103J-866D01*
G03X1588067Y134592I-374J-142D01*
G02X1588931Y136417I-447J1329D01*
G03X1589433Y136180I374J142D01*
G02X1589465Y136190I434J-1333D01*
G03X1589653Y136831I-118J383D01*
G02X1591920Y138800I1147J969D01*
G03X1592503Y138786I298J267D01*
G02Y136814I997J-986D01*
G03X1591920Y136800I-285J-281D01*
G02X1591193Y136350I-1121J999D01*
G03X1590983Y135717I104J-386D01*
G37*
G36*
G01X1550847Y22724D02*
G03X1550321I-263J-302D01*
G02Y24988I-987J1132D01*
G03X1550847I263J302D01*
G02X1552861Y24952I987J-1132D01*
G03X1553407I273J292D01*
G02Y22760I1027J-1096D01*
G03X1552861I-273J-292D01*
G02X1550847Y22724I-1027J1096D01*
G37*
G36*
G01X1532430Y23307D02*
G02Y24629I3693J661D01*
G02Y23307I3693J-661D01*
G37*
G36*
G01X1583532Y-7764D02*
G03X1582993Y-7780I-261J-303D01*
G02X1580901I-1046J1078D01*
G03X1580362Y-7764I-278J-287D01*
G02Y-5640I-915J1062D01*
G03X1580901Y-5624I261J303D01*
G02X1582993I1046J-1078D01*
G03X1583532Y-5640I278J287D01*
G02Y-7764I915J-1062D01*
G37*
G36*
G01X1585513Y-17232D02*
G03X1584987I-263J-302D01*
G02Y-14968I-987J1132D01*
G03X1585513I263J302D01*
G02Y-17232I987J-1132D01*
G37*
G36*
G01X1838140Y25137D02*
G02X1837514Y25561I560J1501D01*
G03X1836958Y25597I-297J-268D01*
G02X1834661Y25829I-1037J1221D01*
G03X1834031I-315J-247D01*
G02Y27807I-1260J989D01*
G03X1834661I315J247D01*
G02X1835036Y28153I1260J-989D01*
G03X1835098Y28769I-221J333D01*
G01X1834327Y29540D01*
X1771351D01*
X1767753Y25942D01*
G03X1767833Y25314I283J-283D01*
G02X1768580Y24020I-764J-1304D01*
G01Y23925D01*
X1768571Y23841D01*
G02X1768477Y23459I-1502J167D01*
G03X1768840Y22914I372J-145D01*
G02X1767481Y21969I-33J-1402D01*
G03X1767096Y22499I-378J130D01*
G02X1767069Y22498I-69J1509D01*
G01X1764800D01*
G03X1764422Y21966I-1J-400D01*
G02X1762492Y20237I-1322J-466D01*
G03X1762205Y20055I-87J-180D01*
G02Y20019I-1512J-18D01*
G01X1762204Y20017D01*
Y20007D01*
G02X1760709Y18534I-1511J38D01*
G01X1760341Y18530D01*
X1759139Y17328D01*
X1586928D01*
X1584804Y19452D01*
Y19562D01*
X1582753Y21613D01*
Y35815D01*
X1582599Y35852D01*
G02Y38580I324J1364D01*
G01X1582753Y38617D01*
Y40460D01*
X1587406Y45113D01*
X1657149D01*
X1657199Y45241D01*
G02X1660001I1401J-541D01*
G01X1660051Y45113D01*
X1707821D01*
G03X1708216Y45577I0J400D01*
G02X1710984I1384J223D01*
G03X1711379Y45113I395J-64D01*
G01X1713396D01*
G03X1713774Y45643I0J400D01*
G02X1716073Y47110I1326J458D01*
G03X1716627I277J288D01*
G02X1718573I973J-1010D01*
G03X1719127I277J288D01*
G02X1721426Y45643I973J-1009D01*
G03X1721804Y45113I378J-130D01*
G01X1798276D01*
G02X1800600I1162J-785D01*
G01X1866718D01*
X1867819Y44012D01*
X1867951Y44083D01*
G02X1868956Y41290I719J-1318D01*
G03X1868718Y40649I76J-393D01*
G02X1868092Y38459I-1099J-870D01*
G01X1867960Y38412D01*
Y20715D01*
X1867959Y20714D01*
Y20637D01*
X1866053Y18731D01*
X1839750D01*
X1838938Y19543D01*
Y19604D01*
X1838576Y19966D01*
X1838467Y19941D01*
G02X1836897Y20443I-367J1559D01*
G03X1836301Y20449I-301J-264D01*
G02X1833901Y20494I-1180J1083D01*
G03X1833291I-305J-259D01*
G02Y22570I-1220J1038D01*
G03X1833901I305J259D01*
G02X1836324Y22589I1220J-1038D01*
G03X1836920Y22583I301J264D01*
G02X1838073Y23102I1181J-1083D01*
G03X1838270Y23302I-3J200D01*
G01Y25089D01*
X1838140Y25137D01*
G37*
G36*
G01X1581998Y9844D02*
G02X1580490Y11456I0J1511D01*
G03X1580020Y11877I-399J27D01*
G02X1579016Y12077I-247J1380D01*
G03X1578433Y11901I-217J-336D01*
G02X1577048Y10994I-1385J605D01*
G01X1573048D01*
G02X1571739Y11750I0J1512D01*
G03X1571128Y11849I-346J-200D01*
G02X1569347Y11787I-928J1051D01*
G03X1568768Y11686I-243J-318D01*
G02X1567498Y10994I-1270J820D01*
G01X1563498D01*
G02X1562172Y11781I1J1512D01*
G03X1561572Y11902I-351J-192D01*
G02X1560031Y11768I-872J1098D01*
G03X1559486Y11603I-191J-351D01*
G02X1558148Y10794I-1338J703D01*
G01X1554148D01*
G02X1552815Y11595I1J1512D01*
G03X1552206Y11714I-353J-188D01*
G02X1550464Y11673I-897J1078D01*
G03X1549904Y11595I-241J-319D01*
G02X1548698Y10994I-1207J911D01*
G01X1544698D01*
G02X1543347Y11829I1J1512D01*
G03X1542636Y11839I-358J-179D01*
G02X1540503Y11422I-1236J661D01*
G03X1539884Y11282I-256J-307D01*
G02X1539528Y13025I-1364J629D01*
G03X1540152Y13139I268J296D01*
G02X1542634Y13166I1248J-639D01*
G03X1543344Y13178I352J190D01*
G02X1544698Y14018I1354J-672D01*
G01X1548699D01*
G02X1549678Y13657I-1J-1512D01*
G03X1550242Y13702I260J304D01*
G02X1552513Y13510I1067J-910D01*
G03X1553127Y13420I344J205D01*
G02X1554148Y13818I1022J-1114D01*
G01X1558148D01*
G02X1558945Y13590I-1J-1512D01*
G03X1559499Y13723I211J340D01*
G02X1561895Y13733I1201J-723D01*
G03X1562500Y13641I341J209D01*
G02X1563498Y14018I999J-1135D01*
G01X1567499D01*
G02X1568481Y13654I-2J-1512D01*
G03X1569065Y13723I260J304D01*
G02X1571379Y13659I1135J-823D01*
G03X1571994Y13589I336J217D01*
G02X1573048Y14018I1055J-1083D01*
G01X1577049D01*
G02X1577927Y13735I-3J-1511D01*
G03X1578518Y13882I233J325D01*
G02X1581175Y13227I1255J-625D01*
G03X1581663Y12829I400J-8D01*
G02X1581998Y12866I332J-1474D01*
G01X1586999D01*
G02X1588425Y11853I-1J-1511D01*
G03X1588904Y11597I378J131D01*
G02X1589834Y11520I356J-1356D01*
G03X1590385Y11785I164J365D01*
G02X1591848Y12918I1463J-379D01*
G01X1595849D01*
G02X1597360Y11416I-1J-1512D01*
G01Y11321D01*
X1597350Y11237D01*
G02X1597282Y10928I-1502J169D01*
G03X1597670Y10402I379J-126D01*
G02X1596353Y9388I30J-1402D01*
G03X1595943Y9897I-384J110D01*
G02X1595848Y9894I-95J1509D01*
G01X1591848D01*
G02X1591161Y10060I2J1512D01*
G03X1590597Y9823I-182J-356D01*
G02X1587967Y9696I-1338J418D01*
G03X1587473Y9920I-368J-156D01*
G02X1586998Y9844I-473J1435D01*
G01X1581998D01*
G37*
G36*
G01X1544803Y2653D02*
G02Y4147I-1303J747D01*
G03X1545497I347J199D01*
G02X1547985Y4323I1303J-747D01*
G03X1548615I315J246D01*
G02X1550787Y4532I1185J-923D01*
G03X1551313I263J302D01*
G02X1553287I987J-1132D01*
G03X1553813I263J302D01*
G02X1556064Y4212I987J-1132D01*
G03X1556736I336J216D01*
G02X1558987Y4532I1264J-812D01*
G03X1559513I263J302D01*
G02X1561566Y4458I987J-1132D01*
G03X1562134I284J282D01*
G02X1564306Y4417I1066J-1058D01*
G03X1564894I294J270D01*
G02X1567185Y4323I1106J-1017D01*
G03X1567815I315J246D01*
G02Y2477I1185J-923D01*
G03X1567185I-315J-246D01*
G02X1564894Y2383I-1185J923D01*
G03X1564306I-294J-270D01*
G02X1562134Y2342I-1106J1017D01*
G03X1561566I-284J-282D01*
G02X1559513Y2268I-1066J1058D01*
G03X1558987I-263J-302D01*
G02X1556736Y2588I-987J1132D01*
G03X1556064I-336J-216D01*
G02X1553813Y2268I-1264J812D01*
G03X1553287I-263J-302D01*
G02X1551313I-987J1132D01*
G03X1550787I-263J-302D01*
G02X1548615Y2477I-987J1132D01*
G03X1547985I-315J-246D01*
G02X1545497Y2653I-1185J923D01*
G03X1544803I-347J-199D01*
G37*
G36*
G01X1523758Y27469D02*
G03X1523264Y27176I-105J-386D01*
G02X1522198Y28870I-1364J324D01*
G03X1522677Y29189I85J391D01*
G02X1523758Y27469I1477J-271D01*
G37*
G36*
G01X1509076Y30459D02*
G03X1508564Y30057I-112J-384D01*
G02X1507532Y32530I-3898J-175D01*
G03X1508178Y32612I294J272D01*
G02X1509076Y30459I1322J-712D01*
G37*
G36*
G01X1529230Y26922D02*
G03X1529190Y26318I241J-319D01*
G02X1526649Y27263I-2320J-2350D01*
G03X1527013Y27746I-27J399D01*
G02X1529230Y26922I1371J294D01*
G37*
G36*
G01X1491101Y5398D02*
G03X1490768Y4776I0J-400D01*
G02X1488486Y4852I-1168J-776D01*
G03X1488294Y5474I-318J243D01*
G02X1488770Y8420I476J1435D01*
G01X1493771D01*
G02X1495282Y6919I0J-1512D01*
G01Y6824D01*
X1495272Y6740D01*
G02X1494220Y5466I-1502J169D01*
G03X1494020Y4844I119J-382D01*
G02X1491732Y4776I-1120J-844D01*
G03X1491399Y5398I-333J222D01*
G01X1491101D01*
G37*
G36*
G01X1471463Y4078D02*
G03X1471095Y3520I0J-400D01*
G02X1468657Y3769I-1288J-553D01*
G03X1468551Y4331I-328J229D01*
G02X1469388Y7100I837J1258D01*
G01X1474389D01*
G02X1475900Y5599I0J-1512D01*
G01Y5504D01*
X1475890Y5420D01*
G02X1475050Y4230I-1502J169D01*
G03X1474881Y3667I175J-359D01*
G02X1472390Y3517I-1207J-714D01*
G03X1472024Y4078I-366J161D01*
G01X1471463D01*
G37*
G36*
G01X1479135Y10052D02*
G02X1477630Y11703I0J1511D01*
G03X1477116Y12124I-398J38D01*
G02X1478112Y13391I-404J1342D01*
G03X1478642Y12992I399J-21D01*
G02X1479135Y13074I491J-1429D01*
G01X1484136D01*
G02X1484313Y13064I3J-1511D01*
G03X1484760Y13470I47J397D01*
G02X1486068Y12101I1402J30D01*
G03X1485643Y11673I-26J-399D01*
G02X1485646Y11573I-1508J-95D01*
G01Y11478D01*
X1485637Y11394D01*
G02X1484135Y10052I-1502J169D01*
G01X1479135D01*
G37*
G36*
G01X1525906Y2483D02*
G02Y4517I-1106J1017D01*
G03X1526494I294J270D01*
G02X1528864Y4312I1106J-1017D01*
G03X1529536I336J216D01*
G02X1532064I1264J-812D01*
G03X1532736I336J216D01*
G02Y2688I1264J-812D01*
G03X1532064I-336J-216D01*
G02X1529536I-1264J812D01*
G03X1528864I-336J-216D01*
G02X1526494Y2483I-1264J812D01*
G03X1525906I-294J-270D01*
G37*
G36*
G01X1510387Y2368D02*
G02X1508354Y2422I-987J1132D01*
G03X1507815Y2438I-278J-287D01*
G02Y4562I-915J1062D01*
G03X1508354Y4578I261J303D01*
G02X1510387Y4632I1046J-1078D01*
G03X1510913I263J302D01*
G02X1512887I987J-1132D01*
G03X1513413I263J302D01*
G02X1515387I987J-1132D01*
G03X1515913I263J302D01*
G02X1518164Y4312I987J-1132D01*
G03X1518836I336J216D01*
G02Y2688I1264J-812D01*
G03X1518164I-336J-216D01*
G02X1515913Y2368I-1264J812D01*
G03X1515387I-263J-302D01*
G02X1513413I-987J1132D01*
G03X1512887I-263J-302D01*
G02X1510913I-987J1132D01*
G03X1510387I-263J-302D01*
G37*
G36*
G01X1498634Y-11183D02*
G02X1497339Y-12326I166J-1493D01*
G03X1496892Y-11837I-389J93D01*
G02X1498204Y-10679I-232J1585D01*
G03X1498634Y-11183I385J-107D01*
G37*
G36*
G01X1452056Y4078D02*
G03X1451713Y3473I1J-400D01*
G02X1449420Y3640I-1205J-717D01*
G03X1449294Y4248I-310J253D01*
G02X1449991Y7100I697J1341D01*
G01X1454992D01*
G02X1456502Y5599I-1J-1511D01*
G01Y5504D01*
X1456493Y5420D01*
G02X1455827Y4330I-1502J169D01*
G03X1455752Y3727I221J-334D01*
G02X1453498Y3479I-1037J-943D01*
G03X1453150Y4078I-348J199D01*
G01X1452056D01*
G37*
G36*
G01X1460237Y10052D02*
G02X1458732Y11703I0J1511D01*
G03X1458218Y12124I-398J38D01*
G02X1459214Y13391I-404J1342D01*
G03X1459744Y12992I399J-21D01*
G02X1460237Y13074I491J-1429D01*
G01X1465238D01*
G02X1465416Y13064I4J-1511D01*
G03X1465863Y13477I47J397D01*
G02X1467168Y12134I1401J56D01*
G03X1466742Y11699I-28J-399D01*
G02X1466748Y11573I-1505J-135D01*
G01Y11478D01*
X1466739Y11394D01*
G02X1465237Y10052I-1502J169D01*
G01X1460237D01*
G37*
G36*
G01X1441340D02*
G02X1439842Y11758I1J1511D01*
G03X1439328Y12192I-397J52D01*
G02X1440314Y13405I-410J1341D01*
G03X1440844Y12991I398J-36D01*
G02X1441340Y13074I494J-1428D01*
G01X1446340D01*
G02X1446519Y13064I5J-1511D01*
G03X1446966Y13477I47J397D01*
G02X1448271Y12134I1401J56D01*
G03X1447845Y11699I-28J-399D01*
G02X1447852Y11573I-1504J-147D01*
G01Y11478D01*
X1447842Y11394D01*
G02X1446340Y10052I-1502J169D01*
G01X1441340D01*
G37*
G36*
G01X1536462Y164418D02*
G03X1536958Y164063I399J33D01*
G02X1535901Y162585I340J-1360D01*
G03X1535405Y162940I-399J-33D01*
G02X1536462Y164418I-340J1360D01*
G37*
G36*
G01X1533362Y146400D02*
G03X1533559Y145879I367J-159D01*
G02X1531546Y145118I-636J-1361D01*
G03X1531349Y145639I-367J159D01*
G02X1533362Y146400I636J1361D01*
G37*
G36*
G01X1543619Y120382D02*
G03X1543451Y119856I192J-351D01*
G02X1541381Y120518I-1351J-656D01*
G03X1541549Y121044I-192J351D01*
G02X1543619Y120382I1351J656D01*
G37*
G36*
G01X1531389Y133225D02*
G02X1529991Y134069I-1288J-554D01*
G03X1530321Y134639I-31J398D01*
G02X1530189Y135484I1357J645D01*
G03X1529721Y135931I-396J54D01*
G02X1530938Y137208I-272J1477D01*
G03X1531406Y136761I396J-54D01*
G02X1531740Y133783I272J-1477D01*
G03X1531389Y133225I16J-400D01*
G37*
G36*
G01X1542102Y137821D02*
G02X1540713Y137839I-712J-1323D01*
G03X1540722Y138548I-180J357D01*
G02X1542111Y138530I712J1323D01*
G03X1542102Y137821I180J-357D01*
G37*
G36*
G01X1542531Y150245D02*
G02X1540774Y149951I-700J-1215D01*
G03X1540657Y150568I-302J262D01*
G02X1542441Y150866I694J1332D01*
G03X1542531Y150245I290J-275D01*
G37*
G36*
G01X1533757Y79614D02*
G03X1534298Y79609I273J292D01*
G02X1534211Y77455I1002J-1119D01*
G03X1533673Y77493I-290J-275D01*
G02X1533757Y79614I-873J1097D01*
G37*
G36*
G01X1503113Y165928D02*
G03X1503655Y165944I262J302D01*
G02Y163798I1051J-1073D01*
G03X1503113Y163814I-280J-286D01*
G02Y165928I-921J1057D01*
G37*
G36*
G01X1532194Y157026D02*
G03X1531597Y156955I-267J-297D01*
G02X1532387Y159812I-3753J2576D01*
G03X1532863Y159444I399J25D01*
G02X1532194Y157026I269J-1376D01*
G37*
G36*
G01X1497090Y149755D02*
G03X1497153Y149233I331J-225D01*
G02X1494908Y148960I-1003J-1118D01*
G03X1494845Y149482I-331J225D01*
G02X1497090Y149755I1003J1118D01*
G37*
G36*
G01X1514293Y140037D02*
G03X1514607Y139471I363J-169D01*
G02X1513143Y137197I-182J-1491D01*
G03X1512562Y137309I-341J-208D01*
G02X1511329Y139975I-902J1201D01*
G03X1511636Y140424I-89J390D01*
G02X1514293Y140037I1387J206D01*
G37*
G36*
G01X1513478Y133014D02*
G03X1512879Y132903I-252J-310D01*
G02X1512497Y134731I-1215J700D01*
G03X1513090Y134869I238J321D01*
G02X1513478Y133014I1335J-689D01*
G37*
G36*
G01X1513090Y127819D02*
G03X1513693Y127719I344J205D01*
G02X1513430Y125878I907J-1069D01*
G03X1512823Y125951I-334J-220D01*
G02X1513090Y127819I-1023J1099D01*
G37*
G36*
G01X1474138Y119918D02*
G03X1474146Y119335I278J-288D01*
G02X1472177Y119259I-946J-1035D01*
G03X1472140Y119841I-292J274D01*
G02X1471900Y121908I956J1158D01*
G03X1471785Y122494I-319J242D01*
G02X1473656Y122906I715J1206D01*
G03X1473799Y122327I330J-226D01*
G02X1474138Y119918I-703J-1327D01*
G37*
G36*
G01X1483594Y117861D02*
G03X1483838Y117328I370J-153D01*
G02X1482010Y116548I-472J-1426D01*
G03X1481793Y117093I-361J172D01*
G02X1481750Y119690I507J1307D01*
G03X1481966Y120202I-157J368D01*
G02X1483877Y119334I1400J544D01*
G03X1483633Y118834I136J-376D01*
G02X1483594Y117861I-1333J-434D01*
G37*
G36*
G01X1514846Y115137D02*
G03X1514833Y114509I241J-319D01*
G02X1512445Y112903I-954J-1160D01*
G03X1511968Y113173I-382J-119D01*
G02X1511938Y115904I-333J1362D01*
G03X1512424Y116305I86J391D01*
G01Y119436D01*
G03X1511937Y119826I-400J-1D01*
G02X1512912Y121773I-303J1369D01*
G03X1513414Y121562I364J164D01*
G02X1515446Y120153I521J-1419D01*
G01Y116258D01*
X1515437Y116174D01*
G02X1514846Y115137I-1502J169D01*
G37*
G36*
G01X1513448Y103101D02*
G03X1512949Y102873I-129J-379D01*
G02X1511941Y104772I-1299J527D01*
G03X1512424Y105163I83J391D01*
G01Y107637D01*
G03X1511941Y108028I-400J0D01*
G02X1512931Y109971I-291J1372D01*
G03X1513430Y109757I365J163D01*
G02X1515446Y108342I505J-1425D01*
G01Y104447D01*
X1515437Y104363D01*
G02X1513448Y103101I-1502J169D01*
G37*
G36*
G01X1490546Y104528D02*
G03X1490393Y104003I204J-344D01*
G02X1488287Y104617I-1340J-678D01*
G03X1488440Y105142I-204J344D01*
G02X1490546Y104528I1340J678D01*
G37*
G36*
G01X1500648Y99497D02*
G02X1499420Y97741I127J-1396D01*
G03X1498965Y98033I-387J-102D01*
G02X1497194Y99501I-260J1489D01*
G01X1497149Y102725D01*
G02X1499767Y103775I1511J21D01*
G03X1500424Y103881I293J272D01*
G02X1500831Y102199I1276J-581D01*
G03X1500184Y101880I-247J-314D01*
G01X1500212Y99890D01*
G03X1500648Y99497I400J5D01*
G37*
G36*
G01X1525399Y102937D02*
G03X1524848Y102973I-294J-271D01*
G02X1524528Y105327I-898J1077D01*
G03X1525092Y105668I165J365D01*
G01X1525187Y107261D01*
G03X1524559Y107613I-399J24D01*
G02X1524842Y109649I-803J1149D01*
G03X1525499Y109704I310J253D01*
G02X1528314Y109136I1314J-747D01*
G01X1528335Y108960D01*
X1528378D01*
X1528498Y108816D01*
X1528246Y107442D01*
X1528032Y103868D01*
X1528031Y103867D01*
X1528027Y103788D01*
X1528015Y103789D01*
G02X1525399Y102937I-1502J169D01*
G37*
G36*
G01X1525175Y115066D02*
G03X1524540Y115166I-355J-185D01*
G02X1524370Y117307I-983J999D01*
G03X1525002Y117633I232J326D01*
G01Y118926D01*
G03X1524427Y119285I-400J-1D01*
G02X1522924Y121630I-614J1260D01*
G03X1522950Y122226I-253J310D01*
G02X1524777Y124585I1050J1074D01*
G03X1525351Y124768I207J342D01*
G02X1527319Y122787I1377J-600D01*
G03X1527275Y122074I158J-368D01*
G02X1528024Y120779I-762J-1305D01*
G01Y115684D01*
X1528015Y115600D01*
G02X1525175Y115066I-1502J169D01*
G37*
G36*
G01X1500837Y125213D02*
G02X1499205Y125860I-1219J-693D01*
G03X1499426Y126454I-118J382D01*
G02X1501083Y125798I1274J796D01*
G03X1500837Y125213I102J-387D01*
G37*
G36*
G01X1484671Y129908D02*
G02X1482702Y129028I-558J-1395D01*
G03X1482497Y129527I-376J137D01*
G02X1483786Y132015I597J1269D01*
G03X1484356Y132217I198J348D01*
G02X1484815Y132843I1400J-545D01*
G03X1484708Y133528I-250J312D01*
G02X1486121Y133771I502J1309D01*
G03X1486249Y133089I260J-304D01*
G02X1484772Y130535I-494J-1418D01*
G03X1484448Y130436I-131J-151D01*
G02X1484436Y130394I-1354J364D01*
G03X1484671Y129908I383J-115D01*
G37*
G36*
G01X1473905Y130098D02*
G02X1472295I-805J-1148D01*
G03Y130752I-230J327D01*
G02X1473905I805J1148D01*
G03Y130098I230J-327D01*
G37*
G36*
G01X1526072Y140039D02*
G02X1524841Y140601I-1172J-939D01*
G03X1525138Y141251I-15J400D01*
G02X1526369Y140689I1172J939D01*
G03X1526072Y140039I15J-400D01*
G37*
G36*
G01X1515388Y153245D02*
G02X1513861Y151866I-30J-1502D01*
G03X1513470Y152298I-399J32D01*
G02X1512692Y155066I30J1502D01*
G03X1512624Y155776I-214J338D01*
G02X1513922Y155920I512J1305D01*
G03X1514010Y155213I224J-331D01*
G02X1514997Y153677I-510J-1413D01*
G03X1515388Y153245I399J-32D01*
G37*
G36*
G01X1494469Y152753D02*
G02X1491831Y153493I-1400J82D01*
G03X1491585Y154066I-353J188D01*
G02X1493359Y154741I428J1544D01*
G03X1493556Y154149I336J-217D01*
G02X1493900Y153963I-488J-1314D01*
G03X1494537Y154274I237J322D01*
G02X1495114Y153045I1501J-45D01*
G03X1494469Y152753I-246J-315D01*
G37*
G36*
G01X1498944Y114388D02*
G02X1501966Y114398I1511J0D01*
G01Y110848D01*
X1501957Y110764D01*
G02X1501849Y110349I-1502J169D01*
G03X1502081Y109818I369J-155D01*
G02X1500638Y107483I-478J-1318D01*
G03X1500037Y107423I-274J-291D01*
G02X1498719Y109789I-1227J867D01*
G03X1499063Y110344I-24J399D01*
G02X1498971Y110644I1391J591D01*
G03X1498384Y110916I-392J-77D01*
G02X1496581Y112986I-685J1223D01*
G03X1496346Y113619I-319J242D01*
G02X1497824Y114141I312J1469D01*
G03X1498038Y113501I310J-252D01*
G02X1498356Y113378I-343J-1359D01*
G03X1498944Y113731I188J354D01*
G01Y114388D01*
G37*
G36*
G01X1515250Y92707D02*
G02X1513910Y91081I44J-1401D01*
G03X1513496Y91416I-394J-64D01*
G02X1511829Y92785I-161J1504D01*
G01X1511819Y92784D01*
X1511496Y96414D01*
X1511497D01*
Y96415D01*
X1511501Y96542D01*
G02X1511539Y96887I1512J8D01*
G03X1511256Y97330I-395J59D01*
G02X1513038Y98469I395J1345D01*
G03X1513316Y98028I396J-59D01*
G02X1514519Y96682I-303J-1482D01*
G01X1514529Y96683D01*
X1514541Y96554D01*
X1514534D01*
X1514535Y96548D01*
X1514541D01*
X1514852Y93055D01*
X1514851Y93054D01*
X1514857Y92983D01*
G03X1515250Y92707I380J124D01*
G37*
G36*
G01X1500789Y85477D02*
G03X1500716Y84911I242J-319D01*
G02X1498702Y85112I-1103J-865D01*
G03X1498742Y85681I-260J304D01*
G02X1498364Y86681I1134J1000D01*
G01Y90481D01*
G02X1501386Y90491I1511J0D01*
G01Y86596D01*
X1501377Y86512D01*
G02X1500789Y85477I-1502J169D01*
G37*
G36*
G01X1491602Y84743D02*
G03X1491815Y84277I386J-105D01*
G02X1489694Y83229I-650J-1354D01*
G03X1489453Y83681I-392J81D01*
G02X1491602Y84743I604J1484D01*
G37*
G36*
G01X1521094Y80163D02*
G02X1519046Y78074I-780J-1283D01*
G03X1518366Y78065I-337J-215D01*
G02X1518482Y79256I-1204J718D01*
G03X1518864Y79271I189J67D01*
G02X1518954Y79518I1451J-389D01*
G03X1518800Y80030I-362J170D01*
G02X1520940Y80675I780J1283D01*
G03X1521094Y80163I362J-170D01*
G37*
G36*
G01X1525232Y97498D02*
G03X1524623Y97839I-400J0D01*
G02X1525175Y99592I-734J1195D01*
G03X1525793Y99440I367J159D01*
G02X1528256Y98275I951J-1175D01*
G01Y93180D01*
X1528246Y93096D01*
G02X1525366Y92644I-1502J169D01*
G03X1524682Y92720I-365J-165D01*
G02X1524551Y94560I-1119J845D01*
G03X1525232Y94844I281J284D01*
G01Y97498D01*
G37*
G36*
G01X1845386Y252511D02*
G03X1844778Y252504I-301J-263D01*
G02X1844712Y254371I-1078J897D01*
G03X1845319Y254406I289J277D01*
G02X1845386Y252511I1198J-906D01*
G37*
G36*
G01X1853700Y251924D02*
G02X1850929Y251708I-1400J76D01*
G03X1850471Y252019I-391J-83D01*
G02X1851704Y253730I-251J1481D01*
G03X1852144Y253393I396J61D01*
G02X1852703Y253343I157J-1393D01*
G03X1853218Y253720I115J383D01*
G02X1854230Y252280I1502J-20D01*
G03X1853700Y251924I-131J-378D01*
G37*
G36*
G01X1859470Y252106D02*
G02X1857345Y252123I-1070J-906D01*
G03X1857333Y252663I-301J263D01*
G02X1859671Y254531I1087J1037D01*
G03X1860360Y254569I333J221D01*
G02X1862690Y254813I1245J-644D01*
G03X1863289Y254791I309J254D01*
G02X1863220Y252937I1016J-966D01*
G03X1862621Y252959I-309J-254D01*
G02X1860462Y253113I-1016J966D01*
G03X1859776Y253053I-325J-232D01*
G02X1859490Y252646I-1355J648D01*
G03X1859470Y252106I285J-281D01*
G37*
G36*
G01X1770221Y249140D02*
G03X1769616Y249114I-291J-274D01*
G02X1769538Y250943I-1100J869D01*
G03X1770143Y250969I291J274D01*
G02X1770221Y249140I1100J-869D01*
G37*
G36*
G01X1779451Y236100D02*
X1774450D01*
G02X1773143Y236771I2J1612D01*
G03X1772514Y236798I-325J-233D01*
G02Y238626I-1063J914D01*
G03X1773143Y238653I304J260D01*
G02X1774451Y239324I1309J-941D01*
G01X1779451D01*
G02X1780760Y238652I0J-1611D01*
G03X1781388Y238625I325J234D01*
G02Y236799I1064J-913D01*
G03X1780760Y236772I-303J-261D01*
G02X1779451Y236100I-1309J939D01*
G37*
G36*
G01X1760554D02*
X1755554D01*
G02X1754246Y236771I1J1612D01*
G03X1753617Y236798I-325J-233D01*
G02Y238626I-1063J914D01*
G03X1754246Y238653I304J260D01*
G02X1755554Y239324I1309J-941D01*
G01X1760555D01*
G02X1761862Y238653I-2J-1612D01*
G03X1762491Y238626I325J233D01*
G02Y236798I1063J-914D01*
G03X1761862Y236771I-304J-260D01*
G02X1760554Y236100I-1309J941D01*
G37*
G54D49*
X388187Y88678D03*
Y50878D03*
Y69778D03*
Y13078D03*
Y31978D03*
Y-5822D03*
Y608555D03*
Y551879D03*
Y589679D03*
Y570755D03*
Y532955D03*
X1037797Y50878D03*
Y88678D03*
Y69778D03*
Y13078D03*
Y31978D03*
Y-5822D03*
Y608555D03*
Y551879D03*
Y589679D03*
Y570755D03*
Y532955D03*
Y514079D03*
G54D24*
X24400Y519500D03*
X-19210Y162529D03*
X-17014Y455604D03*
X-14800Y526100D03*
X-18160Y522609D03*
X-19802Y476738D03*
X-19783Y481286D03*
X-16186Y519304D03*
X-14971Y540000D03*
X-17500Y574000D03*
X11925Y74867D03*
X11864Y71294D03*
X39109Y154901D03*
X41000Y265350D03*
X44310Y268160D03*
X19904Y254162D03*
X37000Y265350D03*
X33490Y267900D03*
X41000Y274647D03*
X37000Y275000D03*
X1500Y295000D03*
X47100Y327000D03*
X10365Y461602D03*
X11100Y446200D03*
X2450Y460000D03*
X24591Y479139D03*
X13300Y509600D03*
X13600Y504300D03*
X4000Y509500D03*
X2485Y498185D03*
X13700Y498500D03*
X40132Y499800D03*
X-6650Y487800D03*
X-6200Y505400D03*
X-6676Y501800D03*
X10932Y523601D03*
X14700Y517000D03*
X27280Y510420D03*
X-9900Y486400D03*
X-13500D03*
X-7360Y512000D03*
X-2083Y513704D03*
X-4350Y482100D03*
X22491Y500618D03*
X-8200Y578600D03*
X-2500Y569500D03*
X-12600Y578900D03*
X1439Y546583D03*
X1539Y550183D03*
Y586183D03*
X1439Y582583D03*
X-6566Y568363D03*
X-9283Y571324D03*
X98420Y112198D03*
X104424Y110833D03*
X87200Y152374D03*
X91913Y121318D03*
X77790Y121030D03*
X79670Y132300D03*
X91306Y157194D03*
X99250Y160370D03*
X61800Y191600D03*
X76143Y183019D03*
X90831Y184982D03*
X86731Y189148D03*
X97200Y265000D03*
X91600Y278700D03*
X71500Y298000D03*
X66000Y292700D03*
X76800Y298000D03*
X76900Y292600D03*
X66500Y303400D03*
X76800D03*
X53100Y327000D03*
X64700Y310525D03*
X69125Y310625D03*
X84300Y305700D03*
Y310700D03*
X66300Y285850D03*
X72904Y284898D03*
X84300Y289000D03*
X82050Y283951D03*
X77103Y283900D03*
X82500Y341400D03*
X84866Y294213D03*
X79400Y325400D03*
X84300Y299000D03*
X53100Y315000D03*
X76500Y368300D03*
X76300Y358400D03*
X82037Y358542D03*
X70600Y368400D03*
X82100Y368300D03*
X70900Y358300D03*
X65000Y383000D03*
X74800Y379700D03*
X80200D03*
X90518Y388828D03*
X79100Y347000D03*
X61041Y351737D03*
X74800Y383114D03*
X51607Y511747D03*
X59731Y480066D03*
X66016Y468350D03*
X71050Y478670D03*
X86100Y505200D03*
X47550Y504367D03*
X240746Y112327D03*
X264171D03*
X234053D03*
X257478D03*
X277557D03*
X270864D03*
X294889Y110927D03*
X313637Y105725D03*
X311701Y499136D03*
X494927Y112357D03*
X518317D03*
X488634D03*
X512024D03*
X531888D03*
X525134D03*
X555313D03*
X548620D03*
X555750Y399770D03*
X592216Y445152D03*
X595070Y447970D03*
X662352Y89566D03*
X603163Y103971D03*
X608600Y103000D03*
X605028Y119000D03*
X626040Y98281D03*
X633800Y119000D03*
X658055Y141493D03*
X647555Y143643D03*
X651055Y142893D03*
X654555Y142193D03*
X642673Y139811D03*
X644055Y144493D03*
X635673Y141318D03*
X639173Y140618D03*
X632173Y142018D03*
X628673Y142718D03*
X609482Y124568D03*
X618800Y100100D03*
X649600Y391200D03*
X609191Y451454D03*
X615300Y457900D03*
X618430Y491550D03*
X623400Y476300D03*
X629300Y490000D03*
X648500Y477400D03*
X612515Y498752D03*
X609284Y480055D03*
X636500Y493924D03*
X627000Y478300D03*
X611250Y476750D03*
X608800Y473475D03*
X618800Y474500D03*
X639120Y475620D03*
X658900Y509300D03*
X639197Y490367D03*
X623600Y521700D03*
X662640Y528330D03*
X692000Y45000D03*
Y48500D03*
X697500D03*
Y45000D03*
X715130Y79574D03*
X697200Y79500D03*
X664471Y86061D03*
X670795Y89189D03*
X709560Y84648D03*
X689500Y37900D03*
X675235Y36797D03*
X670600Y144900D03*
Y150000D03*
X683100Y392200D03*
X687427Y384926D03*
X676900Y381800D03*
X680200Y432100D03*
X718546Y500283D03*
X669300Y504000D03*
X708500Y512500D03*
X690500Y523300D03*
X675500Y521900D03*
X691900Y531350D03*
Y534850D03*
X697500Y534750D03*
Y531250D03*
X739933Y447401D03*
X797780Y423484D03*
X890354Y112327D03*
X883661D03*
X907086D03*
X913779D03*
X927165D03*
X920472D03*
X944497Y110927D03*
X963245Y105725D03*
X961309Y499136D03*
X1144535Y112357D03*
X1138242D03*
X1167925D03*
X1161632D03*
X1181496D03*
X1204921D03*
X1174742D03*
X1198228D03*
X1277100Y122670D03*
X1272100Y141603D03*
X1264550Y114670D03*
X1261030Y105350D03*
X1270350Y98300D03*
X1262569Y147201D03*
X1269810Y154398D03*
X1275470Y99390D03*
X1257800Y120800D03*
X1252437Y140192D03*
X1240000Y129500D03*
X1259200Y168350D03*
X1221767Y175858D03*
X1267050Y169800D03*
X1233902Y173337D03*
X1262900Y466504D03*
X1336850Y76450D03*
X1336900Y61600D03*
X1336500Y81100D03*
X1337400Y72000D03*
X1323000Y83000D03*
X1328500Y92500D03*
X1310098Y150040D03*
X1293700Y121800D03*
X1301770Y101300D03*
X1320500Y145000D03*
X1325100D03*
X1287790Y156575D03*
X1310175Y154696D03*
X1315130Y164870D03*
X1315180Y169950D03*
X1326474Y216500D03*
X1338224Y209051D03*
X1305171Y164767D03*
X1310061Y165235D03*
X1330100Y165000D03*
Y170000D03*
X1340100Y165000D03*
Y170000D03*
X1335100D03*
Y165000D03*
X1320100D03*
X1325100D03*
X1320100Y170000D03*
X1325100D03*
X1299907Y159808D03*
X1295500Y159970D03*
X1283720Y223870D03*
X1296468Y437500D03*
X1300315Y427902D03*
X1335100Y427500D03*
Y432500D03*
X1300438Y433001D03*
X1318054Y460507D03*
X1340100Y432500D03*
X1304200Y462030D03*
X1287770Y501897D03*
X1299450Y484950D03*
X1380950Y30232D03*
X1350800Y66600D03*
X1350830Y60730D03*
X1356950Y54370D03*
X1356760Y66660D03*
X1357000Y60500D03*
X1351190Y54710D03*
X1363170Y54280D03*
X1362900Y60500D03*
X1363040Y66660D03*
X1377009Y39753D03*
X1355500Y83000D03*
X1359500D03*
X1343260Y53770D03*
X1370975Y67225D03*
X1370849Y59349D03*
X1351500Y83000D03*
X1371500Y63200D03*
X1357000Y86640D03*
X1357700Y108400D03*
X1352200D03*
Y104950D03*
X1357700D03*
X1401300Y149600D03*
X1353500Y96959D03*
X1348569Y208960D03*
X1367789Y209216D03*
X1384671Y214832D03*
X1350100Y170000D03*
X1380100Y165000D03*
X1355100Y170000D03*
X1360100D03*
X1355100Y165000D03*
X1360100D03*
X1345100D03*
X1350100D03*
X1345100Y170000D03*
X1365100D03*
Y165000D03*
X1370100D03*
X1375100Y170000D03*
X1370100D03*
X1375100Y165000D03*
X1380100Y170000D03*
X1360100Y452500D03*
Y457500D03*
X1385100Y452500D03*
X1390100Y457500D03*
Y452500D03*
X1349800Y458200D03*
X1350100Y447500D03*
Y452500D03*
X1370100D03*
X1375100D03*
X1352490Y515470D03*
X1346870Y515450D03*
X1352590Y519170D03*
X1346970Y519150D03*
X1347546Y476897D03*
X1347196Y472941D03*
X1354462Y474141D03*
X1350500Y475100D03*
X1390595Y549328D03*
X1375961Y569473D03*
X1376000Y565700D03*
X1380890Y615820D03*
X1386921Y620689D03*
X1375961Y600673D03*
X1375861Y597073D03*
X1375961Y593473D03*
X1425081Y48412D03*
X1420337Y45477D03*
X1416837D03*
X1438348Y155908D03*
X1458569Y192143D03*
X1446331Y197285D03*
X1408247Y206270D03*
X1422196Y218052D03*
X1452728Y243306D03*
X1464150Y235550D03*
X1422281Y221479D03*
X1441750Y236800D03*
X1444850Y242730D03*
X1496713Y174853D03*
X1470382Y188372D03*
X1472758Y216495D03*
X1513900Y218000D03*
X1519243Y191627D03*
X1487716Y218650D03*
X1510800Y193330D03*
X1512790Y240099D03*
X1503842Y245678D03*
X1491265Y226492D03*
X1483457Y244568D03*
X1573060Y84120D03*
X1577269Y95344D03*
X1583374Y81319D03*
X1574780Y90992D03*
X1584748Y70840D03*
X1575018Y71213D03*
X1556810Y71760D03*
X1563108Y126423D03*
X1577700Y140149D03*
X1557981Y141470D03*
X1573153Y103721D03*
X1576606Y104392D03*
X1574197Y127915D03*
X1572395Y110754D03*
X1558100Y128926D03*
X1566486Y181270D03*
X1568488Y164058D03*
X1583874Y217746D03*
X1582249Y191716D03*
X1572817Y169910D03*
X1570294Y167384D03*
X1543100Y184128D03*
X1558000Y205100D03*
X1549693Y196707D03*
X1552063Y202031D03*
X1558042Y172448D03*
X1557787Y192236D03*
X1561538Y174649D03*
X1587549Y192000D03*
X1598006Y192421D03*
X1644290Y196383D03*
X1593218Y191776D03*
X1635621Y208259D03*
X1637281Y260922D03*
Y254322D03*
X1632128Y225472D03*
X1659643Y213505D03*
X1681352Y196092D03*
X1669849Y193067D03*
X1702400Y193450D03*
X1664321Y195244D03*
X1658082Y195298D03*
X1655978Y207827D03*
X1664390Y201163D03*
X1660440Y200789D03*
X1667356Y213096D03*
X1676750Y206050D03*
X1664453Y308557D03*
X1660972Y401447D03*
X1660890Y397300D03*
X1660834Y404934D03*
X1673074Y453185D03*
X1678303Y442765D03*
X1719000Y190500D03*
X1720651Y246141D03*
X1715837Y246178D03*
X1724181Y246159D03*
X1834103Y176021D03*
X1834400Y216900D03*
X1887300Y121500D03*
X1850700Y156000D03*
X1875700Y115700D03*
Y121500D03*
X1881500Y115700D03*
Y121500D03*
Y127300D03*
X1887300D03*
X1846663Y153748D03*
X1887300Y115700D03*
X1875700Y127300D03*
X1890974Y105600D03*
X1898102Y107325D03*
X1885700Y141200D03*
X1897536Y114600D03*
Y120510D03*
X1867280Y135406D03*
X1881165Y105561D03*
X1857849Y148079D03*
X1872254Y138618D03*
X1857919Y156123D03*
X1864904Y114735D03*
X1897507Y124450D03*
X1854663Y158248D03*
X1846663D03*
X1863650Y189750D03*
X1877880Y203780D03*
X1882452Y195888D03*
X1889400Y191200D03*
X1886200Y161000D03*
X1875700Y184800D03*
X1876700Y207600D03*
X1862000Y177500D03*
X1884000Y188100D03*
X1884400Y183700D03*
X1865100Y174600D03*
X1877517Y217988D03*
X1844444Y224035D03*
X1856874Y219443D03*
X1850723Y219250D03*
X1878100Y450200D03*
X1918352Y89300D03*
X1923300Y94300D03*
X1948472Y80362D03*
X1946500Y104974D03*
X1934256Y99459D03*
X1923329Y99475D03*
X1923837Y118800D03*
X1937728Y99441D03*
X1900740Y178720D03*
X1900700Y172990D03*
Y167290D03*
X1906440Y178720D03*
X1906500Y173100D03*
X1906400Y167290D03*
X1912230Y167330D03*
Y173030D03*
X657250Y-2050D03*
X659747Y-12132D03*
X558659Y34100D03*
X551966D03*
X595470D03*
X588777D03*
X558659Y71900D03*
X555313Y92757D03*
Y65699D03*
X551966Y71900D03*
X548620Y92757D03*
Y65699D03*
X571345Y71500D03*
X568699Y92757D03*
Y65699D03*
X595470Y71900D03*
X592124Y92757D03*
Y65699D03*
X564966Y71500D03*
X562006Y92757D03*
Y65699D03*
X565266Y87374D03*
X588777Y71900D03*
X585431Y92757D03*
Y65699D03*
X555313Y54957D03*
X548620D03*
X568699D03*
X592124D03*
X562006D03*
X585431D03*
X598817Y92657D03*
X555313Y27899D03*
X548620D03*
X571345Y33700D03*
X568699Y27899D03*
X592124D03*
X564966Y33700D03*
X562006Y27899D03*
X585431D03*
X558659Y-3700D03*
X555313Y17157D03*
Y-9901D03*
X551966Y-3700D03*
X548620Y17157D03*
Y-9901D03*
X571345Y-4100D03*
X568699Y17157D03*
Y-9901D03*
X595470Y-3700D03*
X592124Y17157D03*
Y-9901D03*
X564966Y-4100D03*
X561868Y17019D03*
X562006Y-9901D03*
X588777Y-3700D03*
X585431Y17157D03*
Y-9901D03*
X598817Y17057D03*
X481691Y92757D03*
Y65699D03*
Y54957D03*
X485037Y34100D03*
X521848D03*
X515155D03*
X485037Y71900D03*
X497723Y71500D03*
X495077Y92757D03*
Y65699D03*
X521848Y71900D03*
X518502Y92757D03*
Y65699D03*
X491344Y71500D03*
X488384Y92757D03*
Y65699D03*
X511809Y92757D03*
X515155Y71900D03*
X511809Y65699D03*
X534534Y71500D03*
X531888Y92757D03*
Y65699D03*
X528155Y71500D03*
X525195Y92757D03*
Y65699D03*
X495077Y54957D03*
X518502D03*
X488384D03*
X491430Y49914D03*
X511809Y54957D03*
X531888D03*
X525195D03*
X528241Y49914D03*
X481691Y27899D03*
Y17157D03*
Y-9901D03*
X497723Y33700D03*
X495077Y27899D03*
X518502D03*
X491344Y33700D03*
X488384Y27899D03*
X511809D03*
X534534Y33700D03*
X531888Y27899D03*
X528155Y33700D03*
X525195Y27899D03*
X485037Y-3700D03*
X497723Y-4100D03*
X495077Y17157D03*
Y-9901D03*
X521848Y-3700D03*
X518502Y17157D03*
Y-9901D03*
X491344Y-4100D03*
X488384Y17157D03*
Y-9901D03*
X511809Y17157D03*
X515155Y-3700D03*
X511809Y-9901D03*
X534534Y-4100D03*
X531888Y17157D03*
Y-9901D03*
X528155Y-4100D03*
X525195Y17157D03*
Y-9901D03*
X478344Y34100D03*
X438187Y84714D03*
X431494Y65807D03*
Y89964D03*
X444880D03*
Y84714D03*
X460912Y71500D03*
X458266Y92757D03*
Y65699D03*
X454533Y71500D03*
X451573Y92757D03*
Y65699D03*
X478344Y71900D03*
X474998Y92757D03*
Y65699D03*
X428147Y87392D03*
X421454Y92757D03*
X434840Y87392D03*
X424801Y65807D03*
Y89964D03*
X438187D03*
X458266Y54957D03*
X474998D03*
X431494Y28007D03*
X460912Y33700D03*
X458266Y27899D03*
X454533Y33700D03*
X451573Y27899D03*
X474998D03*
X424801Y28007D03*
X438187Y-4536D03*
X431494Y-9901D03*
X444880Y-9786D03*
Y-4536D03*
X460912Y-4100D03*
X458266Y17157D03*
Y-9901D03*
X454533Y-4100D03*
X451573Y-9901D03*
X478344Y-3700D03*
X474998Y17157D03*
Y-9901D03*
X428147Y-1743D03*
X421454Y-7108D03*
X434840Y-1743D03*
X424801Y-9786D03*
X438187D03*
X404722Y89964D03*
X401375Y87392D03*
X414761Y92757D03*
X398029Y65807D03*
Y89964D03*
X404722Y84599D03*
X414761Y87392D03*
X408069Y65807D03*
X408068Y92757D03*
X394682Y87392D03*
Y49592D03*
X380600Y37400D03*
X384992Y81600D03*
X411415Y84714D03*
X394682Y68492D03*
X398029Y28007D03*
X408069D03*
X404722Y-9901D03*
X401375Y-1743D03*
X414761Y-7108D03*
X398029Y-9901D03*
X404722Y-4536D03*
X414761Y-1743D03*
X408068Y-7108D03*
X394682Y11792D03*
X394683Y-2200D03*
X376700Y-1300D03*
X371258Y-1858D03*
Y-9800D03*
X411415Y-4536D03*
X394682Y17157D03*
X294289Y92757D03*
Y65699D03*
Y54957D03*
X304328Y34100D03*
X297635D03*
X321061Y92757D03*
X327754Y87392D03*
X324407Y89964D03*
Y84599D03*
X314368Y92657D03*
X311021Y84714D03*
X304328Y71900D03*
X300982Y92757D03*
Y65699D03*
X297635Y71900D03*
X334447Y87392D03*
X331100Y89964D03*
X354415Y92757D03*
Y87392D03*
X351179Y89964D03*
X347833Y87392D03*
X344486Y84714D03*
Y89964D03*
X337793Y84599D03*
X341140Y92757D03*
X334447D03*
X300982Y54957D03*
X317714Y84714D03*
X294289Y27899D03*
Y17157D03*
Y-9901D03*
X300982Y27899D03*
X321061Y-7108D03*
X327754Y-1743D03*
X324407Y-9901D03*
Y-4536D03*
X314368Y-7108D03*
X311021Y-4536D03*
X304328Y-3700D03*
X300982Y17157D03*
Y-9901D03*
X297635Y-3700D03*
X334447Y-1743D03*
X331100Y-9786D03*
X354526Y-7108D03*
X354525Y-1742D03*
X351179Y-9901D03*
X347833Y-1743D03*
X344486Y-4536D03*
Y-9786D03*
X337793Y-4536D03*
X341140Y-7108D03*
X334447D03*
X317714Y-4536D03*
X234053Y92757D03*
Y65699D03*
Y54957D03*
X267517Y34100D03*
X260824D03*
X243392Y71500D03*
X240746Y92757D03*
Y65699D03*
X267517Y71900D03*
X264171Y92757D03*
Y65699D03*
X237013Y71500D03*
X260824Y71900D03*
X257478Y92757D03*
Y65699D03*
X280203Y71500D03*
X277557Y92757D03*
Y65699D03*
X270864Y92757D03*
X273824Y71500D03*
X270864Y65699D03*
X240746Y54957D03*
X264171D03*
X257478D03*
X277557D03*
X270864D03*
X273910Y49914D03*
X234053Y27899D03*
Y17157D03*
Y-9901D03*
X243392Y33700D03*
X240746Y27899D03*
X264171D03*
X237013Y33700D03*
X257478Y27899D03*
X280203Y33700D03*
X277557Y27899D03*
X273824Y33700D03*
X270864Y27899D03*
X243392Y-4100D03*
X240746Y17157D03*
Y-9901D03*
X267517Y-3700D03*
X264171Y17157D03*
Y-9901D03*
X237013Y-4100D03*
X260824Y-3700D03*
X257478Y17157D03*
Y-9901D03*
X280203Y-4100D03*
X277557Y17157D03*
Y-9901D03*
X270864Y17157D03*
X273824Y-4100D03*
X270864Y-9901D03*
X193895Y34100D03*
X187202D03*
X230706D03*
X224013D03*
X193895Y71900D03*
X190549Y92757D03*
Y65699D03*
X187202Y71900D03*
X183856Y92757D03*
Y65699D03*
X206581Y71500D03*
X203935Y92757D03*
Y65699D03*
X230706Y71900D03*
X227360Y92757D03*
Y65699D03*
X200202Y71500D03*
X197242Y92757D03*
Y65699D03*
X224013Y71900D03*
X220667Y92761D03*
Y65699D03*
X190549Y54957D03*
X183856D03*
X203935D03*
X227360D03*
X197242D03*
X220667D03*
X190549Y27899D03*
X183856D03*
X206581Y33700D03*
X203935Y27899D03*
X227360D03*
X200202Y33700D03*
X197242Y27899D03*
X220667D03*
X193895Y-3700D03*
X190549Y17157D03*
Y-9901D03*
X187202Y-3700D03*
X183856Y17157D03*
Y-9901D03*
X206581Y-4100D03*
X203935Y17157D03*
Y-9901D03*
X230706Y-3700D03*
X227360Y17157D03*
Y-9901D03*
X200202Y-4100D03*
X197242Y17157D03*
Y-9901D03*
X224013Y-3700D03*
X220667Y17157D03*
Y-9901D03*
X157084Y34100D03*
X150391D03*
X116070Y35780D03*
X132959Y71500D03*
X130313Y92757D03*
X163391Y71500D03*
X160431Y92757D03*
Y65699D03*
X130313D03*
X157084Y71900D03*
X153738Y92757D03*
Y65699D03*
X126580Y71500D03*
X123620Y92757D03*
Y65699D03*
X150391Y71900D03*
X147045Y92757D03*
Y65699D03*
X169770Y71500D03*
X167124Y92757D03*
Y65699D03*
X130313Y54957D03*
X160431D03*
X153738D03*
X123620D03*
X147045D03*
X167124D03*
X113100Y57770D03*
X132959Y33700D03*
X163391D03*
X160431Y27899D03*
X130313D03*
X153738D03*
X126580Y33700D03*
X123620Y27899D03*
X147045D03*
X169770Y33700D03*
X167124Y27899D03*
X132959Y-4100D03*
X130313Y17157D03*
X163391Y-4100D03*
X160431Y17157D03*
Y-9901D03*
X130313D03*
X157084Y-3700D03*
X153738Y17157D03*
Y-9901D03*
X126580Y-4100D03*
X123620Y17157D03*
Y-9901D03*
X147045Y17157D03*
X150391Y-3700D03*
X147045Y-9901D03*
X169770Y-4100D03*
X167124Y17157D03*
Y-9901D03*
X114050Y21320D03*
X116692Y-1800D03*
X116300Y-9460D03*
X104500Y-1850D03*
X660217Y576734D03*
X558659Y610700D03*
X555313Y593757D03*
Y604499D03*
X551966Y610700D03*
X548620Y593757D03*
Y604499D03*
X571345Y610300D03*
X568699Y593757D03*
Y604499D03*
X592124Y593757D03*
X595470Y610700D03*
X592124Y604499D03*
X564966Y610300D03*
X562006Y593757D03*
Y604499D03*
X585431Y593757D03*
X588777Y610700D03*
X585431Y604499D03*
X598817Y593657D03*
X555313Y528899D03*
X548620D03*
X568699D03*
X592124D03*
X562006D03*
X585431D03*
X558659Y535100D03*
X551966D03*
X571345Y534700D03*
X595470Y535100D03*
X564966Y534700D03*
X588777Y535100D03*
X555313Y555957D03*
X558659Y572900D03*
X555313Y566699D03*
X548620Y555957D03*
X551966Y572900D03*
X548620Y566699D03*
X568699Y555957D03*
X571345Y572500D03*
X568699Y566699D03*
X592124Y555957D03*
X595470Y572900D03*
X592124Y566699D03*
X562006Y555957D03*
X564966Y572500D03*
X565266Y550574D03*
X562006Y566699D03*
X585431Y555957D03*
X588777Y572900D03*
X585431Y566699D03*
X565052Y588714D03*
X555313Y518157D03*
X548620D03*
X568699D03*
X592124D03*
X562006D03*
X565266Y512774D03*
X585431Y518157D03*
X598817Y518057D03*
X481691Y593757D03*
Y604499D03*
X485037Y610700D03*
X495077Y593757D03*
X498092Y611200D03*
X495077Y604499D03*
X521848Y610700D03*
X518502Y593757D03*
Y604499D03*
X488384Y593757D03*
X491724Y611668D03*
X488384Y604499D03*
X515155Y610700D03*
X511809Y593757D03*
Y604499D03*
X534534Y610300D03*
X531888Y593757D03*
Y604499D03*
X528155Y610300D03*
X525195Y593757D03*
Y604499D03*
X481691Y528899D03*
Y555957D03*
Y566699D03*
X495077Y528899D03*
X518502D03*
X488384D03*
X511809D03*
X531888D03*
X525195D03*
X485037Y535100D03*
X497723Y534700D03*
X521848Y535100D03*
X491344Y534700D03*
X515155Y535100D03*
X534534Y534700D03*
X528155D03*
X485037Y572900D03*
X495077Y555957D03*
X497723Y572500D03*
X495077Y566699D03*
X518502Y555957D03*
X521848Y572900D03*
X518502Y566699D03*
X488384Y555957D03*
X491344Y572500D03*
X488384Y566699D03*
X511809Y555957D03*
X515155Y572900D03*
X511809Y566699D03*
X531888Y555957D03*
X534534Y572500D03*
X531888Y566699D03*
X525195Y555957D03*
X528155Y572500D03*
X525195Y566699D03*
X481691Y518157D03*
X495077D03*
X518502D03*
X488384D03*
X511809D03*
X531888D03*
X525195D03*
X438187Y609864D03*
X431494Y604499D03*
X444880Y604614D03*
Y609864D03*
X458266Y593757D03*
X460912Y610300D03*
X458266Y604499D03*
X454533Y610300D03*
X451573Y593757D03*
Y604499D03*
X474998Y593757D03*
Y604499D03*
X428147Y612657D03*
X421454Y607292D03*
X434840Y612657D03*
X424801Y604614D03*
X438187D03*
X447766Y612659D03*
X458266Y528899D03*
X451573D03*
X474998D03*
X460912Y534700D03*
X454533D03*
X478344Y535100D03*
X431494Y566807D03*
X458266Y555957D03*
X460912Y572500D03*
X458266Y566699D03*
X451573Y555957D03*
X454533Y572500D03*
X451573Y566699D03*
X474998Y555957D03*
X478344Y572900D03*
X474998Y566699D03*
X424801Y566807D03*
X438187Y510114D03*
X431494Y515364D03*
X444880D03*
Y510114D03*
X458266Y518157D03*
X451573D03*
X474998D03*
X428147Y512792D03*
X421454Y518157D03*
X434840Y512792D03*
X424801Y515364D03*
X438187D03*
X404722Y604499D03*
X401376Y612658D03*
X414761Y607292D03*
X398029Y604499D03*
X404722Y609864D03*
X414761Y612657D03*
X408068Y607292D03*
X394682Y612657D03*
X378600Y606200D03*
X371312Y604709D03*
X411415Y609864D03*
X394682Y607292D03*
X398029Y529007D03*
X408069D03*
X394587Y529026D03*
X394595Y537058D03*
X398029Y566807D03*
X408069D03*
X394682Y550592D03*
Y588392D03*
X376892Y581127D03*
X370596Y585614D03*
X394682Y569492D03*
X404722Y515364D03*
X401375Y512792D03*
X414761Y518157D03*
X398029Y515364D03*
X404722Y509999D03*
X414761Y512792D03*
X408068Y518157D03*
X394682Y512792D03*
X411415Y510114D03*
X294289Y593757D03*
Y604499D03*
X321061Y607292D03*
X327754Y612457D03*
X324407Y604499D03*
Y609864D03*
X314368Y607292D03*
X311021Y609864D03*
X304328Y610700D03*
X300982Y593757D03*
Y604499D03*
X297635Y610700D03*
X334447Y612457D03*
X331100Y604614D03*
X354526Y607292D03*
X354525Y612358D03*
X351179Y604499D03*
X347833Y612357D03*
X344486Y609864D03*
Y604614D03*
X337793Y609864D03*
X341140Y607292D03*
X334447D03*
X317714Y609864D03*
X294289Y528899D03*
Y555957D03*
Y566699D03*
X300982Y528899D03*
X304328Y535100D03*
X297635D03*
X300982Y555957D03*
X304328Y572900D03*
X300982Y566699D03*
X297635Y572900D03*
X294289Y518157D03*
X321061D03*
X327754Y512792D03*
X324407Y515364D03*
Y509999D03*
X314368Y518057D03*
X311021Y510114D03*
X300982Y518157D03*
X334447Y512792D03*
X331100Y515364D03*
X354526Y518157D03*
X354307Y512792D03*
X351179Y515364D03*
X347833Y512792D03*
X344486Y510114D03*
Y515364D03*
X337793Y509999D03*
X341140Y518157D03*
X334447D03*
X317714Y510114D03*
X234053Y593757D03*
Y604499D03*
X240746Y593757D03*
X243392Y610300D03*
X240746Y604499D03*
X267517Y610700D03*
X264171Y593757D03*
Y604499D03*
X237013Y610300D03*
X257478Y593757D03*
X260824Y610700D03*
X257478Y604499D03*
X280203Y610300D03*
X277557Y593757D03*
Y604499D03*
X273824Y610300D03*
X270864Y593757D03*
Y604499D03*
X234053Y528899D03*
Y555957D03*
Y566699D03*
X240746Y528899D03*
X264171D03*
X257478D03*
X277557D03*
X270864D03*
X243392Y534700D03*
X267517Y535100D03*
X237013Y534700D03*
X260824Y535100D03*
X280203Y534700D03*
X273824D03*
X240746Y555957D03*
X243392Y572500D03*
X240746Y566699D03*
X264171Y555957D03*
X267517Y572900D03*
X264171Y566699D03*
X237013Y572500D03*
X257478Y555957D03*
X260824Y572900D03*
X257478Y566699D03*
X277557Y555957D03*
X280203Y572500D03*
X277557Y566699D03*
X270864Y555957D03*
X273824Y572500D03*
X270864Y566699D03*
X234053Y518157D03*
X240746D03*
X264171D03*
X257478D03*
X277557D03*
X270864D03*
X190549Y593757D03*
X193895Y610700D03*
X190549Y604499D03*
X183856Y593757D03*
X187202Y610700D03*
X183856Y604499D03*
X206581Y610300D03*
X203935Y593757D03*
Y604499D03*
X230706Y610700D03*
X227360Y593757D03*
Y604499D03*
X197242Y593757D03*
X200202Y610300D03*
X197242Y604499D03*
X224013Y610700D03*
X220667Y593761D03*
Y604499D03*
X190549Y528899D03*
X183856D03*
X203935D03*
X227360D03*
X197242D03*
X220667D03*
X193895Y535100D03*
X187202D03*
X206581Y534700D03*
X230706Y535100D03*
X200202Y534700D03*
X224013Y535100D03*
X190549Y555957D03*
X193895Y572900D03*
X190549Y566699D03*
X183856Y555957D03*
X187202Y572900D03*
X183856Y566699D03*
X203935Y555957D03*
X206581Y572500D03*
X203935Y566699D03*
X227360Y555957D03*
X230706Y572900D03*
X227360Y566699D03*
X197242Y555957D03*
X200202Y572500D03*
X197242Y566699D03*
X220667Y555961D03*
X224013Y572900D03*
X220667Y566699D03*
X190549Y518157D03*
X183856D03*
X203935D03*
X227360D03*
X197242D03*
X220667Y518161D03*
X132959Y610300D03*
X130313Y593757D03*
X163391Y610300D03*
X160431Y593757D03*
Y604499D03*
X130313D03*
X157084Y610700D03*
X153738Y593757D03*
Y604499D03*
X126580Y610300D03*
X123620Y593757D03*
Y604499D03*
X150391Y610700D03*
X147045Y593757D03*
Y604499D03*
X167124Y593757D03*
X169770Y610300D03*
X167124Y604499D03*
X160431Y528899D03*
X130313D03*
X153738D03*
X123620D03*
X147045D03*
X167124D03*
X132959Y534700D03*
X163391D03*
X157084Y535100D03*
X126580Y534700D03*
X150391Y535100D03*
X169770Y534700D03*
X130313Y555957D03*
X132959Y572500D03*
X160431Y555957D03*
X163391Y572500D03*
X160431Y566699D03*
X130313D03*
X153738Y555957D03*
X157084Y572900D03*
X153738Y566699D03*
X123620Y555957D03*
X126580Y572500D03*
X123620Y566699D03*
X147045Y555957D03*
X150391Y572900D03*
X147045Y566699D03*
X167124Y555957D03*
X169770Y572500D03*
X167124Y566699D03*
X114150Y585850D03*
X114509Y575658D03*
X116927Y555700D03*
X115883Y548024D03*
X130313Y518157D03*
X160431D03*
X153738D03*
X123620D03*
X147045D03*
X167124D03*
X116927Y517900D03*
X114322Y525980D03*
X274619Y271509D03*
X294899D03*
Y267609D03*
X291519Y273460D03*
X277999D03*
X355737Y252009D03*
X348978D03*
X321938D03*
X352357Y253960D03*
X345598D03*
X355737Y255909D03*
X348978D03*
X338838Y273460D03*
X345598Y261760D03*
X338838Y269560D03*
X332078Y273460D03*
X298279D03*
X335458Y275409D03*
X328698D03*
X338838Y277360D03*
X332078D03*
X325318D03*
X335458Y279310D03*
X328698D03*
X321938D03*
X335458Y271509D03*
X301659D03*
X328698D03*
X298279Y269560D03*
X348978Y259809D03*
X345598Y257860D03*
X352357D03*
X359117Y253960D03*
X362497Y252009D03*
X407448Y338641D03*
X394648Y338341D03*
X430089Y338428D03*
X426494Y338361D03*
X291519Y324160D03*
X288139Y322209D03*
X291519Y320260D03*
X348978Y326110D03*
X352357Y331960D03*
X348978Y330009D03*
X355737Y333909D03*
X348978Y322209D03*
X294899Y330009D03*
Y326109D03*
X359117Y335860D03*
X368127Y333460D03*
X371507Y335409D03*
X361367Y329560D03*
X364747Y331509D03*
X357057Y324160D03*
X357987Y327609D03*
X415634Y243496D03*
Y239596D03*
X469913Y259096D03*
X473292Y261047D03*
X469913Y262996D03*
Y266896D03*
X459773Y264947D03*
X422594Y247396D03*
X466533Y268847D03*
X469913Y278596D03*
X474413Y274696D03*
X477792Y280547D03*
Y276646D03*
X463153Y262996D03*
X466533Y261047D03*
X446253Y253247D03*
X439493Y245447D03*
X442873Y247396D03*
X439493Y249347D03*
X442873Y251296D03*
X446253Y249347D03*
X436113Y247396D03*
X455263Y267197D03*
X441743Y259397D03*
X431604Y257446D03*
X421464Y255497D03*
X438363Y257446D03*
X434983Y255497D03*
X465100Y280300D03*
X452865Y270081D03*
X418084Y253546D03*
X419214Y245447D03*
X466100Y300021D03*
X463800Y289500D03*
X469913Y290296D03*
Y294196D03*
X477792Y292247D03*
Y300047D03*
Y296147D03*
Y284447D03*
X469913Y301996D03*
Y298096D03*
Y282496D03*
X538631Y202247D03*
X528491Y204496D03*
X531871Y218147D03*
X521731Y216196D03*
X494692Y274696D03*
X525111Y264947D03*
X521731Y262996D03*
X494692Y259096D03*
X498072Y261047D03*
X501452Y278596D03*
X504832Y261047D03*
X501452Y262996D03*
X528491Y239596D03*
X525111Y241547D03*
X528491Y251296D03*
X531871Y253247D03*
X498072Y272747D03*
X518352Y276646D03*
X511592Y280547D03*
X504832D03*
X525111Y276646D03*
X518352Y280547D03*
X498072Y257147D03*
Y253247D03*
X504832Y272747D03*
X511592Y276647D03*
X491312D03*
X498072D03*
X521731Y278596D03*
X498072Y249347D03*
X528491Y266896D03*
Y262996D03*
X521731Y243496D03*
X508212D03*
X518352Y264947D03*
X508212Y247396D03*
X504832Y249347D03*
X508212Y251296D03*
X504832Y257147D03*
X494692Y266896D03*
X531871Y264947D03*
X535251Y255196D03*
X528491Y278596D03*
Y270796D03*
X535251Y223996D03*
X531871Y237647D03*
X528491Y223996D03*
X531871Y249347D03*
Y241547D03*
X518352Y233746D03*
X484552Y280547D03*
X504832Y225947D03*
X494692Y223996D03*
X498072Y245447D03*
X504832Y276647D03*
X511592Y272747D03*
X491312D03*
X504832Y268847D03*
X508212Y274696D03*
X518352Y257147D03*
X514972Y274696D03*
X498072Y280547D03*
X483432Y262996D03*
X486812Y261047D03*
X491312Y280547D03*
X521731Y270796D03*
X501452Y251296D03*
Y255196D03*
X514972D03*
X511592Y268847D03*
X501452Y270796D03*
X484552Y276646D03*
Y272747D03*
X518352Y222047D03*
X514972Y220096D03*
X511592Y222047D03*
X487932Y325396D03*
X484552Y327347D03*
X487932Y321496D03*
X494692Y317596D03*
X521731Y313696D03*
X528491D03*
X514972D03*
X518352Y307847D03*
X521731Y309797D03*
Y305896D03*
X525111Y303947D03*
Y307847D03*
Y311747D03*
X528491Y309797D03*
Y301996D03*
X514972Y309797D03*
Y305896D03*
X518352Y303947D03*
X504832Y300045D03*
Y303947D03*
X508212Y301996D03*
Y305896D03*
X504832Y311747D03*
X518352D03*
X528491Y305896D03*
X491312Y323446D03*
X511592Y292245D03*
Y288347D03*
X484552Y315647D03*
Y311747D03*
X535251Y313696D03*
X531871Y296147D03*
X538631D03*
X535251Y305896D03*
Y298096D03*
X538631Y300047D03*
Y303947D03*
Y307847D03*
X511592Y303947D03*
Y300047D03*
X508212Y309797D03*
X511592Y311747D03*
X487932Y298096D03*
X501452Y309797D03*
X487932Y301996D03*
X494692D03*
X491312Y296147D03*
X487932Y294196D03*
X484552Y303947D03*
X498072Y307847D03*
X494692Y298096D03*
X501452Y305896D03*
X491312Y303947D03*
X487932Y305896D03*
X484552Y284447D03*
X521731Y321496D03*
X508212D03*
X504832Y327347D03*
X484552Y296147D03*
Y288347D03*
X487932Y290296D03*
Y286396D03*
X531871Y315647D03*
X508212Y286396D03*
X504832Y284447D03*
Y288347D03*
X518352Y284447D03*
X504832Y292247D03*
X498072D03*
X494692Y290296D03*
X501452Y286396D03*
X498072Y288347D03*
Y284447D03*
X491312D03*
Y288347D03*
X484552Y331247D03*
Y319546D03*
X491312Y315647D03*
X487932Y313696D03*
X494692Y282496D03*
X508212D03*
X521731D03*
X514972D03*
X481172Y286396D03*
Y294196D03*
Y305896D03*
Y298096D03*
Y333196D03*
Y282496D03*
Y348796D03*
X558911Y218147D03*
X542011Y208396D03*
X545391Y276646D03*
X548771Y262996D03*
Y270796D03*
X545391Y237647D03*
X548771Y251296D03*
X552151Y245447D03*
X548771Y227896D03*
X555531Y231797D03*
X552151Y237647D03*
X542011Y270796D03*
Y223996D03*
X548771Y298096D03*
Y301996D03*
Y294196D03*
Y290296D03*
Y282496D03*
X542011Y301996D03*
Y305896D03*
Y309797D03*
X641665Y281139D03*
X632869Y293720D03*
X628950Y293550D03*
X654950Y253446D03*
X633410Y269610D03*
Y274610D03*
X651235Y249165D03*
X643100Y253700D03*
X649800Y252600D03*
X652700Y270600D03*
X617235Y247735D03*
X542011Y383896D03*
Y391696D03*
Y395597D03*
Y387796D03*
Y379996D03*
X545391Y389747D03*
Y393647D03*
Y378047D03*
X552151Y374146D03*
X545391D03*
X548771Y364396D03*
Y360496D03*
Y356596D03*
Y383896D03*
Y376096D03*
Y372196D03*
X545391Y370247D03*
Y362447D03*
X552151Y358547D03*
X548771Y352696D03*
X545391Y381947D03*
X548771Y379996D03*
X552151Y366347D03*
Y370247D03*
X563500Y360500D03*
X555531Y372197D03*
X562591Y348796D03*
X542011Y317596D03*
X548771Y321496D03*
X545391Y323446D03*
X552151Y319547D03*
Y315647D03*
Y311747D03*
X559211Y331103D03*
X555531Y329296D03*
X559211Y323446D03*
X555531Y321496D03*
X548771Y317596D03*
X555831Y313696D03*
X552151Y307847D03*
X559211Y327347D03*
X552151D03*
X555531Y325396D03*
X555831Y317446D03*
X518352Y405347D03*
X525111D03*
X504832Y370247D03*
X508212Y376096D03*
X501452Y372197D03*
X498072Y370247D03*
X504832Y397546D03*
Y393647D03*
X511592D03*
X501452Y387796D03*
X511592Y385847D03*
X518352D03*
Y381947D03*
Y378047D03*
X508212Y395597D03*
X504832Y389747D03*
X508212Y391696D03*
X504832Y385847D03*
X511592Y381947D03*
X514972Y383896D03*
X521731Y379996D03*
X518352Y374146D03*
X525111Y401447D03*
X528491Y395597D03*
X535251Y399496D03*
X531871Y393647D03*
X538631Y389747D03*
Y385847D03*
X518352Y401447D03*
X521731Y403396D03*
X528491Y399496D03*
X531871Y397546D03*
X535251Y395597D03*
Y391696D03*
Y387796D03*
X525111Y370247D03*
X531871D03*
X525111Y362447D03*
X528491Y360496D03*
Y356596D03*
X535251Y352696D03*
X525111Y378047D03*
Y374146D03*
Y366347D03*
X528491Y368296D03*
X521731Y364396D03*
X525111Y358547D03*
X531871Y354647D03*
Y350747D03*
X521731Y376096D03*
X528491Y372197D03*
X535251Y376096D03*
X464273Y342947D03*
X471033D03*
X460893Y344896D03*
X471033Y346847D03*
X464273D03*
X471033Y339047D03*
X469913Y309797D03*
Y313696D03*
Y317596D03*
X1296908Y36900D03*
X1327500Y51547D03*
X1327452Y55544D03*
X1324127Y50827D03*
X1301219Y89141D03*
X1304500Y40066D03*
X1308400Y79600D03*
X1293600Y-17000D03*
X1293816Y-13533D03*
X1292692Y1008D03*
X1287700Y-16700D03*
X1303774Y-18842D03*
X1220953Y71500D03*
X1245078Y34100D03*
X1238385D03*
X1245078Y71900D03*
X1241732Y65699D03*
X1238385Y71900D03*
X1235039Y65699D03*
X1241732Y54957D03*
X1235039D03*
X1220953Y33700D03*
Y-4100D03*
X1241732Y27899D03*
X1235039D03*
X1245078Y-3700D03*
X1241732Y17157D03*
Y-9901D03*
X1238385Y-3700D03*
X1235039Y17157D03*
Y-9901D03*
X1248425Y17057D03*
X1265157Y9157D03*
X1276346Y-10250D03*
X1171456Y34100D03*
X1164763D03*
X1208267D03*
X1201574D03*
X1171456Y71900D03*
X1168110Y65699D03*
X1164763Y71900D03*
X1161417Y65699D03*
X1184142Y71500D03*
X1181496Y65699D03*
X1208267Y71900D03*
X1204921Y65699D03*
X1177763Y71500D03*
X1174803Y65699D03*
X1201574Y71900D03*
X1198228Y65699D03*
X1218307D03*
X1214574Y71500D03*
X1214874Y87374D03*
X1211614Y65699D03*
X1168110Y54957D03*
X1161417D03*
X1181496D03*
X1204921D03*
X1174803D03*
X1177849Y49914D03*
X1198228Y54957D03*
X1218307D03*
X1211614D03*
X1168110Y27899D03*
X1161417D03*
X1184142Y33700D03*
X1181496Y27899D03*
X1204921D03*
X1177763Y33700D03*
X1174803Y27899D03*
X1198228D03*
X1218307D03*
X1214574Y33700D03*
X1211614Y27899D03*
X1171456Y-3700D03*
X1168110Y17157D03*
Y-9901D03*
X1164763Y-3700D03*
X1161417Y17157D03*
Y-9901D03*
X1184142Y-4100D03*
X1181496Y17157D03*
Y-9901D03*
X1204921Y17157D03*
X1208267Y-3700D03*
X1204921Y-9901D03*
X1177763Y-4100D03*
X1174803Y17157D03*
Y-9901D03*
X1198228Y17157D03*
X1201574Y-3700D03*
X1198228Y-9901D03*
X1218307Y17157D03*
Y-9901D03*
X1214574Y-4100D03*
X1211614Y17157D03*
Y-9901D03*
X1134645Y34100D03*
X1127952D03*
X1110520Y71500D03*
X1107874Y65699D03*
X1134645Y71900D03*
X1131299Y65699D03*
X1104141Y71500D03*
X1101181Y65699D03*
X1127952Y71900D03*
X1124606Y65699D03*
X1147331Y71500D03*
X1144685Y65699D03*
X1140952Y71500D03*
X1137992Y65699D03*
X1107874Y54957D03*
X1131299D03*
X1124606D03*
X1144685D03*
X1137992D03*
X1141038Y49914D03*
X1110520Y33700D03*
X1107874Y27899D03*
X1131299D03*
X1104141Y33700D03*
X1101181Y27899D03*
X1124606D03*
X1147331Y33700D03*
X1144685Y27899D03*
X1140952Y33700D03*
X1137992Y27899D03*
X1110520Y-4100D03*
X1107874Y17157D03*
Y-9901D03*
X1134645Y-3700D03*
X1131299Y17157D03*
Y-9901D03*
X1104141Y-4100D03*
X1101181Y-9901D03*
X1127952Y-3700D03*
X1124606Y17157D03*
Y-9901D03*
X1147331Y-4100D03*
X1144685Y17157D03*
Y-9901D03*
X1140952Y-4100D03*
X1137992Y17157D03*
Y-9901D03*
X1054330Y89964D03*
X1050983Y87392D03*
X1087795Y84714D03*
X1081102Y65807D03*
X1064369Y92757D03*
X1081102Y89964D03*
X1094488D03*
Y84714D03*
X1047637Y65807D03*
Y89964D03*
X1054330Y84599D03*
X1077755Y87392D03*
X1064369D03*
X1071062Y92757D03*
X1057677Y65807D03*
X1057676Y92757D03*
X1084448Y87392D03*
X1074409Y65807D03*
Y89964D03*
X1087795D03*
X1044290Y87392D03*
Y49592D03*
X1061023Y84714D03*
X1044290Y68964D03*
X1081102Y28007D03*
X1047637D03*
X1057677D03*
X1074409D03*
X1054330Y-9901D03*
X1050983Y-1743D03*
X1087795Y-4536D03*
X1064369Y-7108D03*
X1081102Y-9901D03*
X1094488Y-9786D03*
Y-4536D03*
X1047637Y-9901D03*
X1054330Y-4536D03*
X1077755Y-1743D03*
X1064369D03*
X1071062Y-7108D03*
X1057676D03*
X1084448Y-1743D03*
X1074409Y-9786D03*
X1087795D03*
X1044290Y11792D03*
X1044291Y-2200D03*
X1061023Y-4536D03*
X974015Y89964D03*
Y84599D03*
X977362Y87392D03*
X984055D03*
X980708Y89964D03*
X1004023Y87392D03*
X1000787Y89964D03*
X997441Y87392D03*
X994094Y84714D03*
Y89964D03*
X987401Y84599D03*
X1020650Y46900D03*
X974015Y-9901D03*
Y-4536D03*
X977362Y-1743D03*
X984055D03*
X980708Y-9786D03*
X1004134Y-7108D03*
X1004133Y-1742D03*
X1000787Y-9901D03*
X997441Y-1743D03*
X994094Y-4536D03*
Y-9786D03*
X987401Y-4536D03*
X990748Y-7108D03*
X984055D03*
X1020866Y-1858D03*
X1027202Y-11005D03*
X913779Y65699D03*
Y54957D03*
X917125Y34100D03*
X953936D03*
X947243D03*
X960629Y84714D03*
X917125Y71900D03*
X929811Y71500D03*
X927165Y65699D03*
X953936Y71900D03*
X950590Y65699D03*
X923432Y71500D03*
X920472Y65699D03*
X947243Y71900D03*
X943897Y65699D03*
X927165Y54957D03*
X950590D03*
X920472D03*
X923518Y49914D03*
X943897Y54957D03*
X967322Y84714D03*
X913779Y27899D03*
Y17157D03*
Y-9901D03*
X929811Y33700D03*
X927165Y27899D03*
X950590D03*
X923432Y33700D03*
X920472Y27899D03*
X943897D03*
X970669Y-7108D03*
X963976D03*
X960629Y-4536D03*
X917125Y-3700D03*
X929811Y-4100D03*
X927165Y17157D03*
Y-9901D03*
X953936Y-3700D03*
X950590Y17157D03*
Y-9901D03*
X923432Y-4100D03*
X920472Y17157D03*
Y-9901D03*
X947243Y-3700D03*
X943897Y17157D03*
Y-9901D03*
X967322Y-4536D03*
X849810Y71500D03*
X880314Y34100D03*
X873621D03*
X910432D03*
X856189Y71500D03*
X853543Y65699D03*
X880314Y71900D03*
X876968Y65699D03*
X873621Y71900D03*
X870275Y65699D03*
X893000Y71500D03*
X890354Y65699D03*
X886621Y71500D03*
X883661Y65699D03*
X910432Y71900D03*
X907086Y65699D03*
X853543Y54957D03*
X876968D03*
X870275D03*
X890354D03*
X883661D03*
X907086D03*
X849810Y33700D03*
Y-4100D03*
X856189Y33700D03*
X853543Y27899D03*
X876968D03*
X870275D03*
X893000Y33700D03*
X890354Y27899D03*
X886621Y33700D03*
X883661Y27899D03*
X907086D03*
X856189Y-4100D03*
X853543Y17157D03*
Y-9901D03*
X880314Y-3700D03*
X876968Y17157D03*
Y-9901D03*
X873621Y-3700D03*
X870275Y17157D03*
Y-9901D03*
X893000Y-4100D03*
X890354Y17157D03*
Y-9901D03*
X883661Y17157D03*
X886621Y-4100D03*
X883661Y-9901D03*
X907086Y17157D03*
X910432Y-3700D03*
X907086Y-9901D03*
X843503Y34100D03*
X836810D03*
X806692D03*
X799999D03*
X843503Y71900D03*
X840157Y65699D03*
X812999Y71500D03*
X810039Y65699D03*
X836810Y71900D03*
X833464Y65699D03*
X846850D03*
X806692Y71900D03*
X803346Y65699D03*
X799999Y71900D03*
X796653Y65699D03*
X819378Y71500D03*
X816732Y65699D03*
X840157Y54957D03*
X810039D03*
X833464D03*
X846850D03*
X803346D03*
X796653D03*
X816732D03*
X840157Y27899D03*
X812999Y33700D03*
X810039Y27899D03*
X833464D03*
X846850D03*
X803346D03*
X796653D03*
X819378Y33700D03*
X816732Y27899D03*
X843503Y-3700D03*
X840157Y17157D03*
Y-9901D03*
X812999Y-4100D03*
X810039Y17157D03*
Y-9901D03*
X833464Y17157D03*
X836810Y-3700D03*
X833464Y-9901D03*
X846850Y17157D03*
Y-9901D03*
X806692Y-3700D03*
X803346Y17157D03*
Y-9901D03*
X799999Y-3700D03*
X796653Y17157D03*
Y-9901D03*
X816732Y17157D03*
X819378Y-4100D03*
X816732Y-9901D03*
X765900Y35800D03*
X782567Y71500D03*
X779921Y65699D03*
X776188Y71500D03*
X773228Y65699D03*
X779921Y54957D03*
X773228D03*
X782567Y33700D03*
X779921Y27899D03*
X776188Y33700D03*
X773228Y27899D03*
X782567Y-4100D03*
X779921Y17157D03*
Y-9901D03*
X776188Y-4100D03*
X773228Y17157D03*
Y-9901D03*
X763500Y23940D03*
X765400Y-9800D03*
X766300Y-1800D03*
X729600Y17991D03*
X734256D03*
X755000Y17255D03*
X724837Y13852D03*
X714300Y-1900D03*
X719400Y14300D03*
X1308500Y540784D03*
X1318500Y539900D03*
X1305500Y542500D03*
X1220953Y610300D03*
X1241732Y593757D03*
X1245078Y610700D03*
X1241732Y604499D03*
X1238385Y610700D03*
X1235039Y593757D03*
Y604499D03*
X1248425Y593657D03*
X1220953Y534700D03*
Y572500D03*
X1241732Y528899D03*
X1235039D03*
X1245078Y535100D03*
X1238385D03*
X1241732Y555957D03*
X1245078Y572900D03*
X1241732Y566699D03*
X1238385Y572900D03*
X1235039Y555957D03*
Y566699D03*
X1251771Y547957D03*
Y585757D03*
Y566699D03*
X1255120Y555144D03*
X1241732Y518157D03*
X1235039D03*
X1278573Y519596D03*
X1248425Y518057D03*
X1168110Y593757D03*
X1171456Y610700D03*
X1168110Y604499D03*
X1161417Y593757D03*
X1164763Y610700D03*
X1161417Y604499D03*
X1181496Y593757D03*
X1184142Y610300D03*
X1181496Y604499D03*
X1208267Y610700D03*
X1204921Y593757D03*
Y604499D03*
X1174803Y593757D03*
X1177763Y610300D03*
X1174803Y604499D03*
X1198228Y593757D03*
X1201574Y610700D03*
X1198228Y604499D03*
X1218307Y593757D03*
Y604499D03*
X1211614Y593757D03*
X1214574Y610300D03*
X1211614Y604499D03*
X1168110Y528899D03*
X1161417D03*
X1181496D03*
X1204921D03*
X1174803D03*
X1198228D03*
X1218307D03*
X1211614D03*
X1171456Y535100D03*
X1164763D03*
X1184142Y534700D03*
X1208267Y535100D03*
X1177763Y534700D03*
X1201574Y535100D03*
X1214574Y534700D03*
X1171456Y572900D03*
X1168110Y555957D03*
Y566699D03*
X1164763Y572900D03*
X1161417Y555957D03*
Y566699D03*
X1184142Y572500D03*
X1181496Y555957D03*
Y566699D03*
X1208267Y572900D03*
X1204921Y555957D03*
Y566699D03*
X1177763Y572500D03*
X1174803Y555957D03*
Y566699D03*
X1201574Y572900D03*
X1198228Y555957D03*
Y566699D03*
X1218307Y555957D03*
Y566699D03*
X1211614Y555957D03*
X1214574Y572500D03*
X1214874Y550574D03*
X1211614Y566699D03*
X1214660Y588714D03*
X1168110Y518157D03*
X1161417D03*
X1181496D03*
X1204921D03*
X1174803D03*
X1198228D03*
X1218307D03*
X1211614D03*
X1214874Y512774D03*
X1097374Y612659D03*
X1110520Y610300D03*
X1107874Y593757D03*
Y604499D03*
X1134645Y610700D03*
X1131299Y593757D03*
Y604499D03*
X1101181Y593757D03*
X1104141Y610300D03*
X1101181Y604499D03*
X1124606Y593757D03*
X1127952Y610700D03*
X1124606Y604499D03*
X1147700Y611200D03*
X1144685Y593757D03*
Y604499D03*
X1137992Y593757D03*
X1141332Y611668D03*
X1137992Y604499D03*
X1107874Y528899D03*
X1131299D03*
X1101181D03*
X1124606D03*
X1144685D03*
X1137992D03*
X1110520Y534700D03*
X1134645Y535100D03*
X1104141Y534700D03*
X1127952Y535100D03*
X1147331Y534700D03*
X1140952D03*
X1107874Y555957D03*
X1110520Y572500D03*
X1107874Y566699D03*
X1131299Y555957D03*
X1134645Y572900D03*
X1131299Y566699D03*
X1101181Y555957D03*
X1104141Y572500D03*
X1101181Y566699D03*
X1124606Y555957D03*
X1127952Y572900D03*
X1124606Y566699D03*
X1147331Y572500D03*
X1144685Y555957D03*
Y566699D03*
X1140952Y572500D03*
X1137992Y555957D03*
Y566699D03*
X1107874Y518157D03*
X1131299D03*
X1101181D03*
X1124606D03*
X1144685D03*
X1137992D03*
X1054330Y604499D03*
X1050984Y612658D03*
X1087795Y609864D03*
X1064369Y607292D03*
X1081102Y604499D03*
X1094488Y604614D03*
Y609864D03*
X1047637Y604499D03*
X1054330Y609864D03*
X1077755Y612657D03*
X1064369D03*
X1071062Y607292D03*
X1057676D03*
X1084448Y612657D03*
X1074409Y604614D03*
X1087795D03*
X1074409Y593642D03*
X1044291Y612658D03*
X1061023Y609864D03*
X1044290Y607292D03*
X1047637Y529007D03*
X1057677D03*
X1044195Y529026D03*
X1044203Y537058D03*
X1081102Y566807D03*
X1047637D03*
X1057677D03*
X1074409D03*
X1044290Y550592D03*
Y588392D03*
Y569492D03*
X1054330Y515364D03*
X1050983Y512792D03*
X1087795Y510114D03*
X1064369Y518157D03*
X1081102Y515364D03*
X1094488D03*
Y510114D03*
X1047637Y515364D03*
X1054330Y509999D03*
X1077755Y512792D03*
X1064369D03*
X1071062Y518157D03*
X1057676D03*
X1084448Y512792D03*
X1074409Y515364D03*
X1087795D03*
X1044290Y512792D03*
X1061023Y510114D03*
X974015Y604499D03*
Y609864D03*
X977362Y612457D03*
X984055D03*
X980708Y604614D03*
X1004134Y607292D03*
X1004133Y612358D03*
X1000787Y604499D03*
X997441Y612357D03*
X994094Y609864D03*
Y604614D03*
X987401Y609864D03*
X990748Y607292D03*
X984055D03*
X1020700Y604600D03*
X1029777Y613581D03*
X1026500Y581000D03*
X974015Y515364D03*
Y509999D03*
X977362Y512792D03*
X984055D03*
X980708Y515364D03*
X1004134Y518157D03*
X1003915Y512792D03*
X1000787Y515364D03*
X997441Y512792D03*
X994094Y510114D03*
Y515364D03*
X987401Y509999D03*
X990748Y518157D03*
X984055D03*
X913779Y593757D03*
Y604499D03*
X970669Y607292D03*
X963976D03*
X960629Y609864D03*
X917125Y610700D03*
X929811Y610300D03*
X927165Y593757D03*
Y604499D03*
X953936Y610700D03*
X950590Y593757D03*
Y604499D03*
X923432Y610300D03*
X920472Y593757D03*
Y604499D03*
X947243Y610700D03*
X943897Y593757D03*
Y604499D03*
X967322Y609864D03*
X913779Y528899D03*
Y555957D03*
Y566699D03*
X927165Y528899D03*
X950590D03*
X920472D03*
X943897D03*
X917125Y535100D03*
X929811Y534700D03*
X953936Y535100D03*
X923432Y534700D03*
X947243Y535100D03*
X917125Y572900D03*
X929811Y572500D03*
X927165Y555957D03*
Y566699D03*
X953936Y572900D03*
X950590Y555957D03*
Y566699D03*
X923432Y572500D03*
X920472Y555957D03*
Y566699D03*
X947243Y572900D03*
X943897Y555957D03*
Y566699D03*
X913779Y518157D03*
X970669D03*
X963976Y518057D03*
X960629Y510114D03*
X927165Y518157D03*
X950590D03*
X920472D03*
X943897D03*
X967322Y510114D03*
X849810Y610300D03*
X853543Y593757D03*
X856189Y610300D03*
X853543Y604499D03*
X876968Y593757D03*
X880314Y610700D03*
X876968Y604499D03*
X870275Y593761D03*
X873621Y610700D03*
X870275Y604499D03*
X893000Y610300D03*
X890354Y593757D03*
Y604499D03*
X886621Y610300D03*
X883661Y593757D03*
Y604499D03*
X907086Y593757D03*
X910432Y610700D03*
X907086Y604499D03*
X849810Y534700D03*
Y572500D03*
X853543Y528899D03*
X876968D03*
X870275D03*
X890354D03*
X883661D03*
X907086D03*
X856189Y534700D03*
X880314Y535100D03*
X873621D03*
X893000Y534700D03*
X886621D03*
X910432Y535100D03*
X853543Y555957D03*
X856189Y572500D03*
X853543Y566699D03*
X876968Y555957D03*
X880314Y572900D03*
X876968Y566699D03*
X870275Y555961D03*
X873621Y572900D03*
X870275Y566699D03*
X893000Y572500D03*
X890354Y555957D03*
Y566699D03*
X886621Y572500D03*
X883661Y555957D03*
Y566699D03*
X910432Y572900D03*
X907086Y555957D03*
Y566699D03*
X853543Y518157D03*
X876968D03*
X870275Y518161D03*
X890354Y518157D03*
X883661D03*
X907086D03*
X840157Y593757D03*
X843503Y610700D03*
X840157Y604499D03*
X812999Y610300D03*
X810039Y593757D03*
Y604499D03*
X833464Y593757D03*
X836810Y610700D03*
X833464Y604499D03*
X846850Y593757D03*
Y604499D03*
X806692Y610700D03*
X803346Y593757D03*
Y604499D03*
X799999Y610700D03*
X796653Y593757D03*
Y604499D03*
X816732Y593757D03*
X819378Y610300D03*
X816732Y604499D03*
X840157Y528899D03*
X810039D03*
X833464D03*
X846850D03*
X803346D03*
X796653D03*
X816732D03*
X843503Y535100D03*
X812999Y534700D03*
X836810Y535100D03*
X806692D03*
X799999D03*
X819378Y534700D03*
X840157Y555957D03*
X843503Y572900D03*
X840157Y566699D03*
X810039Y555957D03*
X812999Y572500D03*
X810039Y566699D03*
X833464Y555957D03*
X836810Y572900D03*
X833464Y566699D03*
X846850Y555957D03*
Y566699D03*
X803346Y555957D03*
X806692Y572900D03*
X803346Y566699D03*
X796653Y555957D03*
X799999Y572900D03*
X796653Y566699D03*
X816732Y555957D03*
X819378Y572500D03*
X816732Y566699D03*
X840157Y518157D03*
X810039D03*
X833464D03*
X846850D03*
X803346D03*
X796653D03*
X816732D03*
X782567Y610300D03*
X779921Y593757D03*
Y604499D03*
X776188Y610300D03*
X773228Y593757D03*
Y604499D03*
X779921Y528899D03*
X773228D03*
X782567Y534700D03*
X776188D03*
X779921Y555957D03*
X782567Y572500D03*
X779921Y566699D03*
X773228Y555957D03*
X776188Y572500D03*
X773228Y566699D03*
X764117Y575658D03*
X765100Y537110D03*
X766535Y555700D03*
X779921Y518157D03*
X773228D03*
X766535Y517900D03*
X717612Y598554D03*
X718200Y581000D03*
X913787Y273460D03*
X917467Y271509D03*
X971546Y252009D03*
X944507Y267609D03*
X947887Y269560D03*
X951267Y271509D03*
X947887Y273460D03*
X941127D03*
X927607D03*
X974926Y277360D03*
X971546Y279310D03*
X944507Y271509D03*
X924227D03*
X1005345Y252009D03*
X998586D03*
X1008725Y253960D03*
X1001965D03*
X1005345Y255909D03*
X998586D03*
X1001965Y257860D03*
X995206D03*
X998586Y259809D03*
X995206Y261760D03*
X988446Y269560D03*
X985066Y271509D03*
X978306D03*
X988446Y273460D03*
X981686D03*
X985066Y275409D03*
X978306D03*
X988446Y277360D03*
X981686D03*
X985066Y279310D03*
X978306D03*
X1012105Y252009D03*
X1044256Y338341D03*
X1076435Y343595D03*
X837272Y391420D03*
X840871Y391380D03*
X944507Y330009D03*
Y326110D03*
X1006665Y324160D03*
X1010975Y329560D03*
X1014355Y331509D03*
X1017735Y333460D03*
X1021115Y335409D03*
X1007595Y327609D03*
X1001965Y331960D03*
X1005345Y333909D03*
X1008725Y335860D03*
X998586Y330009D03*
Y326110D03*
Y322209D03*
X1161200Y288347D03*
Y292247D03*
X1164580Y282496D03*
X1171339D03*
X1198379D03*
X1167960Y284447D03*
X1161200Y300047D03*
Y276646D03*
Y280547D03*
X1167960Y222047D03*
X1164580Y220096D03*
X1161200Y222047D03*
Y268847D03*
X1164580Y255196D03*
X1171339Y270796D03*
X1167960Y280547D03*
X1164580Y274696D03*
X1167960Y257147D03*
X1161200Y272747D03*
X1191619Y223996D03*
X1178099D03*
X1167960Y233746D03*
X1178099Y270796D03*
Y278596D03*
X1181479Y249347D03*
Y237647D03*
Y241547D03*
X1184859Y223996D03*
X1201759Y237647D03*
X1198379Y227896D03*
X1205139Y231797D03*
X1201759Y245447D03*
X1194999Y237647D03*
X1198379Y251296D03*
X1181479Y264947D03*
X1184859Y255196D03*
X1191619Y270796D03*
X1198379Y262996D03*
X1194999Y276646D03*
X1198379Y270796D03*
X1178099Y266896D03*
X1171339Y243496D03*
X1174719Y241547D03*
X1178099Y239596D03*
X1171339Y278596D03*
X1178099Y262996D03*
X1174719Y276646D03*
X1167960D03*
X1181479Y253247D03*
X1178099Y251296D03*
X1171339Y262996D03*
X1174719Y264947D03*
X1208519Y229847D03*
Y218147D03*
X1171339Y216196D03*
X1181479Y218147D03*
X1191619Y208397D03*
X1178099Y204496D03*
X1127400Y346847D03*
X1130780Y348796D03*
X1127400Y350747D03*
X1137540Y356596D03*
X1157820Y282496D03*
X1144300D03*
X1119521D03*
X1130780D03*
X1137540Y313696D03*
X1140920Y315647D03*
X1134160Y319547D03*
X1130780Y317596D03*
Y333196D03*
X1134160Y331247D03*
X1140920Y288347D03*
Y284447D03*
X1147680D03*
Y288347D03*
X1151060Y286396D03*
X1144300Y290296D03*
X1147680Y292247D03*
X1154440D03*
Y288347D03*
Y284447D03*
X1157820Y286396D03*
X1137540D03*
X1119521Y301996D03*
Y298096D03*
Y294196D03*
Y290296D03*
X1127400Y284447D03*
Y300047D03*
X1130780Y294196D03*
X1127400Y296147D03*
Y292247D03*
X1130780Y298096D03*
Y305896D03*
X1137540Y290296D03*
X1134160Y296147D03*
Y288347D03*
Y284447D03*
X1130780Y286396D03*
X1134160Y311747D03*
Y315647D03*
X1140920Y323446D03*
X1147680Y307847D03*
X1151060Y309797D03*
X1144300Y298096D03*
X1137540Y301996D03*
X1140920Y303947D03*
X1137540Y305896D03*
X1140920Y296147D03*
X1137540Y294196D03*
X1119521Y309797D03*
Y313696D03*
Y317596D03*
X1127400Y311747D03*
X1154440D03*
Y303947D03*
X1157820Y301996D03*
X1154440Y300047D03*
X1144300Y317596D03*
X1137540Y321496D03*
X1134160Y327347D03*
X1137540Y325396D03*
X1098111Y263400D03*
X1134160Y272747D03*
Y276646D03*
X1151060Y270796D03*
Y255196D03*
Y251296D03*
X1154440Y280547D03*
X1140920D03*
X1136420Y261047D03*
X1133040Y262996D03*
X1147680Y280547D03*
X1157820Y274696D03*
X1154440Y268847D03*
X1140920Y272747D03*
X1114340Y280560D03*
X1154440Y276647D03*
X1101491Y265400D03*
X1116141Y268847D03*
X1112761Y262996D03*
X1116141Y261047D03*
X1119521Y278596D03*
X1144300Y223996D03*
X1154440Y225947D03*
X1147680Y245447D03*
X1127400Y280547D03*
Y276646D03*
X1134160Y280547D03*
X1144300Y266896D03*
X1154440Y257147D03*
X1157820Y251296D03*
X1154440Y249347D03*
X1157820Y247396D03*
X1147680Y249347D03*
Y276647D03*
X1140920D03*
X1154440Y272747D03*
X1147680Y253247D03*
Y257147D03*
X1109381Y264947D03*
X1119521Y266896D03*
Y262996D03*
X1122900Y261047D03*
X1119521Y259096D03*
X1157820Y243496D03*
X1147680Y272747D03*
X1151060Y278596D03*
X1133040Y239596D03*
X1147680Y261047D03*
X1144300Y259096D03*
X1151060Y262996D03*
X1154440Y261047D03*
X1144300Y274696D03*
X1129660Y210346D03*
X1133040Y212296D03*
X1065242Y239596D03*
Y243496D03*
X1068822Y245447D03*
X1067692Y254000D03*
X1071072Y255728D03*
X1087971Y257800D03*
X1091351Y259600D03*
X1094731Y261500D03*
X1084591Y255497D03*
X1081212Y257600D03*
X1092481Y247396D03*
X1089101Y245447D03*
X1085721Y247396D03*
X1089101Y249347D03*
X1092481Y251296D03*
X1095861Y249347D03*
Y253247D03*
X1072202Y247396D03*
X1249230Y402022D03*
X1167960Y405347D03*
X1174719D03*
X1161200Y362447D03*
Y358547D03*
Y366347D03*
Y354647D03*
Y389747D03*
X1161201Y401447D03*
X1201759Y342947D03*
X1198379Y344896D03*
X1184859D03*
X1191619D03*
X1188239Y342947D03*
X1201759Y346847D03*
X1164580Y368296D03*
X1167960Y350747D03*
Y354647D03*
X1164580Y360496D03*
Y364396D03*
X1167960Y346847D03*
X1171339Y352696D03*
X1184859Y348796D03*
X1188239Y346847D03*
X1178099Y387796D03*
X1171339D03*
Y391696D03*
X1167960Y393647D03*
X1164580Y395597D03*
X1178099Y379996D03*
Y383896D03*
X1174719Y385847D03*
X1171339Y383896D03*
X1174719Y389747D03*
X1171339Y395596D03*
X1164580Y391696D03*
Y387796D03*
X1178099Y376096D03*
X1181479Y381947D03*
X1188239Y354647D03*
Y358547D03*
Y362447D03*
X1181479D03*
Y366347D03*
X1184859Y372197D03*
Y376096D03*
Y379996D03*
X1188239Y350747D03*
X1191619Y356596D03*
X1184859Y360496D03*
X1181479Y358547D03*
X1184859Y364396D03*
Y368296D03*
X1188239Y374146D03*
X1181479Y378047D03*
X1174719Y370247D03*
X1181479D03*
X1171339Y364396D03*
X1178099Y360496D03*
Y356596D03*
X1184859Y352696D03*
X1161200Y393647D03*
Y385847D03*
X1167960D03*
Y381947D03*
Y378047D03*
X1174719D03*
Y374146D03*
Y366347D03*
X1178099Y368296D03*
X1174719Y362447D03*
Y358547D03*
X1181479Y354647D03*
Y350747D03*
X1161200Y381947D03*
X1164580Y383896D03*
X1171339Y379996D03*
X1167960Y374146D03*
X1171339Y376096D03*
X1178099Y372197D03*
X1194999Y378047D03*
X1201759Y374146D03*
X1194999D03*
X1198379Y364396D03*
Y360496D03*
Y356596D03*
X1174719Y401447D03*
X1178099Y395596D03*
X1184859Y399496D03*
X1181479Y393647D03*
X1188239Y389747D03*
Y385847D03*
X1191619Y379996D03*
X1198379Y383896D03*
X1167960Y401447D03*
X1198379Y376096D03*
Y372197D03*
X1194999Y370247D03*
Y362447D03*
X1201759Y358547D03*
X1198379Y352696D03*
X1171339Y403396D03*
X1178099Y399496D03*
X1181479Y397546D03*
X1184859Y395596D03*
Y391696D03*
Y387796D03*
X1191619Y383896D03*
X1194999Y381947D03*
X1198379Y379996D03*
X1164580Y376096D03*
X1194999Y350747D03*
X1198379Y348796D03*
X1201759Y331247D03*
Y335147D03*
X1198379Y333196D03*
X1201759Y339047D03*
X1205139Y340996D03*
X1181479Y331247D03*
X1198379Y321496D03*
X1194999Y323446D03*
X1174719D03*
X1181479D03*
X1174719Y327347D03*
X1178099Y333196D03*
X1171339Y329296D03*
X1167960Y335147D03*
X1171339Y340996D03*
X1178099Y321496D03*
Y325396D03*
Y329296D03*
X1174719Y331247D03*
X1171339Y333196D03*
Y337096D03*
X1191619Y340996D03*
Y337096D03*
X1188239Y331247D03*
X1194999Y327347D03*
X1188239D03*
X1184859Y340996D03*
X1194999Y339047D03*
X1191619Y333196D03*
Y329296D03*
Y325396D03*
X1188239Y323446D03*
X1113881Y342947D03*
X1120641D03*
X1110501Y344896D03*
X1157820Y364396D03*
X1154440Y370246D03*
X1157820Y376096D03*
X1151060Y372196D03*
X1147680Y378047D03*
X1144300Y379996D03*
Y387796D03*
X1157820Y368296D03*
Y372196D03*
X1154440Y374146D03*
X1151060Y376096D03*
X1147680Y381947D03*
X1144300Y383896D03*
X1107121Y350747D03*
X1113881Y346847D03*
X1147680Y370247D03*
Y374146D03*
X1120641Y346847D03*
X1154440Y397546D03*
Y393647D03*
X1151060Y387796D03*
X1157820Y395597D03*
X1154440Y389747D03*
X1157820Y391696D03*
X1154440Y385847D03*
X1157820Y383896D03*
X1156699Y401447D03*
X1120641Y339047D03*
X1109200Y325100D03*
X1395100Y432500D03*
Y427500D03*
X1370200Y343900D03*
X1358300Y344200D03*
X1370300Y350200D03*
X1364100D03*
X1358400Y350100D03*
X1374300Y377885D03*
Y381485D03*
X1378200Y346900D03*
X1364300Y338300D03*
X1370200Y338400D03*
X1358500D03*
X1335250Y344250D03*
X1342570Y368220D03*
X1302768Y296942D03*
X1331720Y334810D03*
X1326300Y341309D03*
X1316600Y305500D03*
X1302203Y314439D03*
X1198379Y294196D03*
X1191619Y313696D03*
Y309797D03*
X1188239Y307847D03*
Y303947D03*
Y300047D03*
X1184859Y298096D03*
X1194999Y311747D03*
X1191619Y305896D03*
X1184859D03*
X1191619Y301996D03*
X1188239Y296147D03*
X1181479D03*
X1184859Y313696D03*
X1965400Y619500D03*
X1968375Y509375D03*
X1961771Y591744D03*
X1963300Y612800D03*
X1963000Y573000D03*
X1961715Y555639D03*
X1962950Y566600D03*
X1962500Y578500D03*
X1964890Y534940D03*
X1964270Y511410D03*
X1932390Y590100D03*
X1959400Y601100D03*
X1911750Y592800D03*
X1914700Y594600D03*
X1938130Y601480D03*
X1937870Y594480D03*
X1921244Y533750D03*
X1951900Y534900D03*
X1934200Y573700D03*
Y577700D03*
X1935400Y583000D03*
X1945900Y549900D03*
X1923500Y579500D03*
X1948100Y538700D03*
X1923400Y583000D03*
X1926600Y559500D03*
X1923600Y565100D03*
X1923000Y568700D03*
X1958940Y538890D03*
X1914750Y544863D03*
X1958500Y535000D03*
X1907500Y545600D03*
X1907200Y551600D03*
X1900890Y477200D03*
X1919510Y475100D03*
Y479200D03*
X1956606Y526671D03*
X1957212Y479521D03*
X1957063Y474769D03*
X1928620Y482710D03*
X1956300Y515900D03*
X1959300Y518000D03*
X1908300Y514500D03*
X1942328Y508712D03*
X1937430Y464785D03*
X1939845Y445055D03*
X1848900Y590750D03*
X1845000Y590800D03*
X1896358Y595255D03*
X1837475Y573835D03*
X1842764Y528136D03*
X1870100Y561150D03*
X1844018Y586482D03*
X1840690Y557190D03*
X1895523Y586365D03*
X1869800Y557100D03*
X1878875Y565475D03*
X1847070Y537610D03*
X1882300Y565550D03*
X1856040Y588704D03*
X1875600Y588500D03*
X1840700Y563800D03*
X1854530Y533132D03*
X1837300Y472276D03*
X1868167Y467855D03*
X1859530Y516430D03*
X1842400Y516800D03*
X1841900Y498800D03*
X1863000Y480000D03*
X1859600Y476200D03*
X1876945Y471316D03*
X1847000Y487500D03*
X1860000Y495500D03*
X1808152Y591601D03*
X1812852D03*
X1778675Y592224D03*
X1812852Y596401D03*
X1808252D03*
X1794500Y612500D03*
X1791500Y606500D03*
X1788290Y612006D03*
X1784200Y593924D03*
X1831600Y529000D03*
X1812452Y538501D03*
Y533601D03*
X1807852D03*
X1807752Y538501D03*
X1781300Y537800D03*
X1816020Y571448D03*
X1812802Y578693D03*
X1816330Y545260D03*
X1816100Y576200D03*
X1829176Y584287D03*
X1831500Y544500D03*
X1835000Y550300D03*
X1782300Y555900D03*
X1776695Y512640D03*
X1814852Y519901D03*
X1833700Y497300D03*
X1727743Y592342D03*
X1732443D03*
X1727843Y597142D03*
X1732443D03*
X1770600Y600800D03*
X1764912Y618718D03*
X1730759Y548162D03*
X1722500Y562000D03*
X1754897Y578750D03*
X1767500Y559800D03*
X1765300Y574700D03*
X1713600Y513000D03*
X1714530Y519900D03*
X1716490Y506970D03*
X1719560Y501770D03*
X1709950Y592900D03*
X1701291Y602268D03*
X1680133Y535489D03*
X1710389Y577787D03*
X1699600Y578100D03*
X1709400Y513000D03*
X1710594Y519900D03*
X1676800Y483800D03*
X1681650Y510673D03*
X1687606Y500938D03*
X1681500Y482000D03*
X1655790Y476593D03*
X1705767Y482434D03*
X1701617Y482706D03*
X1622330Y592325D03*
X1639271Y491135D03*
X1639391Y513065D03*
X1649336Y511502D03*
X1649545Y515215D03*
X1612825Y405438D03*
X1630750Y404800D03*
X1595800Y405900D03*
X1630120Y418887D03*
X1630386Y413942D03*
X1639822Y453140D03*
X1647200Y430450D03*
X1611935Y429515D03*
X1617900Y409900D03*
X1590154Y354762D03*
X1632503Y343146D03*
X1642443Y344879D03*
X1629503Y346146D03*
X1635503Y346046D03*
X1602215Y363981D03*
X1621727Y395374D03*
X1629300Y385400D03*
X1638991Y352037D03*
X1621800Y381500D03*
Y386300D03*
X1590212Y315425D03*
X1590176Y331844D03*
X1635503Y340146D03*
X1629503D03*
X1638086Y319664D03*
X1625400Y327667D03*
X1602776Y331304D03*
X1620159Y332004D03*
X1638063Y326504D03*
X1635355Y324228D03*
X1639040Y316343D03*
X1625846Y286154D03*
X1609172Y339630D03*
X1636800Y287956D03*
X1610290Y265352D03*
X1581704Y590196D03*
X1589604D03*
X1558800Y599300D03*
X1560400Y611600D03*
X1564300Y599400D03*
X1564400Y605500D03*
X1561700Y602200D03*
X1556200Y602400D03*
X1554400Y599300D03*
X1564300Y611500D03*
X1586700Y620100D03*
X1540477Y620308D03*
X1545407Y598393D03*
X1579680Y610279D03*
X1534968Y597268D03*
X1573500Y619500D03*
X1577000D03*
X1589604Y585896D03*
X1581704D03*
X1550990Y586588D03*
X1554358Y587258D03*
X1587610Y579550D03*
X1560500Y350000D03*
X1557534Y353400D03*
X1532367Y356530D03*
X1550639Y350200D03*
X1587684Y362653D03*
X1552500Y358500D03*
X1586500Y354900D03*
X1550417Y362607D03*
X1566922Y359681D03*
X1529734Y319714D03*
X1530500Y287700D03*
X1584568Y281339D03*
X1551404Y309376D03*
X1533228Y325000D03*
X1550619Y303087D03*
X1534400Y296029D03*
X1538450Y314300D03*
X1577486Y307621D03*
X1573950Y338050D03*
X1581834Y318591D03*
X1559800Y285300D03*
X1559500Y290300D03*
X1588551Y341410D03*
X1581940Y295820D03*
X1582800Y312100D03*
X1548273Y313227D03*
X1565000Y290500D03*
X1551250Y320303D03*
X1554775Y295328D03*
X1548100Y342200D03*
X1560024Y329200D03*
X1534833Y309798D03*
X1547000Y263500D03*
Y269400D03*
X1541000Y263500D03*
Y269500D03*
X1544000Y266500D03*
X1532237Y247801D03*
X1563157Y258164D03*
X1541325Y245090D03*
X1558700Y252000D03*
X1568365Y247761D03*
X1523450Y612900D03*
X1519850Y613000D03*
X1487912Y611632D03*
X1484312Y611732D03*
X1514265Y355542D03*
X1517367Y349964D03*
X1511000Y350627D03*
X1502970Y350610D03*
X1478163Y354940D03*
X1526936Y307015D03*
X1501550Y293750D03*
X1518006Y286706D03*
X1510851Y340113D03*
X1504370Y330970D03*
X1470276Y330774D03*
X1496900Y293900D03*
X1492540Y328250D03*
X1470257Y321929D03*
X1483506Y326061D03*
X1521962Y278650D03*
X1470556Y256900D03*
X1527657Y278700D03*
X1504772Y259229D03*
X1496812Y273718D03*
X1409500Y538000D03*
X1420500Y549800D03*
X1420400Y538000D03*
X1429026Y541026D03*
X1428281Y546119D03*
X1432560Y561160D03*
X1436160Y561200D03*
X1428791Y535512D03*
X1423800Y534800D03*
X1425243Y562260D03*
X1463870Y367869D03*
X1457300Y373600D03*
X1464400Y390800D03*
X1450400Y354300D03*
X1460400Y353000D03*
X1459111Y356353D03*
X1444311Y324366D03*
X1433362Y278244D03*
X1394370Y384230D03*
X1394260Y351170D03*
X1345700Y285300D03*
X1365246Y285931D03*
X1363700Y321600D03*
X1367200D03*
X1353672Y299605D03*
X1347892Y299741D03*
X1381431Y284259D03*
X1345050Y272350D03*
X1338700Y284700D03*
X1319310Y300795D03*
X1319888Y290205D03*
X1323688D03*
X1300444Y267919D03*
X1309462Y240229D03*
X1288800Y233900D03*
X1457000Y82000D03*
X1972598Y165236D03*
X1967580Y104721D03*
X1963300Y191000D03*
X1918143Y219848D03*
X1903150Y217250D03*
X1957334Y201269D03*
X1939300Y204300D03*
X1917024Y193600D03*
X1929700Y163400D03*
X1921500Y193600D03*
X1903917Y201472D03*
X1925000Y192000D03*
X1918489Y212513D03*
X1943500Y209500D03*
X1930500Y209464D03*
X1927064Y207564D03*
X1938400Y178200D03*
X1939200Y194300D03*
X1935600Y198700D03*
X1950981Y191218D03*
X1940700Y136300D03*
X1923800Y151000D03*
X1927000Y152200D03*
X1947000Y142600D03*
X1920300Y68300D03*
X1917600Y66000D03*
X1900256Y-14760D03*
X1892274Y235080D03*
X1893238Y208042D03*
X1891880Y204370D03*
X1843107Y97988D03*
X1848208Y49427D03*
X1838850Y13160D03*
X1882999Y7383D03*
X1883041Y15814D03*
X1876792Y18461D03*
X1785500Y164000D03*
X1776828Y155211D03*
X1810100Y114700D03*
X1803509Y128500D03*
X1807818Y124179D03*
X1815026Y121478D03*
X1788000Y129000D03*
X1808313Y111705D03*
X1807509Y128500D03*
X1814900Y116900D03*
X1809810Y155858D03*
X1800792Y122691D03*
X1824990Y103620D03*
X1807166Y147401D03*
X1800420Y148240D03*
X1813913Y2287D03*
X1790078Y11860D03*
X1795078Y11900D03*
X1828874Y-13520D03*
X1815150Y26650D03*
X1791500Y26918D03*
X1808100Y21800D03*
X1786865Y22375D03*
X1823600Y8800D03*
X1797700Y21018D03*
X1836700Y-18900D03*
X1804800Y-1500D03*
X1816723Y9781D03*
X1765015Y119100D03*
X1768886Y156173D03*
X1767250Y94500D03*
Y89500D03*
X1766333Y59116D03*
X1775000Y53500D03*
X1757772Y90174D03*
X1749085Y9177D03*
X1744900Y9100D03*
X1755500Y9076D03*
X1689785Y161180D03*
X1688207Y168972D03*
X1696907Y99077D03*
X1681586Y141438D03*
X1693586Y142438D03*
X1697300Y73296D03*
X1689250Y86000D03*
X1692300Y56900D03*
X1708610Y85121D03*
X1669000Y92000D03*
X1679900Y74500D03*
X1704824Y90049D03*
X1591800Y164900D03*
X1630826Y88087D03*
X1614997Y84403D03*
X1625075Y80182D03*
X1599500Y75000D03*
X1643500Y80400D03*
X1635337Y73500D03*
X1627489Y74960D03*
X1620900Y81300D03*
X1590431Y-6702D03*
X1617500Y-14500D03*
X1598602Y3437D03*
X1605500Y-3600D03*
X1588500Y106788D03*
X1549600Y-10800D03*
X1540000Y3400D03*
X1545111Y24172D03*
X1580398Y-600D03*
Y5400D03*
X1571500Y-1406D03*
X1477100Y2400D03*
X1501900Y-9124D03*
X1506300Y-6600D03*
X1521092Y21665D03*
X1520700Y7100D03*
X1513700Y7082D03*
X1541765Y114000D03*
X1542685Y133321D03*
X1531726Y123800D03*
X1542000Y126246D03*
X1541520Y79387D03*
X1494939Y159500D03*
X1497493Y162078D03*
X1493200Y162700D03*
X1505673Y146346D03*
X1476761Y157400D03*
X1518376Y111499D03*
X1518438Y100926D03*
X1510184Y142614D03*
X1503466Y142486D03*
X1520150Y127600D03*
X1475200Y142600D03*
X1500643Y154819D03*
X1496726Y120588D03*
X1500806Y133339D03*
X1518514Y130991D03*
X1482455Y124222D03*
X1490674Y98787D03*
X1488800Y145000D03*
X1524744Y133656D03*
X1519599Y86117D03*
X1524557Y88336D03*
X1746900Y249804D03*
X1751900Y249700D03*
G54D55*
X1694000Y595039D03*
X1646756D03*
G54D48*
X44050Y504383D03*
G54D54*
X1694000Y610000D03*
Y565118D03*
Y580079D03*
X1646756Y610000D03*
Y565118D03*
Y580079D03*
G54D34*
X19800Y257900D03*
X5120Y276058D03*
X2269Y273532D03*
X64778Y218062D03*
X58000Y206500D03*
X56900Y197800D03*
X50500Y205696D03*
X61256Y186000D03*
X108174Y164127D03*
X85609Y385234D03*
X628589Y463649D03*
X634033Y467638D03*
X641107Y471989D03*
X605176Y487581D03*
X632771Y473269D03*
X629359Y469583D03*
X1301240Y476228D03*
X1431664Y190213D03*
X1567425Y144373D03*
X1573121Y120649D03*
X1561925Y192675D03*
X1566858Y175192D03*
X1591865Y237407D03*
X1713000Y185000D03*
X1663566Y213009D03*
X1687741Y466988D03*
X1852654Y164624D03*
X1847654D03*
X1925358Y140685D03*
X251213Y646784D03*
Y652784D03*
X261125Y646784D03*
Y652784D03*
X389473Y646508D03*
Y652508D03*
X379561Y646508D03*
Y652508D03*
X448593Y652514D03*
Y646514D03*
X438681D03*
Y652514D03*
X567029Y652238D03*
Y646238D03*
X576941D03*
Y652238D03*
X951795Y652234D03*
Y646234D03*
X941883D03*
Y652234D03*
X1196198Y652206D03*
Y646206D03*
X1206110D03*
Y652206D03*
X1265293Y652264D03*
Y646264D03*
X1255381D03*
Y652264D03*
X1509696Y652236D03*
Y646236D03*
X1519608D03*
Y652236D03*
X114084Y399937D03*
X98149Y399769D03*
X102456Y393756D03*
X267859Y271509D03*
X264179Y273460D03*
X298279Y320260D03*
Y324160D03*
X814849Y205001D03*
X773419Y270414D03*
X753098Y338316D03*
X744698Y332816D03*
X757500Y374000D03*
X1032102Y278904D03*
X1089702D03*
X1919230Y483430D03*
X1919000Y487210D03*
X1836396Y481349D03*
X1644856Y604930D03*
X1640921Y605334D03*
X1598028Y256422D03*
X1600552Y261281D03*
X1569926Y308064D03*
X1944550Y176450D03*
X1950981Y168064D03*
X1949389Y152083D03*
X1777000Y115750D03*
X1778000Y120000D03*
X1780720Y153850D03*
X1784750Y124000D03*
X1790100Y154000D03*
X1759093Y9310D03*
X1761872Y-7220D03*
X1734875Y9238D03*
X1695734Y164676D03*
X1680139Y99073D03*
X1709184Y88811D03*
X1502000Y147500D03*
X1758000Y250000D03*
G54D44*
X1379025Y-9799D03*
X710900Y231660D03*
X700000Y233700D03*
X1858600Y74300D03*
G54D39*
X63093Y202300D03*
X72936D03*
X82779D03*
X1912406Y518328D03*
X1904532D03*
X1914911Y495775D03*
X1934597D03*
X1924754D03*
G54D36*
X10512Y467244D03*
X20512D03*
X50512D03*
X60512D03*
X1904100Y493000D03*
X1891086Y592105D03*
Y612105D03*
Y602105D03*
X1884100Y493000D03*
X1894100D03*
G54D64*
X1720164Y97550D03*
X1723314Y98550D03*
X1717014Y97550D03*
X1742212Y117451D03*
X1717014Y108000D03*
Y139500D03*
X1739064Y114300D03*
X1742214Y111150D03*
X1745364Y120600D03*
X1742214Y126900D03*
X1751800Y141700D03*
X1720164Y126800D03*
Y133200D03*
Y120600D03*
X1723314Y117450D03*
Y111150D03*
X1720164D03*
X1731903Y133712D03*
X1745364Y145800D03*
X1752889Y146250D03*
X1757689Y123850D03*
X1754189Y124250D03*
X1752389Y132250D03*
X1752189Y136750D03*
X1755089Y150750D03*
X1742214Y101700D03*
X1739064Y108000D03*
X1735914Y139500D03*
X1723314Y142650D03*
X1735989Y133250D03*
X1739064Y145800D03*
X1728789Y136250D03*
X1723264Y145850D03*
X1735989Y149050D03*
X1726539Y139450D03*
X1734989Y142750D03*
X1720164Y139500D03*
X1739064Y142650D03*
X1720164Y145800D03*
X1742214D03*
X1726464D03*
X1739064Y139500D03*
X1723314D03*
X1739064Y136350D03*
Y126900D03*
X1723314Y130050D03*
Y126900D03*
X1726464Y133200D03*
Y111150D03*
X1739064Y120600D03*
X1735914Y104850D03*
X1723314D03*
X1720164Y108000D03*
X1735914D03*
X1723314D03*
X1739064Y123750D03*
X1726464Y120600D03*
X1742214D03*
X1723314Y120601D03*
X1735912Y123750D03*
X1720164Y104850D03*
X1739064Y117450D03*
X1735914D03*
X1731789Y139450D03*
X1717014Y142650D03*
X1739064Y130050D03*
X1746189Y153250D03*
X1723314Y133200D03*
X1742214Y142650D03*
X1746189Y134777D03*
X1742214Y130050D03*
X1745363Y108004D03*
X1735914Y101700D03*
X1742214Y114300D03*
Y123750D03*
X1745364D03*
X1723314D03*
X1720164D03*
Y117451D03*
X1726464Y117450D03*
X1745364Y142650D03*
X1746189Y131624D03*
X1745364Y117450D03*
X1717014Y133200D03*
Y111150D03*
Y104850D03*
X1745500Y104500D03*
X1654638Y159685D03*
X1654685Y162735D03*
X1660985Y159585D03*
X1657835D03*
X1668213Y172608D03*
X1657835Y165884D03*
Y162735D03*
X1665063Y172608D03*
X1660985Y165885D03*
Y162735D03*
X1654678Y137530D03*
X1654685Y146987D03*
X1654686Y109191D03*
X1654673Y118628D03*
X1654685Y112341D03*
X1653111Y102240D03*
X1654685Y143837D03*
X1654686Y150138D03*
X1654685Y140687D03*
X1654686Y124940D03*
Y134389D03*
X1654685Y131239D03*
X1654686Y153288D03*
Y156436D03*
X1674685Y134217D03*
X1678127Y117293D03*
X1673883Y124308D03*
X1680402Y128652D03*
X1657835Y134389D03*
X1664134Y140688D03*
X1667284Y150136D03*
Y128089D03*
Y121790D03*
X1657835Y150136D03*
Y124940D03*
X1667284Y137537D03*
X1691207Y139891D03*
X1709000Y127200D03*
X1671000Y103000D03*
X1657835Y115491D03*
Y109191D03*
X1660985D03*
X1670434Y115491D03*
X1667284D03*
X1660985D03*
X1664135Y118640D03*
X1657835Y112341D03*
X1660985D03*
X1667238Y112387D03*
X1660985Y156435D03*
X1660986Y137538D03*
X1657835Y143837D03*
X1664186Y147038D03*
X1657835Y146987D03*
X1660985Y150137D03*
X1657836Y153288D03*
X1664135Y153286D03*
X1660985Y143837D03*
X1664136Y137538D03*
X1664135Y121790D03*
X1660985Y128089D03*
Y121790D03*
X1657835D03*
X1667284Y131239D03*
X1664135Y128089D03*
X1660985Y131239D03*
Y124939D03*
X1677386Y132788D03*
Y129638D03*
X1676886Y120038D03*
Y123188D03*
X1660985Y146987D03*
X1657836Y137538D03*
Y140688D03*
X1660985D03*
X1664134Y156436D03*
X1667348Y156500D03*
X1664135Y112341D03*
Y115491D03*
X1660985Y118640D03*
X1657835D03*
X1607442Y159585D03*
X1648387D03*
X1651536D03*
X1610591D03*
X1596427Y157975D03*
X1600490Y158010D03*
X1651536Y156435D03*
X1638938Y159585D03*
X1613741D03*
X1629489D03*
X1635788D03*
X1642087D03*
X1620040D03*
X1645237D03*
X1626339D03*
X1623189D03*
X1616890D03*
X1627998Y172854D03*
X1620040Y162735D03*
X1613741D03*
X1607441D03*
X1645237Y165884D03*
X1626339Y162735D03*
X1623276Y165798D03*
X1629489Y162735D03*
Y165884D03*
X1645151Y162649D03*
X1642101Y162749D03*
X1610591Y162735D03*
X1651536Y165884D03*
X1638938Y162735D03*
X1635788Y165885D03*
X1642088D03*
X1638938Y165884D03*
X1616890Y162735D03*
X1651536D03*
X1648320Y172690D03*
X1648326Y162674D03*
X1648386Y165885D03*
X1623250Y162611D03*
X1626339Y165884D03*
X1635788Y162735D03*
X1643662Y172609D03*
X1638250Y125750D03*
X1651536Y121790D03*
X1638938Y118641D03*
X1645378Y128378D03*
X1638938Y153286D03*
X1616900Y153200D03*
X1616891Y146987D03*
X1616893Y140782D03*
X1616891Y134389D03*
X1623189Y118640D03*
X1616891Y124939D03*
X1602717Y102240D03*
X1613741Y115491D03*
X1607441Y118640D03*
X1629489D03*
X1620040Y106042D03*
X1629489Y131239D03*
Y143837D03*
Y137538D03*
X1635788Y143837D03*
Y137538D03*
X1629489Y150136D03*
X1638937Y137538D03*
Y143837D03*
Y131239D03*
X1648430Y150163D03*
X1638938Y109192D03*
X1616891Y150137D03*
X1613741Y146987D03*
X1632574Y106107D03*
X1620100Y153300D03*
X1613741Y121790D03*
X1610591D03*
X1629489Y115491D03*
X1632615Y109215D03*
X1632638Y112341D03*
Y115491D03*
X1616890Y112341D03*
X1616848Y115449D03*
X1613741Y153286D03*
X1648387Y115491D03*
X1651536D03*
X1610591Y112341D03*
X1607441Y115491D03*
X1610591Y118640D03*
X1607441Y112341D03*
X1616891Y128089D03*
X1613741Y118640D03*
X1610645Y143783D03*
X1600148Y142262D03*
X1604292Y150137D03*
X1607401Y146947D03*
X1600182Y148562D03*
X1600148Y151711D03*
X1610591Y156436D03*
X1604169Y156407D03*
X1610591Y153286D03*
X1607441Y156436D03*
X1613741Y106042D03*
X1616890Y118641D03*
X1616900Y143880D03*
X1645237Y115491D03*
X1607441Y134389D03*
X1610591Y140688D03*
Y137538D03*
Y124939D03*
Y150137D03*
X1613741Y137538D03*
X1607441Y153286D03*
X1600900Y131900D03*
X1595390Y151778D03*
X1610591Y134389D03*
X1613741Y140688D03*
X1613690Y124990D03*
X1613741Y134389D03*
X1608000Y99400D03*
X1607441Y143837D03*
X1610591Y146987D03*
X1645237Y112341D03*
X1607441Y106042D03*
X1613741Y150137D03*
Y156436D03*
X1626339Y115491D03*
X1613741Y128089D03*
X1626339Y118651D03*
Y109191D03*
X1626300Y112300D03*
X1651536Y112341D03*
X1623200Y153100D03*
X1607441Y124939D03*
X1651536Y146988D03*
Y128089D03*
X1642087Y143837D03*
X1623190Y124940D03*
Y128089D03*
Y134388D03*
Y140687D03*
Y146987D03*
X1635788Y153286D03*
X1626339Y150136D03*
X1637363Y149484D03*
X1645237Y124940D03*
X1642087D03*
X1651536Y134388D03*
Y131239D03*
Y124939D03*
Y140687D03*
Y143837D03*
X1626364Y121765D03*
X1635788Y118640D03*
X1632639D03*
X1642150Y118660D03*
X1645237Y118640D03*
X1626313Y153312D03*
X1642087Y153286D03*
X1632638D03*
X1620100Y150200D03*
X1620040Y146987D03*
Y140687D03*
X1632639Y124940D03*
X1648393Y153280D03*
X1651532Y137534D03*
X1626339Y124940D03*
X1607441Y121790D03*
X1604292Y137538D03*
X1607239Y131358D03*
X1629400Y106131D03*
X1629487Y109280D03*
X1642084Y115494D03*
X1629489Y112341D03*
X1648387D03*
Y109191D03*
X1651536D03*
X1607441Y137538D03*
X1604292Y134388D03*
X1610591Y128089D03*
Y115491D03*
X1648386Y156435D03*
X1645237Y109191D03*
X1594565Y148720D03*
G54D63*
X1779504Y-15000D03*
X1713503D03*
G54D43*
X1392264Y23976D03*
X1513918D03*
G54D30*
X-10236Y116969D03*
X-4725D03*
X23228Y124843D03*
X17716D03*
X-10236Y132717D03*
X-4725D03*
X6299D03*
X11811D03*
X17716Y140591D03*
X23228D03*
X-10236Y373110D03*
X-4725D03*
X23228Y380984D03*
X17716D03*
X-10236Y388858D03*
X-4725D03*
X6299D03*
X11811D03*
X17716Y396732D03*
X23228D03*
G54D45*
X1724606Y235430D03*
X1527844Y80791D03*
G54D65*
X1667012Y-14488D03*
X1627642D03*
X1647327Y-315D03*
G54D51*
X1900595Y525415D03*
X1908469D03*
X1916343D03*
X1924217D03*
X1922248Y518328D03*
X1892720Y525415D03*
X1894689Y518328D03*
X1628142Y263999D03*
G54D29*
X-17084Y467626D03*
X-17200Y510800D03*
X-17300Y530800D03*
X-17397Y564242D03*
X-1000Y81500D03*
X37037Y138425D03*
X7995Y285385D03*
X-6104Y461190D03*
X10443Y490649D03*
X26780Y488910D03*
X21000Y495800D03*
X-9600Y526100D03*
X-6712Y515731D03*
X-10200Y558200D03*
X0Y566800D03*
X46560Y581000D03*
Y577500D03*
X-8318Y542216D03*
X-3100Y533991D03*
X-10947Y544117D03*
X-4300Y558400D03*
X-4100Y554400D03*
X-9287Y531604D03*
X-9291Y535201D03*
X85250Y127680D03*
X77730Y126860D03*
X70980Y97166D03*
X77650Y178150D03*
X73500Y191500D03*
X83300Y267400D03*
X79300Y272300D03*
X84000Y272500D03*
X53500Y307300D03*
X70700Y330349D03*
X93500Y289000D03*
X58400Y314600D03*
X53000Y323500D03*
X52804Y333247D03*
X61300Y328600D03*
X93500Y285000D03*
X93400Y296000D03*
X48550Y301650D03*
X88600Y302997D03*
X53250Y302800D03*
X77300Y390600D03*
X60400Y355750D03*
X61914Y368731D03*
X57800Y376100D03*
X62600Y375100D03*
X72603Y474072D03*
X47800Y487600D03*
X264171Y104284D03*
X270864D03*
X257478D03*
X277407D03*
X234053D03*
X240596D03*
X386292Y98800D03*
X385244Y504027D03*
X512024Y104314D03*
X488634D03*
X495077D03*
X518467D03*
X525134D03*
X531738D03*
X548620D03*
X555313D03*
X584076Y443828D03*
X605300Y124600D03*
X630000Y126572D03*
X651920Y125750D03*
X654558Y115101D03*
X648690Y125590D03*
X625430Y490100D03*
X623660Y466746D03*
X632113Y496892D03*
X656900Y482290D03*
X649600Y492400D03*
X660500Y492000D03*
X641150Y484300D03*
X653800Y496600D03*
X678020Y69870D03*
X713830Y82730D03*
X720572Y88700D03*
X716894Y84047D03*
X701500Y85500D03*
X698300Y85300D03*
X715505Y155076D03*
X720700Y154750D03*
X725650Y155000D03*
X675600Y150000D03*
Y144900D03*
X715550Y158880D03*
X705550D03*
X710550D03*
X686619Y392600D03*
X691240Y390039D03*
X685600Y432500D03*
X690600D03*
Y437500D03*
X664610Y512810D03*
X704500Y512850D03*
X696000Y496800D03*
X680000Y511800D03*
X686200Y511700D03*
X700500Y512850D03*
X726040Y506080D03*
X755500Y46700D03*
X737800Y55800D03*
X751708Y73800D03*
X753100Y92111D03*
X751600Y41000D03*
X755500Y55200D03*
X730600Y154984D03*
X740718Y150957D03*
X746000Y150500D03*
X752900Y101000D03*
X740650Y164800D03*
X735600Y164900D03*
X740650Y158800D03*
X749640Y431797D03*
X728940Y457806D03*
X756000Y525950D03*
X738648Y492050D03*
X736300Y541500D03*
X756000Y537000D03*
X754910Y556400D03*
X907086Y104284D03*
X890204D03*
X883661D03*
X920472D03*
X913779D03*
X927015D03*
X1138242Y104314D03*
X1144685D03*
X1161632D03*
X1168075D03*
X1174742D03*
X1181346D03*
X1198228D03*
X1204921D03*
X1277660Y109450D03*
X1237400Y103100D03*
X1259950Y144650D03*
X1277600Y106200D03*
X1237704Y148423D03*
X1268576Y117788D03*
X1252000Y145300D03*
X1267800Y161800D03*
X1271400Y161900D03*
X1240309D03*
X1263300Y169450D03*
X1277978Y491571D03*
X1262843Y497553D03*
X1341400Y46100D03*
X1336900Y89896D03*
X1330300Y83500D03*
X1335120Y94450D03*
X1340100Y145000D03*
X1335100Y155000D03*
Y145000D03*
X1330100Y150000D03*
X1340100D03*
Y155000D03*
X1315100Y145000D03*
X1335100Y150000D03*
X1330100Y155000D03*
X1306900Y131744D03*
X1301900Y124400D03*
X1338500Y96000D03*
X1330100Y160000D03*
X1340100D03*
X1335100D03*
X1281799Y193190D03*
X1300300Y169900D03*
X1300100Y442500D03*
X1301000Y460900D03*
X1305100Y432500D03*
X1320100Y427500D03*
Y432500D03*
X1325100Y427500D03*
Y432500D03*
X1305181Y427834D03*
X1310100Y427500D03*
Y432500D03*
X1315100Y427500D03*
Y432500D03*
X1330100D03*
Y427500D03*
X1335100Y457500D03*
Y452500D03*
Y447500D03*
Y442500D03*
X1330100D03*
X1305100D03*
X1310100D03*
X1320100D03*
X1315100D03*
X1325100D03*
X1340100Y457500D03*
Y452500D03*
Y447500D03*
Y442500D03*
X1340986Y511187D03*
X1341050Y498275D03*
X1357400Y-19800D03*
X1360400Y10600D03*
X1385608Y-17485D03*
X1389523Y4966D03*
X1344000Y83000D03*
X1402700Y51100D03*
X1388627Y35032D03*
X1380500Y54500D03*
Y50500D03*
X1370100Y82500D03*
X1366100D03*
X1375500Y76000D03*
X1365855Y46972D03*
X1347500Y83000D03*
X1358500Y74500D03*
X1363500Y77400D03*
X1351488Y74000D03*
X1347000Y87500D03*
X1343500D03*
X1360700Y86550D03*
X1372300Y86400D03*
X1355100Y155000D03*
Y145000D03*
Y150000D03*
X1360100Y155000D03*
Y145000D03*
Y150000D03*
X1345100D03*
X1350100Y155000D03*
Y150000D03*
Y145000D03*
X1345100D03*
Y155000D03*
X1394253Y116989D03*
X1385100Y155000D03*
X1375100D03*
X1365100D03*
X1380100D03*
Y145000D03*
X1385100D03*
X1380100Y150000D03*
X1385100D03*
X1365100Y145000D03*
Y150000D03*
X1375100D03*
X1370100Y155000D03*
Y145000D03*
X1375100D03*
X1370100Y150000D03*
X1384600Y108500D03*
X1381359Y108496D03*
X1388100Y108500D03*
X1371500Y101000D03*
X1348615Y96239D03*
X1380100Y160000D03*
X1360100D03*
X1355100D03*
X1345100D03*
X1350100D03*
X1390100D03*
X1370100D03*
X1390100Y170000D03*
X1385100Y160000D03*
Y165000D03*
Y170000D03*
X1365100Y160000D03*
X1375100D03*
X1390100Y165000D03*
X1396933Y215763D03*
X1344462Y209272D03*
X1345100Y442500D03*
X1350100D03*
X1345100Y437500D03*
X1365100Y452500D03*
X1380100D03*
X1362560Y463478D03*
X1377492Y516892D03*
X1369757Y517465D03*
X1344761Y498282D03*
X1355800Y508500D03*
X1400830Y564090D03*
X1400288Y570099D03*
X1404420Y576330D03*
X1379053Y581864D03*
X1387050Y615350D03*
X1375600Y589700D03*
X1413721Y36749D03*
X1449847Y202322D03*
X1439000Y208500D03*
X1442251Y180818D03*
X1418300Y199900D03*
X1440150Y175550D03*
X1440124Y166180D03*
X1458908Y187699D03*
X1447999Y205645D03*
X1464200Y231400D03*
X1458318Y243000D03*
X1461348Y244350D03*
X1414107Y447267D03*
X1410850Y564210D03*
X1410340Y570370D03*
X1422500Y579800D03*
X1414800D03*
X1410950Y589670D03*
X1499800Y199300D03*
X1523400Y217900D03*
X1483523Y181100D03*
X1517328Y186208D03*
X1511100Y186275D03*
X1492597Y172636D03*
X1488900Y172576D03*
X1477388Y172988D03*
X1497237Y217281D03*
X1512700Y205100D03*
X1512525Y208944D03*
X1492136Y199125D03*
X1512500Y199837D03*
X1516872Y208863D03*
X1515060Y192443D03*
X1507524Y218600D03*
X1479500Y238500D03*
X1491700Y241661D03*
X1470950Y229669D03*
X1486926Y247834D03*
X1516549Y234278D03*
X1516613Y240656D03*
X1482400Y248000D03*
X1487500Y244500D03*
X1583621Y87213D03*
X1556200Y94800D03*
X1554800Y129100D03*
X1558189Y107067D03*
X1578000Y113000D03*
X1553500Y157000D03*
X1576506Y143416D03*
X1583600Y207495D03*
X1531565Y176645D03*
X1557634Y175948D03*
X1552051Y172053D03*
X1571501Y180031D03*
X1535000Y207200D03*
X1557979Y188844D03*
X1553500Y165400D03*
X1548178Y190880D03*
X1531935Y224160D03*
X1643887Y181841D03*
X1618500Y181680D03*
X1620036Y196186D03*
X1601142Y172185D03*
X1604401Y213500D03*
X1651000Y178628D03*
X1603300Y185100D03*
X1615362Y213507D03*
X1650600Y186300D03*
X1648349Y182276D03*
X1602185Y180709D03*
X1608731Y180819D03*
X1591174Y225017D03*
X1643775Y246137D03*
X1638216Y246021D03*
X1687550Y213751D03*
X1708350Y175050D03*
X1654015Y217239D03*
X1660800Y181900D03*
X1663400Y179475D03*
X1673800Y201070D03*
X1667140Y182300D03*
X1705666Y198055D03*
X1681116Y238614D03*
X1679145Y461950D03*
X1714528Y190189D03*
X1719080Y236152D03*
X1718820Y249032D03*
X1727896Y246175D03*
X1719080Y232852D03*
X1715078Y250231D03*
X1832274Y209734D03*
X1828950Y209600D03*
X1827565Y179174D03*
X1824200Y176900D03*
X1787000Y175500D03*
X1800787Y447943D03*
X1878550Y99470D03*
X1856700Y110167D03*
X1863908Y140992D03*
X1857110Y113600D03*
X1866606Y109967D03*
X1861932Y146431D03*
X1839500Y212700D03*
X1863750Y163750D03*
X1846163Y168448D03*
X1868375Y171900D03*
X1868843Y207920D03*
X1840900Y179700D03*
X1845700D03*
X1872100Y207900D03*
X1861243Y183100D03*
X1858686Y180377D03*
X1858500Y200100D03*
X1864000Y184900D03*
X1878789Y213663D03*
X1885465Y166285D03*
X1855000Y167100D03*
X1882677Y447930D03*
X1863137Y452710D03*
X1875900Y453600D03*
X1909406Y76790D03*
X1918379Y84788D03*
X1911231Y137097D03*
X1928100Y136078D03*
X1952440Y98520D03*
X1911440Y128840D03*
X1921199Y140499D03*
X1933914Y96040D03*
X1929000Y445800D03*
X620070Y50878D03*
X620192Y69778D03*
X620092Y88678D03*
Y13078D03*
X620192Y31978D03*
Y-5822D03*
X647317Y-1310D03*
X660676Y-2600D03*
X659700Y22900D03*
X548620Y36049D03*
X568699D03*
X555313D03*
X562006Y35999D03*
X585431Y36049D03*
X592124D03*
X598817D03*
X562006Y46914D03*
X548620D03*
X551966Y67749D03*
X564966D03*
X571345Y67900D03*
X548620Y84714D03*
X568549D03*
X555313D03*
X562006D03*
X548620Y73849D03*
X562006Y73799D03*
X555313Y73849D03*
X585431Y46914D03*
X598817Y46957D03*
Y65699D03*
X595470Y67749D03*
X588777D03*
X602163Y65699D03*
X592124Y84714D03*
X585431D03*
X598817Y84757D03*
X585431Y73849D03*
X598817D03*
X592124D03*
X602163Y92599D03*
X592124Y46914D03*
X568699Y73849D03*
X555313Y46914D03*
X568549D03*
X558659Y67749D03*
X562006Y9114D03*
X568549D03*
X555313D03*
X548620D03*
X571345Y-7700D03*
X551966Y-7851D03*
X564966D03*
X558659D03*
X562006Y-1801D03*
X558659Y29949D03*
X551966D03*
X564966D03*
X571345Y30100D03*
X588777Y-7851D03*
X598817Y-9901D03*
X595470Y-7851D03*
X592124Y-1751D03*
X598817D03*
X585431D03*
X602163Y-9901D03*
X598817Y9157D03*
X592124Y9114D03*
X585431D03*
X588777Y29949D03*
X595470D03*
X598817Y27899D03*
X602163Y16999D03*
X548620Y-1751D03*
X568699D03*
X555313D03*
X481691Y36049D03*
Y46914D03*
Y84714D03*
Y73849D03*
X488384Y35999D03*
X495077Y36049D03*
X518502D03*
X531888D03*
X525195Y35999D03*
X511809Y36049D03*
X497723Y67900D03*
X511809Y46914D03*
X491344Y67749D03*
X494927Y46914D03*
X488384D03*
X511809Y84714D03*
X494927D03*
X488384D03*
Y73799D03*
X495077Y73849D03*
X518502Y46914D03*
X521848Y67749D03*
X531738Y46914D03*
X515155Y67749D03*
X534534Y67900D03*
X528155Y67749D03*
X525195Y46914D03*
X518502Y73849D03*
Y84714D03*
X531738D03*
X525195D03*
X531888Y73849D03*
X525195Y73799D03*
X511809Y73849D03*
X485037Y67749D03*
X481691Y-1751D03*
Y9114D03*
X511809Y-1751D03*
X495077D03*
X488384Y-1801D03*
X485037Y-7851D03*
X491344D03*
X497723Y-7700D03*
X494927Y9114D03*
X488384D03*
X497723Y30100D03*
X485037Y29949D03*
X491344D03*
X515155Y-7851D03*
X518502Y-1751D03*
X521848Y-7851D03*
X531888Y-1751D03*
X525195Y-1801D03*
X528155Y-7851D03*
X534534Y-7700D03*
X518502Y9114D03*
X531738D03*
X525195D03*
X534534Y30100D03*
X515155Y29949D03*
X528155D03*
X521848D03*
X511809Y9114D03*
X427696Y103100D03*
X421512Y103116D03*
X474998Y36049D03*
X458266D03*
X438189Y35957D03*
X444882D03*
X428149D03*
X434842D03*
X448492Y51000D03*
X421368D03*
X433508D03*
Y69900D03*
X421368D03*
X474998Y46914D03*
X454533Y67749D03*
X460912Y67900D03*
X458116Y84714D03*
X474998Y73849D03*
X458266D03*
X474998Y84714D03*
X478344Y67749D03*
X458116Y46914D03*
X448692Y89900D03*
X421455Y46921D03*
X421456Y73757D03*
X438189D03*
X444880Y65822D03*
X428149Y73757D03*
X421456Y65822D03*
X434842Y73757D03*
X438189Y65822D03*
Y46922D03*
X431494Y54842D03*
X444880Y54859D03*
Y46922D03*
X428149D03*
X421456Y54857D03*
X434842Y46922D03*
X424801Y54842D03*
X438187Y54859D03*
X447744Y-7180D03*
X451573Y-1801D03*
Y9114D03*
X448226Y28100D03*
X433508Y32100D03*
X448292Y31900D03*
X421368Y32100D03*
X433508Y13200D03*
X421368D03*
X458266Y-1751D03*
X460912Y-7700D03*
X454533Y-7851D03*
X474998Y-1751D03*
X478344Y-7851D03*
X474998Y9114D03*
X478344Y29949D03*
X460912Y30100D03*
X454533Y29949D03*
X458116Y9114D03*
X421455Y9121D03*
X421454Y-1817D03*
X444880Y28022D03*
X421456D03*
X438189D03*
X438187Y9120D03*
X431494Y17042D03*
X444880Y17059D03*
Y9122D03*
X428147Y9120D03*
X421456Y17057D03*
X434840Y9120D03*
X424801Y17042D03*
X438187Y17059D03*
X401375Y103116D03*
X414819D03*
X408126D03*
X401377Y35957D03*
X404723D03*
X414763D03*
X394684D03*
X411415Y36058D03*
X371042Y46900D03*
X380792Y56500D03*
X408184Y51000D03*
Y69900D03*
X394492Y54700D03*
X404723Y65822D03*
X401377Y73757D03*
X414763Y65822D03*
X404723Y73757D03*
X414763D03*
X404723Y54857D03*
X401377Y46922D03*
X414763Y54857D03*
X398029Y54842D03*
X404723Y46922D03*
X414763D03*
X408069Y54842D03*
X411416Y73757D03*
Y46922D03*
X380200Y-1200D03*
X394192Y-9700D03*
X408184Y32100D03*
Y13200D03*
X404723Y28022D03*
X364565Y28014D03*
X361218D03*
X414762Y28021D03*
X404723Y17057D03*
X401376Y9121D03*
X414762Y17058D03*
X398029Y17042D03*
X404722Y9121D03*
X414763Y9122D03*
X408069Y17042D03*
X411416Y9122D03*
X294289Y36049D03*
Y46914D03*
Y84714D03*
Y73849D03*
X300982Y36049D03*
X307675Y35957D03*
X327754D03*
X324407D03*
X311021D03*
X334447D03*
X354526D03*
X347833D03*
X344486D03*
X337793D03*
X317714D03*
X307950Y50729D03*
X321192Y51000D03*
X304328Y67749D03*
X297635D03*
X300982Y46914D03*
X321334Y69900D03*
X307592Y73800D03*
X300982Y84714D03*
X334292Y51000D03*
Y69900D03*
X308166Y87394D03*
X300982Y73849D03*
X307675Y54857D03*
Y92657D03*
X321061Y65814D03*
X327754Y73757D03*
X324407Y65814D03*
Y73757D03*
X314368Y65814D03*
X334447Y73757D03*
X331100Y65814D03*
X354525Y65822D03*
X354526Y73757D03*
X351179Y65822D03*
X347833Y73757D03*
X344486D03*
Y65822D03*
X337793Y73757D03*
X341140Y65822D03*
X334446Y65814D03*
X321061Y54857D03*
X327754Y46914D03*
X324407Y54857D03*
Y46914D03*
X314368Y54857D03*
X311021Y46914D03*
X334446D03*
X331100Y54857D03*
X354526D03*
X354525Y46922D03*
X351179Y54857D03*
X347833Y46922D03*
X344486D03*
Y54857D03*
X337793Y46914D03*
X341140Y54857D03*
X334447D03*
X317714Y73757D03*
Y46914D03*
X294289Y-1751D03*
Y9114D03*
X297635Y-7851D03*
X304328D03*
X300982Y-1751D03*
Y9114D03*
X307675Y-1843D03*
Y9300D03*
X304328Y29949D03*
X307992Y13200D03*
X321192D03*
X321334Y32100D03*
X308092D03*
X297635Y29949D03*
X334292Y13200D03*
Y32100D03*
X308157Y-7180D03*
X307675Y17057D03*
Y28014D03*
X321061D03*
X324407D03*
X314368D03*
X331100D03*
X354525Y28022D03*
X351179D03*
X344486D03*
X341140D03*
X334446Y28014D03*
X321061Y17057D03*
X327754Y9114D03*
X324407Y17057D03*
Y9114D03*
X314368Y17057D03*
X311021Y9114D03*
X334446D03*
X331100Y17057D03*
X354526D03*
X354525Y9122D03*
X351179Y17057D03*
X347833Y9122D03*
X344486D03*
Y17057D03*
X337793Y9114D03*
X341140Y17057D03*
X334447D03*
X317714Y9114D03*
X234053Y35999D03*
Y73799D03*
Y84714D03*
Y46914D03*
X257478Y36049D03*
X240746D03*
X264171D03*
X277557D03*
X270864Y35999D03*
X257478Y46914D03*
X240596D03*
X243392Y67900D03*
X267517Y67749D03*
X270864Y46914D03*
X237013Y67749D03*
X260824D03*
X264171Y46914D03*
Y84714D03*
X257478D03*
X240746Y73849D03*
X257478D03*
X264171D03*
X270864Y84714D03*
X240596D03*
X270864Y73799D03*
X273824Y67749D03*
X280203Y67900D03*
X277407Y46914D03*
Y84714D03*
Y73849D03*
X234053Y-1801D03*
Y9114D03*
X270864Y-1801D03*
X240746Y-1751D03*
X264171D03*
X257478D03*
X243392Y-7700D03*
X260824Y-7851D03*
X237013D03*
X267517D03*
X264171Y9114D03*
X240596D03*
X270864D03*
X257478D03*
X267517Y29949D03*
X243392Y30100D03*
X260824Y29949D03*
X237013D03*
X273824Y-7851D03*
X280203Y-7700D03*
X277407Y9114D03*
X277557Y-1751D03*
X273824Y29949D03*
X280203Y30100D03*
X183856Y36049D03*
X203935D03*
X220667D03*
X227360D03*
X197242Y35999D03*
X190549Y36049D03*
X183856Y84714D03*
Y73849D03*
Y46914D03*
X193895Y67749D03*
X200202D03*
X187202D03*
X203785Y46914D03*
X190549D03*
X197242D03*
X206581Y67900D03*
X197242Y73799D03*
X203935Y73849D03*
X190549D03*
Y84714D03*
X197242D03*
X203785D03*
X220667Y46914D03*
X224013Y67749D03*
X230706D03*
X227360Y46914D03*
X220667Y73849D03*
Y84714D03*
X227360D03*
Y73849D03*
X183856Y-1751D03*
Y9114D03*
X190549D03*
X197242D03*
X193895Y-7851D03*
X187202D03*
X200202D03*
X190549Y-1751D03*
X197242Y-1801D03*
X203935Y-1751D03*
X206581Y-7700D03*
X203785Y9114D03*
X200202Y29949D03*
X187202D03*
X193895D03*
X206581Y30100D03*
X220667Y-1751D03*
X227360D03*
X230706Y-7851D03*
X224013D03*
X220667Y9114D03*
X227360D03*
X224013Y29949D03*
X230706D03*
X109057Y92774D03*
X167124Y36049D03*
X123620Y35983D03*
X130313D03*
X147045Y36049D03*
X153738D03*
X160431Y35999D03*
X166974Y84714D03*
Y73849D03*
Y46914D03*
X169770Y67900D03*
X157084Y67749D03*
X163391D03*
X130313Y73849D03*
X123620Y73799D03*
X126580Y67749D03*
X132959Y67900D03*
X123620Y46914D03*
X147045D03*
X120273Y54839D03*
Y92500D03*
X160431Y84714D03*
X153738D03*
X123620D03*
X147045D03*
X130163D03*
Y46914D03*
X120273Y66000D03*
X147045Y73849D03*
X153738D03*
X160431Y73799D03*
X150391Y67749D03*
X160431Y46914D03*
X153738D03*
X119892Y84700D03*
X120273Y46957D03*
X160431Y-1801D03*
X153738Y9114D03*
X150391Y-7851D03*
X163391D03*
X157084D03*
X153738Y-1751D03*
X160431Y9114D03*
X120273Y16839D03*
X147045Y9114D03*
X130163D03*
X123620D03*
X126580Y-7851D03*
X132959Y-7700D03*
X120273Y-9901D03*
X123620Y-1801D03*
X130313Y-1751D03*
X147045D03*
X167124D03*
X169770Y-7700D03*
X166974Y9114D03*
X169770Y30100D03*
X120273Y27899D03*
X126580Y29949D03*
X132959Y30100D03*
X157084Y29949D03*
X163391D03*
X150391D03*
X120273Y9157D03*
X102100Y73800D03*
X105892Y45290D03*
X108385Y84291D03*
X105898Y55194D03*
X105892Y8700D03*
X106200Y26500D03*
X93500Y-18000D03*
X87091Y-16391D03*
X106000Y17260D03*
X110670Y344500D03*
X110397Y402603D03*
X109640Y376070D03*
X109500Y370000D03*
X122361Y342649D03*
X119300Y400900D03*
X118220Y360500D03*
X110180Y280920D03*
X109960Y313190D03*
X118800Y298400D03*
X113100Y333106D03*
X113000Y304000D03*
X112904Y237218D03*
X113100Y269163D03*
X103100Y411800D03*
X107750Y238730D03*
X108000Y249330D03*
X620033Y608878D03*
X660230Y598170D03*
X662000Y589000D03*
X585431Y612649D03*
X592124D03*
X598817D03*
X555313D03*
X562006Y612599D03*
X568699Y612649D03*
X548620D03*
X571345Y606700D03*
X558659Y606549D03*
X564966D03*
X551966D03*
X598817Y604499D03*
X595470Y606549D03*
X588777D03*
X602163Y593599D03*
Y604499D03*
X598817Y528899D03*
X602163D03*
X548620Y547914D03*
Y537049D03*
X551966Y530949D03*
X558659D03*
X555313Y537049D03*
X562006Y536999D03*
X564966Y530949D03*
X568699Y537049D03*
X571345Y531100D03*
X555313Y547914D03*
X568549D03*
X562006D03*
X555313Y585714D03*
X568549D03*
X562006D03*
X548620D03*
X598817Y547957D03*
X592124Y547914D03*
X595470Y530949D03*
X592124Y537049D03*
X588777Y530949D03*
X598817Y537049D03*
X585431Y547914D03*
Y537049D03*
Y585714D03*
X598817Y585757D03*
Y566699D03*
X592124Y585714D03*
Y574849D03*
X588777Y568749D03*
X595470D03*
X598817Y574849D03*
X585431D03*
X548620D03*
X551966Y568749D03*
X568699Y574849D03*
X558659Y568749D03*
X555313Y574849D03*
X562006Y574799D03*
X564966Y568749D03*
X571345Y568900D03*
X555313Y510114D03*
X548620D03*
X568549D03*
X562006D03*
X598817Y510157D03*
X602163Y517999D03*
X592124Y510114D03*
X585431D03*
X525195Y612599D03*
X518502Y612649D03*
X531888D03*
X495077D03*
X488384Y612599D03*
X511809Y612649D03*
X491344Y606549D03*
X497723Y606700D03*
X485037Y607230D03*
X515155Y606549D03*
X521848D03*
X534534Y606700D03*
X528155Y606549D03*
X481691Y547914D03*
Y537049D03*
Y585714D03*
Y574849D03*
X511809Y547914D03*
Y537049D03*
X494927Y547914D03*
X488384D03*
X491344Y530949D03*
X488384Y536999D03*
X495077Y537049D03*
X497723Y531100D03*
X485037Y530949D03*
X488384Y585714D03*
X511809D03*
X494927D03*
X515155Y530949D03*
X534534Y531100D03*
X531888Y537049D03*
X528155Y530949D03*
X525195Y536999D03*
Y547914D03*
X531738D03*
X518502D03*
Y537049D03*
X521848Y530949D03*
X518502Y585714D03*
X531738D03*
X525195D03*
X531888Y574849D03*
X528155Y568749D03*
X525195Y574799D03*
X534534Y568900D03*
X521848Y568749D03*
X518502Y574849D03*
X515155Y568749D03*
X495077Y574849D03*
X488384Y574799D03*
X497723Y568900D03*
X491344Y568749D03*
X511809Y574849D03*
X485037Y568749D03*
X481691Y510114D03*
X511809D03*
X494927D03*
X488384D03*
X531738D03*
X525195D03*
X518502D03*
X420634Y589800D03*
X433500D03*
X474998Y612649D03*
X458266D03*
X451573Y612599D03*
X447744Y607220D03*
X478344Y606549D03*
X460912Y606700D03*
X454533Y606549D03*
X421454Y612560D03*
X431494Y593642D03*
X444880Y593659D03*
X421456Y593657D03*
X424801Y593642D03*
X438187Y593659D03*
X421456Y529022D03*
X451573Y547914D03*
X448510Y549843D03*
X448692Y553100D03*
X421368Y533100D03*
X434395Y532904D03*
X433508Y552000D03*
X421368D03*
X433508Y570900D03*
X421368D03*
X451573Y585714D03*
Y574799D03*
X458116Y547914D03*
X454533Y530949D03*
X460912Y531100D03*
X458266Y537049D03*
X474998D03*
Y547914D03*
X478344Y530949D03*
X474998Y585714D03*
X458116D03*
X454533Y568749D03*
X460912Y568900D03*
X458266Y574849D03*
X474998D03*
X478344Y568749D03*
X448291Y574773D03*
X448226Y569200D03*
X421456Y547922D03*
Y585722D03*
X438189Y536957D03*
X444882D03*
X428149D03*
X434842D03*
X438189Y547922D03*
Y574757D03*
X444880Y566822D03*
X444882Y574757D03*
X431494Y555842D03*
X444880Y555859D03*
Y547922D03*
X428149D03*
Y574757D03*
X421456Y555857D03*
Y566822D03*
X434842Y547922D03*
Y574757D03*
X438189Y566822D03*
X424801Y555842D03*
X438187Y555859D03*
X438189Y585722D03*
X444880D03*
X428149D03*
X434842D03*
X451573Y510114D03*
X474998D03*
X458116D03*
X408184Y589800D03*
X404723Y593657D03*
X414763D03*
X398029Y593642D03*
X408069D03*
X363760Y529293D03*
X404723Y529022D03*
X376785Y538305D03*
X376892Y577500D03*
X408184Y533100D03*
Y552000D03*
Y570900D03*
X401377Y536957D03*
X404723D03*
X414763D03*
X404723Y566822D03*
Y555857D03*
X401376Y547922D03*
X401377Y574757D03*
X414763Y566822D03*
Y555857D03*
X398029Y555842D03*
X404723Y547922D03*
Y574757D03*
X414763D03*
Y547922D03*
X408069Y555842D03*
X394684Y574757D03*
X401377Y585722D03*
X404723D03*
X414763D03*
X411416Y536957D03*
X411415Y547921D03*
X411416Y574757D03*
Y585722D03*
X294289Y612249D03*
X321192Y589800D03*
X334292D03*
X304328Y606549D03*
X297635D03*
X300982Y612249D03*
X307675Y611600D03*
X308157Y607220D03*
X321061Y593657D03*
X324407D03*
X314368D03*
X331100D03*
X354526D03*
X351179D03*
X344486D03*
X341140D03*
X334447D03*
X294289Y547914D03*
Y537049D03*
Y585714D03*
Y574849D03*
X308198Y528863D03*
X321061Y529014D03*
X324407D03*
X331100D03*
X354525Y529022D03*
X351179D03*
X344486D03*
X341140D03*
X334446Y529014D03*
X307675Y548200D03*
X300982Y547914D03*
X307675Y536957D03*
X304328Y530949D03*
X300982Y537049D03*
X297635Y530949D03*
X307992Y533100D03*
X321334D03*
X321123Y552000D03*
X308100D03*
X307992Y570900D03*
X321334D03*
X307675Y574757D03*
X300982Y574849D03*
Y585714D03*
X334292Y533100D03*
Y552000D03*
Y570900D03*
X297635Y568749D03*
X304328D03*
X307675Y555857D03*
X307984Y566743D03*
X327754Y536957D03*
X324407D03*
X311021D03*
X334447D03*
X354526D03*
X347833D03*
X344486D03*
X337793D03*
X321061Y566814D03*
Y555857D03*
X327754Y547914D03*
Y574757D03*
X324407Y555857D03*
Y566814D03*
Y547914D03*
Y574757D03*
X314368Y566814D03*
X311021Y574757D03*
X314368Y555857D03*
X311021Y547914D03*
X334446D03*
X334447Y574757D03*
X331100Y555857D03*
Y566814D03*
X354526Y555857D03*
X354525Y566822D03*
Y547922D03*
X354526Y574757D03*
X351179Y555857D03*
Y566822D03*
X347833Y547922D03*
Y574757D03*
X344486Y547922D03*
Y574757D03*
Y566822D03*
Y555857D03*
X337793Y547914D03*
Y574757D03*
X341140Y555857D03*
Y566822D03*
X334447Y555857D03*
X334446Y566814D03*
X327754Y585714D03*
X324407D03*
X311021D03*
X334446D03*
X354525Y585722D03*
X347833D03*
X344486D03*
X337793Y585714D03*
X317714Y536957D03*
Y547914D03*
Y574757D03*
Y585714D03*
X294289Y510114D03*
X308166Y512794D03*
X300982Y510114D03*
X307675Y518057D03*
X234053Y612599D03*
X240746Y612649D03*
X257478D03*
X260824Y606549D03*
X237013D03*
X243392Y606700D03*
X264171Y612449D03*
X267517Y606549D03*
X270864Y612399D03*
X273824Y606549D03*
X280203Y606700D03*
X277407Y612449D03*
X234053Y536999D03*
Y547914D03*
Y585714D03*
Y574799D03*
X257478Y537049D03*
X237013Y530949D03*
X243392Y531100D03*
X240746Y537049D03*
X270864Y547914D03*
X267517Y530949D03*
X270864Y536999D03*
X264171Y547914D03*
X257478D03*
X240596D03*
X264171Y537049D03*
X260824Y530949D03*
X270864Y585714D03*
X264171D03*
X257478D03*
X240596D03*
X277407Y537049D03*
X273824Y530949D03*
X280203Y531100D03*
X277407Y547914D03*
Y585714D03*
Y574849D03*
X280203Y568900D03*
X273824Y568749D03*
X243392Y568900D03*
X260824Y568749D03*
X257478Y574849D03*
X264171D03*
X237013Y568749D03*
X240746Y574849D03*
X267517Y568749D03*
X270864Y574799D03*
X234053Y510114D03*
X264171D03*
X257478D03*
X270864D03*
X240596D03*
X277407D03*
X227360Y612649D03*
X220667D03*
X203935D03*
X197242Y612599D03*
X190549Y612649D03*
X183856D03*
X187202Y606549D03*
X193895D03*
X200202D03*
X206581Y606700D03*
X224013Y606549D03*
X230706D03*
X183856Y547914D03*
X190549D03*
X203785D03*
X197242D03*
X190549Y537049D03*
X183856D03*
X187202Y530949D03*
X193895D03*
X197242Y536999D03*
X203935Y537049D03*
X200202Y530949D03*
X206581Y531100D03*
X197242Y574799D03*
X190549Y585714D03*
X183856D03*
X197242D03*
X203785D03*
X224013Y530949D03*
X220667Y537049D03*
X230706Y530949D03*
X227360Y537049D03*
X220667Y547914D03*
X227360D03*
X220667Y585714D03*
X227360D03*
Y574849D03*
X230706Y568749D03*
X220667Y574849D03*
X224013Y568749D03*
X206581Y568900D03*
X183856Y574849D03*
X190549D03*
X193895Y568749D03*
X187202D03*
X200202D03*
X203935Y574849D03*
X197242Y510114D03*
X203785D03*
X190549D03*
X183856D03*
X220667D03*
X227360D03*
X147045Y612649D03*
X123620Y612599D03*
X130313Y612649D03*
X160431Y612599D03*
X166974Y612649D03*
X153738D03*
X132959Y606700D03*
X126580Y606549D03*
X120092Y604900D03*
X150391Y606549D03*
X163391D03*
X169770Y606700D03*
X157084Y606549D03*
X119892Y612583D03*
X120210Y529200D03*
X130163Y547914D03*
X123620D03*
X147045Y537049D03*
Y547914D03*
X130313Y537049D03*
X132959Y531100D03*
X126580Y530949D03*
X123620Y536999D03*
Y574799D03*
X130313Y574849D03*
X120092Y566900D03*
X147045Y585714D03*
X120273Y555700D03*
X130163Y585714D03*
X123620D03*
X150391Y530949D03*
X166974Y537049D03*
X163391Y530949D03*
X160431Y536999D03*
X166974Y547914D03*
X160431D03*
X157084Y530949D03*
X153738Y537049D03*
Y547914D03*
X169770Y531100D03*
X160431Y585714D03*
X166974D03*
X153738D03*
Y574849D03*
X157084Y568749D03*
X169770Y568900D03*
X160431Y574799D03*
X166974Y574849D03*
X163391Y568749D03*
X150391D03*
X147045Y574849D03*
X126580Y568749D03*
X132959Y568900D03*
X119892Y536983D03*
Y547900D03*
Y574700D03*
Y585700D03*
X130163Y510114D03*
X147045D03*
X120273Y517900D03*
X123620Y510114D03*
X166974D03*
X160431D03*
X153738D03*
X119892Y510100D03*
X82459Y618932D03*
X105352Y594770D03*
X106192Y604600D03*
X106392Y537000D03*
X105392Y574800D03*
X105412Y556580D03*
X105392Y566000D03*
X105958Y518550D03*
X106392Y527413D03*
X359117Y230559D03*
X396296Y244209D03*
Y240309D03*
X376017Y224709D03*
X372637Y222760D03*
X365877D03*
X369257Y224709D03*
X362497D03*
X386157Y222760D03*
X396296Y228610D03*
X389537Y224709D03*
X399676Y222760D03*
X382777Y224709D03*
X379397Y222760D03*
X359117D03*
X392916D03*
X396296Y224709D03*
X379397Y230559D03*
X365877Y242260D03*
X372637Y234460D03*
X365877D03*
X372637Y230559D03*
X365877D03*
X369257Y236409D03*
X362497D03*
X369257Y228610D03*
X362497D03*
X382777D03*
X389537Y236409D03*
X399676Y230559D03*
Y234460D03*
X382777Y236409D03*
X392916Y230559D03*
X376017Y236409D03*
X369257Y240309D03*
X376017D03*
X386157Y230559D03*
X372637Y242260D03*
X379397Y234460D03*
X399676Y238360D03*
X359117Y242260D03*
X362497Y240309D03*
X359117Y234460D03*
X386157D03*
X392916D03*
X389537Y228610D03*
X396296Y236409D03*
X376017Y228610D03*
X386157Y226660D03*
X389537Y232509D03*
X369257Y244209D03*
X362497D03*
X372637Y226660D03*
X365877D03*
X369257Y232509D03*
X362497D03*
X379397Y226660D03*
X382777Y232509D03*
X376017D03*
X359117Y226660D03*
X392916D03*
X396296Y232509D03*
X399676Y226660D03*
Y242260D03*
X389537Y240309D03*
X382777D03*
X392916Y242260D03*
X386157D03*
X379397D03*
X389537Y244209D03*
X382777D03*
X376017D03*
X392916Y246160D03*
X386157D03*
X399676D03*
X359117Y211060D03*
Y218860D03*
X372637Y207159D03*
X399676D03*
X372637Y211060D03*
X392916D03*
X389537Y213009D03*
X396296D03*
X369257D03*
X396296Y216909D03*
X376017D03*
X365877Y218860D03*
X372637D03*
X362497Y216909D03*
X382777Y213009D03*
X399676Y218860D03*
X386157Y211060D03*
X379397Y207159D03*
X369257Y216909D03*
X382777D03*
X379397Y218860D03*
X392916D03*
X362497Y213009D03*
X386157Y218860D03*
X389537Y216909D03*
X376017Y213009D03*
X386157Y207159D03*
X382777Y201309D03*
X365877Y214960D03*
X372637D03*
X379397D03*
X359117D03*
X365877Y203260D03*
X376017Y205211D03*
X362497Y205210D03*
X386157Y214960D03*
X404392Y199100D03*
X392898Y195041D03*
X392916Y214960D03*
Y203260D03*
X396296Y197359D03*
X399676Y203260D03*
Y214960D03*
Y211060D03*
X294899Y220809D03*
Y232509D03*
Y236409D03*
Y240309D03*
X308418Y220809D03*
X301659D03*
X335458D03*
X338838Y230560D03*
X298279Y222760D03*
X305039D03*
X328698Y236409D03*
X301659Y224709D03*
X328698Y240309D03*
Y244209D03*
X325318Y238360D03*
X335458Y240309D03*
Y244209D03*
X321938Y240309D03*
Y244209D03*
X332078Y238360D03*
X342218Y224709D03*
X345598Y230559D03*
X338838Y222760D03*
X352357D03*
X348978Y224709D03*
X355737D03*
X348978Y228610D03*
X352357Y230559D03*
X348978Y236409D03*
Y240309D03*
X352357Y234460D03*
X345598Y242260D03*
Y234460D03*
X342218Y240309D03*
Y228610D03*
Y236409D03*
X298279Y230559D03*
X301659Y244209D03*
X305039Y242260D03*
X301659Y232509D03*
X311798Y230559D03*
X318558Y234460D03*
Y222760D03*
X321938Y224709D03*
X311798Y234460D03*
X315178Y236409D03*
Y224709D03*
X321938Y228610D03*
X298279Y242260D03*
X305039Y238360D03*
X311798Y226660D03*
X305039Y234460D03*
X321938Y232509D03*
X298279Y238360D03*
X315178Y228610D03*
X301659Y236409D03*
X318558Y230559D03*
X355737Y228610D03*
Y236409D03*
X352357Y242260D03*
X355737Y240309D03*
X342218Y244209D03*
Y232509D03*
X355737Y244209D03*
X348978D03*
X345598Y226660D03*
X352357D03*
X348978Y232509D03*
X355737D03*
X345598Y222760D03*
X332078D03*
X328698Y224709D03*
X332078Y226660D03*
X335458Y228610D03*
X328698D03*
X332078Y230560D03*
X335458Y232510D03*
X311798Y242260D03*
X315178Y244209D03*
X294899Y216909D03*
Y205210D03*
Y209109D03*
Y197409D03*
X342218Y205210D03*
X298279Y214960D03*
X308418Y216909D03*
X305039Y214960D03*
X301659Y213009D03*
Y216909D03*
X345598Y207159D03*
X342218Y209109D03*
X348978Y205210D03*
Y216909D03*
X352357Y218860D03*
X345598D03*
X342218Y213009D03*
X338838Y214960D03*
X355737Y216909D03*
Y213009D03*
X338838Y218860D03*
X345598Y214960D03*
X352357D03*
X345598Y203260D03*
X355737Y205210D03*
X342218Y216909D03*
X338838Y207158D03*
Y203258D03*
X345598Y211060D03*
X348978Y213009D03*
X288139Y220809D03*
X281379Y228610D03*
X288139Y224709D03*
X284759Y230559D03*
X288139Y228610D03*
X277999Y222760D03*
X264092Y242260D03*
X271239D03*
X277999Y226660D03*
X281379Y224709D03*
X284759Y222760D03*
X277999Y238360D03*
X281379Y236409D03*
X277999Y242260D03*
X284759Y238360D03*
X288139Y244209D03*
Y240309D03*
X281379Y244209D03*
X284759Y242260D03*
X274619Y205210D03*
X271239Y207159D03*
X277999Y218860D03*
X281379Y216909D03*
X284759Y218860D03*
Y203260D03*
Y211060D03*
X281379Y205210D03*
Y209109D03*
X291519Y203260D03*
Y211060D03*
X288139Y201309D03*
Y213009D03*
Y205210D03*
Y209109D03*
X267859D03*
X277999Y199360D03*
X274619Y201309D03*
X271239Y203260D03*
X274619Y209109D03*
X150000Y194850D03*
Y199850D03*
X162800Y195600D03*
X162788Y200650D03*
X271239Y269560D03*
Y273460D03*
Y265660D03*
X267859Y263709D03*
Y259809D03*
X264179Y265660D03*
X267859Y252009D03*
X264179Y253960D03*
X281379Y252009D03*
X274619D03*
X277999Y253960D03*
X284759D03*
X291519D03*
X284759Y265660D03*
X291519D03*
Y277360D03*
X281379Y275409D03*
Y271509D03*
X284759Y277360D03*
Y273460D03*
X288139Y275409D03*
Y271509D03*
X277999Y277360D03*
X274619Y255909D03*
Y259809D03*
X277999Y269560D03*
X274619Y275409D03*
Y267609D03*
Y263709D03*
X288139Y255909D03*
X291519Y269560D03*
Y257860D03*
Y261760D03*
X294899Y275409D03*
Y263709D03*
X281379Y259809D03*
X288139Y252009D03*
X264179Y257860D03*
X271239D03*
X264179Y261760D03*
X271239D03*
Y253960D03*
X267859Y255909D03*
X281379Y267609D03*
X288139Y263709D03*
X277999Y257860D03*
X281379Y255909D03*
X284759Y269560D03*
X288139Y267609D03*
X277999Y261760D03*
X284759Y257860D03*
X288139Y259809D03*
X277999Y265660D03*
X284759Y261760D03*
X281379Y263709D03*
X294899Y252009D03*
Y255909D03*
Y259809D03*
X271239Y328060D03*
X264179D03*
X291519Y285160D03*
Y292959D03*
X284759Y285160D03*
X277999Y308560D03*
Y300760D03*
Y292959D03*
Y285160D03*
X291519Y308560D03*
X284759D03*
Y300760D03*
X291519D03*
X284759Y292959D03*
X281379Y318309D03*
X274619Y322209D03*
X277999Y320260D03*
Y316360D03*
X308418Y252009D03*
X298279Y253960D03*
X325318D03*
X308418Y275409D03*
X301659D03*
X308418Y255909D03*
X321938Y283209D03*
Y275409D03*
X315178Y279310D03*
X318558Y277360D03*
X315178Y283209D03*
X318558Y281260D03*
X311798Y261760D03*
X321938Y259809D03*
X301659D03*
X308418Y263709D03*
X325318Y269560D03*
X305039D03*
X318558D03*
X328698Y267609D03*
Y283209D03*
Y259809D03*
X332078Y269560D03*
Y281260D03*
X321938Y255909D03*
X308418Y259809D03*
X325318Y281260D03*
Y273460D03*
Y265660D03*
X301659Y267609D03*
X321938Y263709D03*
X298279Y265660D03*
X305039Y273460D03*
Y277360D03*
X311798D03*
Y269560D03*
X305039Y265660D03*
X298279Y277360D03*
X328698Y252009D03*
X338838Y253960D03*
X335458Y252009D03*
X338838Y265660D03*
X335458Y259809D03*
Y267609D03*
X338838Y281260D03*
X335458Y283209D03*
X345598Y265660D03*
X348978Y263709D03*
X355737Y259809D03*
X352357Y261760D03*
X345598Y273460D03*
Y269560D03*
X342218Y263709D03*
Y271509D03*
Y259809D03*
Y255909D03*
Y267609D03*
Y283209D03*
Y279310D03*
Y275409D03*
X298279Y261760D03*
X305039Y257860D03*
X328698Y255909D03*
Y263709D03*
X338838Y257860D03*
Y261760D03*
X325318Y257860D03*
Y261760D03*
X335458Y255909D03*
Y263709D03*
X301659D03*
X305039Y261760D03*
X301659Y252009D03*
X305039Y253960D03*
X332078D03*
X315178Y263709D03*
X332078Y265660D03*
X315178Y275409D03*
X301659Y255909D03*
X332078Y257860D03*
X315178Y267609D03*
X332078Y261760D03*
X315178Y271509D03*
X298279Y257860D03*
X311798Y265660D03*
Y273460D03*
X321938Y267609D03*
Y271509D03*
X308418Y267609D03*
Y271509D03*
X318558Y265660D03*
Y273460D03*
X342218Y252009D03*
X311798Y292959D03*
X305039D03*
X318558D03*
X311798Y285160D03*
X332078Y300760D03*
Y292959D03*
X298279Y308560D03*
X315178Y310509D03*
X305039Y308560D03*
X311798D03*
X305039Y300760D03*
X325318D03*
X311798D03*
X298279D03*
X318558D03*
X325318Y292959D03*
X305039Y285160D03*
X298279D03*
Y292959D03*
X338838Y300760D03*
Y292959D03*
X342218Y310509D03*
Y314409D03*
X365877Y253960D03*
X362497Y255909D03*
X359117Y257860D03*
X369257Y252009D03*
X441743Y348497D03*
X445123Y346546D03*
X288139Y337809D03*
X281379Y333909D03*
X284759Y335860D03*
X277999Y331960D03*
Y335860D03*
X284759Y339760D03*
Y328060D03*
X288139Y330009D03*
X277999Y339760D03*
X281379Y341709D03*
Y330009D03*
X288139Y333909D03*
X267859Y337809D03*
X271239Y339760D03*
X264179Y335860D03*
X271239D03*
X288139Y326110D03*
X281379D03*
X291519Y331960D03*
X284759D03*
X291519Y335860D03*
Y339760D03*
X281379Y337809D03*
X284759Y324160D03*
X274619Y337809D03*
Y333909D03*
Y341709D03*
X288139D03*
X291519Y328060D03*
X264179Y339760D03*
X267859Y341709D03*
Y333909D03*
X281379Y353409D03*
X277999Y351460D03*
X281379Y349509D03*
X277999Y359260D03*
Y355360D03*
X284759Y347560D03*
X271239D03*
X264179D03*
X271239Y351460D03*
X264179D03*
X288139Y345609D03*
X274619Y349509D03*
Y357309D03*
Y353409D03*
X277999Y347560D03*
X274619Y345609D03*
Y361209D03*
X281379Y345609D03*
X284759Y351460D03*
X264179Y355360D03*
X267559Y361209D03*
X267859Y353409D03*
Y349509D03*
X271239Y355360D03*
X267859Y345609D03*
X271239Y343660D03*
X291519D03*
X277999D03*
X284759D03*
X264179D03*
X321938Y333909D03*
Y326110D03*
X311798Y331960D03*
Y328060D03*
X325318Y331960D03*
Y328060D03*
X315178Y333909D03*
Y326110D03*
X318558Y331960D03*
Y324160D03*
X335458Y333909D03*
X298279Y339760D03*
X301659Y341709D03*
X318558Y335860D03*
Y328060D03*
X301659Y333909D03*
X305039Y335860D03*
X338838D03*
X332078D03*
X298279D03*
X305039Y339760D03*
X345598Y324160D03*
X342218Y333909D03*
Y326110D03*
Y330009D03*
Y322209D03*
X348978Y333909D03*
X352357Y335860D03*
X345598Y328060D03*
X338838Y331960D03*
X335458Y330009D03*
X345598Y331960D03*
Y335860D03*
X308418Y326110D03*
X332078Y331960D03*
X318558Y320260D03*
X325318Y324160D03*
X328698Y333909D03*
Y326110D03*
Y330009D03*
X321938Y337809D03*
Y330009D03*
X305039Y328060D03*
X321938Y322209D03*
X315178D03*
X308418Y330009D03*
X311798Y324160D03*
X298279Y331960D03*
Y328060D03*
X305039Y331960D03*
X308418Y337809D03*
X301659Y330009D03*
X315178D03*
X301659Y337809D03*
X325318Y335860D03*
X308418Y341709D03*
Y333909D03*
X294899Y337809D03*
Y341709D03*
Y322209D03*
Y333909D03*
X301659Y345609D03*
X308418D03*
X305039Y343660D03*
X298279D03*
X294899Y345609D03*
X443993Y381947D03*
Y389747D03*
X440613Y383896D03*
Y387796D03*
X450753Y381947D03*
Y389747D03*
X447373Y383896D03*
Y391696D03*
Y379996D03*
Y387796D03*
X423714Y389747D03*
Y393647D03*
X433854Y383896D03*
Y387796D03*
X423714Y378047D03*
Y381947D03*
X430474D03*
Y389747D03*
X427094Y383896D03*
Y391696D03*
Y379996D03*
Y387796D03*
Y364396D03*
X423714Y370247D03*
X437233Y366347D03*
Y370247D03*
X423714Y358547D03*
Y366347D03*
X433854Y364396D03*
Y372197D03*
X450753Y370247D03*
Y374146D03*
X443993Y362447D03*
X440613Y356596D03*
Y360496D03*
X450753Y362447D03*
X430474Y366347D03*
X447373Y356596D03*
X430474Y370247D03*
X447373Y364396D03*
X430474Y362447D03*
Y374146D03*
X447373Y360496D03*
X430474Y358547D03*
X433854Y356596D03*
X437233Y378047D03*
X440613Y376096D03*
X443993Y374147D03*
Y370247D03*
X359117Y386560D03*
Y374860D03*
Y363160D03*
Y351460D03*
X357987Y402800D03*
X392916Y355360D03*
X396296Y357309D03*
X389537D03*
X372637Y390460D03*
X396296Y384609D03*
X372637Y386560D03*
X392916D03*
X389537Y384609D03*
X399676Y390460D03*
X376017Y372909D03*
X369257Y384609D03*
X396296Y380709D03*
X369257Y372909D03*
X362497D03*
X372637Y378760D03*
X362497Y380709D03*
X372637Y374860D03*
X365877D03*
X376017Y380709D03*
X365877Y378760D03*
X382777Y384609D03*
X386157Y374860D03*
X399676Y378760D03*
X396296Y369010D03*
X386157Y386560D03*
X389537Y372909D03*
X403056Y380709D03*
X399676Y374860D03*
X379397Y386560D03*
X369257Y380709D03*
X382777D03*
Y372909D03*
X379397Y378760D03*
Y374860D03*
X392916Y378760D03*
X362497Y384609D03*
X359117Y378760D03*
X386157D03*
X392916Y374860D03*
X389537Y380709D03*
X396296Y372909D03*
X376017Y384609D03*
X379397Y367060D03*
X365877Y355360D03*
X403056Y361209D03*
X369257Y369010D03*
X362497D03*
X369257Y361209D03*
X362497D03*
X372637Y367060D03*
X365877D03*
X372637Y363160D03*
X365877D03*
X382777Y369010D03*
X389537Y361209D03*
X399676Y367060D03*
Y363160D03*
X382777Y361209D03*
X392916Y367060D03*
X403056Y372909D03*
Y369010D03*
X376017Y361209D03*
X369257Y357309D03*
X376017D03*
X386157Y367060D03*
X372637Y355360D03*
X379397Y363160D03*
X399676Y359260D03*
X359117Y355360D03*
X362497Y357309D03*
X359117Y367060D03*
X386157Y363160D03*
X392916D03*
X389537Y369010D03*
X396296Y361209D03*
X376017Y369010D03*
X379397Y370959D03*
X372637D03*
X365877D03*
X359117D03*
X386157D03*
X362497Y353409D03*
X376017D03*
X369257D03*
X389537Y365109D03*
X382777D03*
X369257D03*
X362497D03*
X376017D03*
X390657Y394359D03*
X391787Y402800D03*
X369257Y392410D03*
X362497D03*
X379397Y382660D03*
X372637D03*
X365877D03*
X359117D03*
X379397Y390460D03*
X378267Y402800D03*
X376017Y392410D03*
X386157Y382660D03*
X392916Y370959D03*
X399676D03*
X396296Y365109D03*
X403056D03*
Y357309D03*
X392916Y382660D03*
Y390460D03*
X399676Y382660D03*
X406568Y402471D03*
X403056Y392410D03*
X411431Y359351D03*
X403056Y353409D03*
X399676Y355360D03*
X365877Y351460D03*
X372637D03*
X379397D03*
X362497Y349509D03*
X382777Y353409D03*
X386157Y355360D03*
X403056Y396309D03*
X411086Y394359D03*
Y390460D03*
X399676Y386560D03*
X411086D03*
Y382660D03*
Y378760D03*
X398546Y402900D03*
X382777Y357309D03*
X379397Y355360D03*
X402892Y400400D03*
X359117Y347560D03*
X294899Y376809D03*
Y380709D03*
Y388509D03*
Y392410D03*
Y361209D03*
Y365109D03*
Y357309D03*
Y400209D03*
X332078Y343660D03*
X338838D03*
X355737Y345609D03*
X352357Y343660D03*
X342218Y384609D03*
X341892Y396301D03*
X345598Y386560D03*
X298279Y374860D03*
Y382660D03*
X308418Y376809D03*
Y380709D03*
X305039Y374860D03*
Y382660D03*
X301659Y376809D03*
X328698Y353409D03*
X301659Y384609D03*
X328698Y361209D03*
X301659Y372909D03*
X328698Y349509D03*
X301659Y380709D03*
X328698Y357309D03*
X325318Y351460D03*
Y359260D03*
X335458Y353409D03*
Y357309D03*
X321938Y353409D03*
Y357309D03*
X332078Y351460D03*
Y359260D03*
X348978Y388509D03*
X342218Y380709D03*
X351192Y402800D03*
X345598Y378760D03*
X348978Y380709D03*
X345598Y367060D03*
X348978Y372909D03*
X342218D03*
X338838Y374860D03*
Y370959D03*
Y378760D03*
X352357D03*
Y374860D03*
X355737Y380709D03*
Y372909D03*
X348978Y369010D03*
X352357Y367060D03*
X355737Y384609D03*
X345598Y355360D03*
X348978Y357309D03*
X345598Y351460D03*
X348978Y361209D03*
X345598Y363160D03*
X342218Y357309D03*
Y369010D03*
Y361209D03*
X301659Y365109D03*
X298279Y367060D03*
X305039Y355360D03*
X301659Y353409D03*
X318558Y363160D03*
X311798Y367060D03*
X321938Y372909D03*
X318558Y374860D03*
X315178Y361209D03*
X311798Y363160D03*
X321938Y369010D03*
X315178Y372909D03*
X305039Y359260D03*
X298279Y355360D03*
X301659Y361209D03*
X318558Y367060D03*
X311798Y370959D03*
X335458Y345609D03*
X305039Y363160D03*
X321938Y365109D03*
X298279Y359260D03*
X315178Y369010D03*
X352357Y351460D03*
Y363160D03*
X355737Y361209D03*
Y369010D03*
X352357Y355360D03*
X355737Y357309D03*
X345598Y370959D03*
X355737Y353409D03*
X348978D03*
X342218Y365109D03*
Y353409D03*
X338838Y367060D03*
X348978Y365109D03*
X355737D03*
X352357Y370959D03*
X338838Y382660D03*
X345598D03*
X352357D03*
X348978Y392410D03*
X355737D03*
X315178Y353409D03*
X348978Y345609D03*
X311798Y355360D03*
Y351460D03*
X342218Y349509D03*
X345598Y347560D03*
X315178Y384609D03*
X348978D03*
X315178Y380709D03*
X335458Y376809D03*
X332078Y374860D03*
X345598D03*
X328698Y372909D03*
X332078Y370959D03*
X328698Y369010D03*
X335458D03*
X332078Y367060D03*
X335458Y365109D03*
X338838Y363160D03*
X352357Y347560D03*
X288139Y372909D03*
X281379Y369010D03*
Y380709D03*
X277999Y378760D03*
X288139Y369010D03*
X284759Y367060D03*
Y378760D03*
X277999Y374860D03*
X284759D03*
X277999Y370959D03*
X288139Y376809D03*
X281379Y372909D03*
X284759Y386560D03*
Y394359D03*
X281379Y388509D03*
Y392410D03*
X291519Y386560D03*
Y394359D03*
X288139Y388509D03*
Y396309D03*
Y384609D03*
Y392410D03*
X274619Y400209D03*
X281379D03*
X271239Y394359D03*
X267859Y392410D03*
X271239Y398260D03*
X277999D03*
X274619Y396309D03*
X415634Y216196D03*
Y208397D03*
Y212296D03*
Y204496D03*
Y231797D03*
Y227896D03*
Y223996D03*
Y235696D03*
Y247396D03*
Y220096D03*
X459773Y218147D03*
X439493D03*
X463153Y216196D03*
X456393Y212296D03*
X462023Y198327D03*
X456393Y216196D03*
X458640Y200596D03*
X466533Y206446D03*
X459773Y214247D03*
X476672Y216196D03*
Y212296D03*
X473292Y214247D03*
X466533Y218147D03*
X475692Y199900D03*
X469912Y212296D03*
X469913Y216196D03*
X473292Y218147D03*
X455263Y198050D03*
X434983Y198931D03*
X439493Y210346D03*
X453013Y214247D03*
X436113Y216196D03*
X439493Y214247D03*
X442873Y216196D03*
X446253Y218147D03*
X429353Y212296D03*
X425974Y218147D03*
X432733D03*
X429354Y216196D03*
X432733Y214247D03*
X436113Y212296D03*
X422594Y216196D03*
X449633D03*
Y212296D03*
X453013Y218147D03*
X425974Y206446D03*
X446253D03*
X421464Y199583D03*
X441743Y199841D03*
X419214Y218147D03*
Y214247D03*
X459773Y253247D03*
X449633Y239596D03*
X429354D03*
X459773Y249347D03*
X449633Y235696D03*
X429354D03*
X459773Y257147D03*
X449633Y243496D03*
X429354D03*
X459773Y245447D03*
X449633Y231797D03*
X429354D03*
X473292Y253247D03*
Y249347D03*
X476672Y255196D03*
Y247396D03*
X463153Y255196D03*
Y247396D03*
X453013Y253247D03*
Y249347D03*
X466533Y253247D03*
Y249347D03*
X456393Y255196D03*
Y247396D03*
X453013Y241547D03*
Y233746D03*
X442873Y239596D03*
Y235696D03*
X456393Y239596D03*
Y235696D03*
X446253Y241547D03*
Y233746D03*
X432733Y241547D03*
Y233746D03*
X422594Y239596D03*
Y235696D03*
X436113Y239596D03*
Y235696D03*
X425974Y241547D03*
Y233746D03*
X469913Y239596D03*
Y235696D03*
Y243496D03*
Y231797D03*
X473292Y241547D03*
Y233746D03*
X463153Y239596D03*
Y235696D03*
X476672Y239596D03*
Y235696D03*
X466533Y241547D03*
Y233746D03*
X422594Y227896D03*
X425974Y225947D03*
X459773D03*
X439493D03*
X459773Y229847D03*
X439493D03*
X473292Y225947D03*
X476672Y227896D03*
X463153D03*
X453013Y225947D03*
X466533D03*
X456393Y227896D03*
X442873D03*
X432733Y225947D03*
X446253D03*
X436113Y227896D03*
X466533Y264947D03*
X469913Y270796D03*
X468783Y274997D03*
X466533Y257147D03*
X473292D03*
X469913Y255196D03*
X459773Y261047D03*
X456393Y259096D03*
Y262996D03*
X458643Y269146D03*
X462023Y271097D03*
X477792Y272747D03*
X463153Y259096D03*
X476672D03*
X463153Y223996D03*
Y231797D03*
Y251296D03*
Y243496D03*
X476672Y231797D03*
X456393D03*
Y223996D03*
X459773Y237647D03*
Y241547D03*
Y233746D03*
X456393Y251296D03*
Y243496D03*
X466533Y237647D03*
X473292D03*
X466533Y229847D03*
X469913Y227896D03*
X473292Y229847D03*
X469913Y223996D03*
Y247396D03*
X476672Y251296D03*
Y243496D03*
Y223996D03*
X473292Y245447D03*
X466533D03*
X469913Y251296D03*
X453013Y261047D03*
Y257147D03*
X442873Y255196D03*
X446253Y257147D03*
X449633Y259096D03*
Y255196D03*
X439493Y253247D03*
X432733Y237647D03*
X425974D03*
X442873Y223996D03*
Y231797D03*
X439493Y233746D03*
X425974Y229847D03*
X432733D03*
X446253D03*
X429354Y227896D03*
Y223996D03*
X436113D03*
X439493Y241547D03*
X436113Y231797D03*
X422594D03*
Y223996D03*
X446253Y237647D03*
X439493D03*
X432733Y245447D03*
X446253D03*
X422594Y251296D03*
X429354Y247396D03*
X436113Y251296D03*
X432733Y249347D03*
X425974D03*
Y245447D03*
X422594Y243496D03*
X442873D03*
X436113D03*
X449633Y223996D03*
Y227896D03*
Y247396D03*
Y251296D03*
X453013Y237647D03*
Y229847D03*
Y245447D03*
X429354Y251296D03*
X422594Y220096D03*
X425974Y222047D03*
X459773D03*
X439493D03*
X473292D03*
X476672Y220096D03*
X463153D03*
X453013Y222047D03*
X466533D03*
X456393Y220096D03*
X442873D03*
X432733Y222047D03*
X446253D03*
X436113Y220096D03*
X469913D03*
X449633D03*
X429354D03*
X419214Y229847D03*
Y225947D03*
Y241547D03*
Y237647D03*
Y233746D03*
Y249347D03*
Y222047D03*
X477792Y288347D03*
Y303947D03*
X535251Y216196D03*
X528491Y212296D03*
X535251Y208397D03*
X494692Y216196D03*
Y212296D03*
X501452Y216196D03*
X504832Y218147D03*
X511592Y214247D03*
X514972Y216196D03*
X518352Y210345D03*
Y214247D03*
X525111D03*
X531871D03*
Y210346D03*
X535251Y212296D03*
X538631Y218147D03*
X498072Y214247D03*
Y218147D03*
X504832Y214247D03*
X508212Y216196D03*
X514972Y212296D03*
Y208397D03*
X521731Y212296D03*
X525111Y210346D03*
X483432Y216196D03*
X521731Y208397D03*
X531871Y206447D03*
X525111D03*
X535251Y204496D03*
X528491Y216196D03*
X525111Y218147D03*
X528491Y208397D03*
X538631Y206447D03*
Y214247D03*
Y210346D03*
X518352Y206445D03*
Y218147D03*
X508212Y212296D03*
X486812Y210346D03*
X501452Y212296D03*
X498350Y209900D03*
X486812Y218147D03*
Y214247D03*
X511592Y218147D03*
Y210346D03*
Y206447D03*
X480052Y218147D03*
Y206447D03*
Y214247D03*
X513857Y260881D03*
X518352Y249347D03*
Y268847D03*
X528491Y259096D03*
X525111Y257147D03*
X521731Y227896D03*
X518352Y225947D03*
X525111D03*
X528491Y231797D03*
X531871Y233746D03*
Y225947D03*
X538631Y229847D03*
Y233746D03*
X501452Y243496D03*
X494692Y239596D03*
X501452D03*
X494692Y231797D03*
X501452D03*
Y227896D03*
X504832Y237647D03*
X511592Y233746D03*
X508212Y227896D03*
X514972Y231797D03*
X525111Y229847D03*
X521731Y223996D03*
X525111Y233746D03*
X531871Y229847D03*
X535251Y227896D03*
Y231797D03*
X498072Y241547D03*
Y237647D03*
X501452Y235696D03*
X494692Y227896D03*
X504832Y233746D03*
X498072Y229847D03*
X508212Y235696D03*
X511592Y237647D03*
Y225947D03*
Y229847D03*
X535251Y262996D03*
X538631Y253247D03*
Y245447D03*
X535251Y274696D03*
Y270796D03*
X538631Y268847D03*
Y264947D03*
X531871Y245447D03*
X538631Y261047D03*
Y241547D03*
X531871Y280547D03*
X535251Y278596D03*
X538631Y276646D03*
Y280547D03*
X531871Y272747D03*
X538631D03*
X535251Y243496D03*
X508212Y266896D03*
X525111Y245447D03*
Y249347D03*
X521731Y239596D03*
X518352Y237647D03*
Y241547D03*
X525111Y268847D03*
X511592Y253247D03*
X528491Y255196D03*
X531871Y257147D03*
X518352Y245447D03*
X525111Y272747D03*
X483432Y255196D03*
Y247396D03*
X486812Y253247D03*
Y249347D03*
X483432Y231797D03*
Y227896D03*
X514972Y243496D03*
X511592Y245447D03*
X498072Y264947D03*
X521731Y251296D03*
Y255196D03*
X518352Y272747D03*
X514972Y251296D03*
X525111Y261047D03*
X518352D03*
X538631Y257147D03*
X521731Y274696D03*
Y259096D03*
Y266896D03*
X525111Y280547D03*
X535251Y266896D03*
X531871Y276646D03*
Y268847D03*
X528491Y274696D03*
X518352Y253247D03*
X525111D03*
X514972Y278596D03*
Y270796D03*
X531871Y261047D03*
X535251Y259096D03*
X514972Y223996D03*
Y239596D03*
Y235696D03*
Y227896D03*
Y247396D03*
X525111Y237647D03*
X535251Y239596D03*
Y251296D03*
Y247396D03*
X528491Y235696D03*
Y227896D03*
X535251Y235696D03*
X538631Y249347D03*
X528491Y243496D03*
Y247396D03*
X538631Y237647D03*
Y225947D03*
X521731Y247396D03*
Y235696D03*
Y231797D03*
X518352Y229847D03*
X494692Y270796D03*
X508212D03*
X483432Y259096D03*
X501452D03*
Y266896D03*
X494692Y278596D03*
X487932Y274696D03*
Y278596D03*
X504832Y253247D03*
X486812Y257147D03*
X494692Y255196D03*
X484552Y268847D03*
X508212Y278596D03*
X501452Y274696D03*
X494692Y251296D03*
X483432Y223996D03*
Y235696D03*
X508212Y223996D03*
Y231797D03*
X501452Y223996D03*
X504832Y245447D03*
X483432Y243496D03*
X494692D03*
X486812Y241547D03*
X504832D03*
X486812Y237647D03*
X498072Y225947D03*
X486812D03*
X504832Y229847D03*
X494692Y235696D03*
X486812Y229847D03*
Y233746D03*
X498072D03*
X508212Y239596D03*
X501452Y247396D03*
X483432Y251296D03*
X494692Y247396D03*
X486812Y245447D03*
X511592Y249347D03*
Y241547D03*
X535251Y220096D03*
X504832Y222047D03*
X494692Y220096D03*
X501452D03*
X525111Y222047D03*
X483432Y220096D03*
X531871Y222047D03*
X528491Y220096D03*
X538631Y222047D03*
X521731Y220096D03*
X508212D03*
X486812Y222047D03*
X498072D03*
X480052Y253247D03*
Y249347D03*
Y257147D03*
Y245447D03*
Y229847D03*
Y225947D03*
Y261047D03*
X481172Y278596D03*
Y274696D03*
X480052Y241547D03*
Y233746D03*
Y237647D03*
Y222047D03*
X535251Y286396D03*
X531871Y284447D03*
Y319547D03*
X528491Y317596D03*
X525111Y315647D03*
X518352Y327347D03*
X521731Y325396D03*
Y317596D03*
X518352Y315647D03*
Y323446D03*
Y319547D03*
X514972Y325396D03*
Y329296D03*
Y317596D03*
Y321496D03*
X535251Y309797D03*
X531871Y307847D03*
Y311747D03*
X535251Y301996D03*
X531871Y303947D03*
X538631Y284447D03*
Y288347D03*
Y292245D03*
X535251Y294196D03*
X528491Y298096D03*
Y286396D03*
X521731Y301996D03*
X531871Y300047D03*
X525111D03*
X528491Y294196D03*
X531871Y292245D03*
Y288347D03*
X525111Y284447D03*
X514972Y294196D03*
Y286396D03*
Y290296D03*
Y301996D03*
X535251Y290296D03*
X538631Y311747D03*
X511592Y319547D03*
X491312Y331247D03*
X498072Y327347D03*
X504832Y323446D03*
X498072Y319547D03*
X504832Y315647D03*
X508212Y313696D03*
X511592Y323446D03*
Y315647D03*
Y327347D03*
X491312Y339047D03*
X508212Y325396D03*
Y317596D03*
X484552Y323446D03*
X504832Y319547D03*
X487932Y317596D03*
X508212Y329296D03*
X501452Y298096D03*
X494692Y286396D03*
X484552Y292245D03*
Y300047D03*
X498072Y303947D03*
X487932Y309797D03*
X494692D03*
X511592Y284447D03*
Y307847D03*
X508212Y294196D03*
Y290296D03*
X491312Y300047D03*
Y292245D03*
X501452Y290296D03*
X494692Y294196D03*
X504832Y307847D03*
X528491Y282496D03*
X535251D03*
X487932D03*
X501452D03*
X481172Y329296D03*
Y290296D03*
Y301996D03*
X484552Y346847D03*
X481172Y352696D03*
Y344896D03*
X548771Y216196D03*
X545391Y214247D03*
Y218147D03*
X552151D03*
X545391Y210346D03*
X547800Y201400D03*
X552151Y214247D03*
X548771Y212296D03*
X557000Y206800D03*
X555531Y216196D03*
X542011Y212296D03*
Y216196D03*
X548771Y223996D03*
X555531D03*
Y227896D03*
Y255196D03*
X558911Y253247D03*
X555531Y251296D03*
X558911Y241547D03*
X562630Y227896D03*
X552151Y280547D03*
X548771Y274696D03*
X552151Y272747D03*
X555531Y270796D03*
X552151Y264947D03*
X555531Y262996D03*
X558911Y225947D03*
Y257147D03*
Y249347D03*
X552151Y253247D03*
X555531Y243496D03*
X562640Y231735D03*
X555531Y278596D03*
X552151Y276646D03*
Y268847D03*
X558911D03*
X555531Y266896D03*
Y259096D03*
X562616Y223996D03*
X548771Y231797D03*
X545391Y229847D03*
Y261047D03*
Y257147D03*
Y249347D03*
X548771Y247396D03*
X545391Y241547D03*
X548771Y259096D03*
X545391Y253247D03*
Y245447D03*
Y268847D03*
Y264947D03*
Y280547D03*
Y272747D03*
X552151Y261047D03*
X555531Y274696D03*
X558911Y272747D03*
X548771Y278596D03*
X559211Y280547D03*
X563800Y275900D03*
X558911Y264947D03*
X548771Y266896D03*
Y255196D03*
X562591D03*
X552151Y257147D03*
X548771Y243496D03*
X562591Y251296D03*
X555531Y247396D03*
X552151Y249347D03*
X548771Y239596D03*
X552151Y241547D03*
X545391Y233746D03*
Y225947D03*
X564084Y235685D03*
X552151Y229847D03*
X558911D03*
X548771Y235696D03*
X552151Y233746D03*
Y225947D03*
Y222047D03*
X548771Y220096D03*
X555531D03*
X545391Y222047D03*
X562591Y220096D03*
X558911Y222047D03*
X542011Y231797D03*
Y235696D03*
Y227896D03*
Y259096D03*
Y278596D03*
Y262996D03*
Y255196D03*
Y251296D03*
Y243496D03*
Y266896D03*
Y274696D03*
Y247396D03*
Y239596D03*
Y220096D03*
X552151Y292245D03*
X555831Y294196D03*
X560884Y290296D03*
X545391Y284447D03*
Y303947D03*
Y300047D03*
Y292245D03*
Y288347D03*
Y296147D03*
X552151D03*
Y288347D03*
X548771Y286396D03*
X552151Y284447D03*
X555531Y282496D03*
X542011Y290296D03*
Y286396D03*
Y298096D03*
Y294196D03*
Y282496D03*
X716557Y198557D03*
X720369Y205199D03*
X718300Y227400D03*
X688388Y231280D03*
X688643Y225980D03*
X722050Y221150D03*
X632500Y238500D03*
Y235000D03*
X632532Y241717D03*
X633308Y263808D03*
X627529Y280441D03*
X618279Y251393D03*
X624500Y240500D03*
X542011Y368296D03*
Y360496D03*
Y348796D03*
Y376096D03*
X558911Y342947D03*
X562591Y344896D03*
X552151Y350747D03*
X559212Y370247D03*
X548771Y368296D03*
X562591Y352696D03*
X563200Y356596D03*
X545391Y354647D03*
Y346847D03*
Y366347D03*
Y358547D03*
X559212Y374146D03*
X555531Y387797D03*
X559212Y381947D03*
X552151Y378047D03*
X545391Y397546D03*
Y385847D03*
X542011Y321496D03*
X555831Y309797D03*
Y305896D03*
X548771Y313696D03*
X561971Y317320D03*
X548771Y325396D03*
X558911Y335147D03*
X555531Y333196D03*
X562591D03*
X548771Y340996D03*
X561966Y325502D03*
X559211Y319547D03*
X552151Y323446D03*
X545391Y319547D03*
Y335147D03*
Y331247D03*
Y315647D03*
X484552Y405347D03*
X481172Y372197D03*
Y391696D03*
Y395596D03*
Y379996D03*
Y383896D03*
Y387796D03*
Y364396D03*
Y368296D03*
Y376096D03*
X504832Y342947D03*
X501452Y344896D03*
X498072Y342947D03*
X518352D03*
X525111D03*
X491312Y370247D03*
X498072Y366347D03*
X494692Y372197D03*
X504832Y366347D03*
X501452Y368296D03*
X487932D03*
X498072Y362447D03*
X491312D03*
X494692Y360496D03*
X504832Y354647D03*
X491312Y366347D03*
X487932Y372197D03*
X484552Y370247D03*
Y366347D03*
X487932Y364396D03*
X494692D03*
X501452D03*
X498072Y350747D03*
Y346847D03*
X501452Y360496D03*
X498072Y358547D03*
Y354647D03*
X508212Y352696D03*
Y360496D03*
X504832Y346847D03*
Y358547D03*
X501452Y356596D03*
Y348796D03*
Y352696D03*
X511592Y370247D03*
X484552Y393647D03*
Y385847D03*
X498072Y393647D03*
X494692Y391696D03*
X491312Y385847D03*
X498072D03*
X508212Y387796D03*
X501452Y391696D03*
Y395597D03*
X491312Y389747D03*
X504832Y381947D03*
Y378047D03*
X501452Y379996D03*
X511592Y378047D03*
Y397546D03*
X491312Y378047D03*
X484552D03*
X487932Y376096D03*
X491312Y381947D03*
Y374146D03*
X498072Y397546D03*
X487932Y403396D03*
Y399496D03*
X491312Y397546D03*
X487932Y395597D03*
X514972Y372197D03*
Y356596D03*
X521731Y360496D03*
Y356596D03*
Y348796D03*
X518352Y362447D03*
X521731Y372197D03*
X518352Y370247D03*
X525111Y354647D03*
X531871Y346847D03*
X535251Y356596D03*
X538631Y366347D03*
X528491Y364396D03*
X514972Y403396D03*
Y379996D03*
X531871Y374146D03*
X521731Y399496D03*
X518352Y397546D03*
Y389747D03*
X535251Y383896D03*
X525111Y381947D03*
X538631Y393647D03*
Y378047D03*
X528491Y403396D03*
X531871Y401447D03*
Y389747D03*
X525111Y393647D03*
X484552Y381947D03*
Y389747D03*
X494692Y395597D03*
Y399496D03*
X491312Y401447D03*
Y393647D03*
X487932Y379996D03*
Y391696D03*
Y383896D03*
Y387796D03*
X484552Y374146D03*
X511592Y339047D03*
Y335147D03*
X508212Y337096D03*
X504832Y335147D03*
Y339047D03*
X501452Y340996D03*
X514972Y337096D03*
X518352Y339047D03*
X531871Y335147D03*
X525111D03*
X528491Y337096D03*
X535251Y329296D03*
X538631Y335147D03*
Y339047D03*
X464273Y405347D03*
X477792Y362447D03*
X457513D03*
X464273Y366347D03*
X474413Y372197D03*
X471033Y366347D03*
X467653Y372197D03*
X474413Y364396D03*
X464273Y350747D03*
X471033D03*
Y358547D03*
X464273D03*
X467653Y368296D03*
Y348796D03*
X460893Y372197D03*
Y364396D03*
Y352696D03*
X457513Y354647D03*
Y358547D03*
Y346847D03*
X477792Y389747D03*
X457513D03*
X471033Y393647D03*
X460893Y395595D03*
X464273Y401447D03*
X471033D03*
X460893Y391696D03*
X457513Y385847D03*
Y381947D03*
X460893Y379996D03*
X477792Y381947D03*
X474413Y391696D03*
X464273Y385847D03*
X471033D03*
X464273Y393647D03*
X474413Y379996D03*
X471033Y378047D03*
X467653Y376096D03*
X464273Y378047D03*
Y397546D03*
X477792Y385847D03*
X464273Y381947D03*
Y389747D03*
X474413Y383896D03*
Y387796D03*
X460893Y383896D03*
Y387796D03*
X471033Y381947D03*
Y389747D03*
X467653Y379996D03*
Y391696D03*
Y383896D03*
Y387796D03*
X474413Y368296D03*
Y376096D03*
X471033Y370247D03*
Y374146D03*
X477792Y370247D03*
Y378047D03*
Y366347D03*
Y374146D03*
X464273Y370247D03*
Y374146D03*
X460893Y368296D03*
Y376096D03*
X464273Y354647D03*
Y362447D03*
X474413Y360496D03*
X460893Y356596D03*
Y360496D03*
X471033Y354647D03*
Y362447D03*
X457513Y370247D03*
X467653Y356596D03*
X457513Y378047D03*
X467653Y364396D03*
X457513Y366347D03*
X467653Y352696D03*
X457513Y374146D03*
X467653Y360496D03*
X458643Y338746D03*
X467653Y340996D03*
X469913Y321496D03*
X463671Y319386D03*
X662238Y296146D03*
X654600Y296000D03*
X658900Y339150D03*
X646700Y308850D03*
X637561Y317000D03*
X637143Y322000D03*
X664267Y292668D03*
X646520Y297400D03*
X648900Y336600D03*
X658500Y284500D03*
X637681Y337390D03*
X654194Y351206D03*
X649194D03*
X664194D03*
X659694D03*
X679300Y261700D03*
X710675Y263425D03*
X710700Y260200D03*
X667700Y275600D03*
X677800Y254100D03*
X689960Y260500D03*
X704090Y256080D03*
X715200Y258900D03*
X690130Y277380D03*
X700800Y261300D03*
X704500Y252500D03*
X700400Y257200D03*
X697255Y267098D03*
X674469Y287375D03*
X688924Y288147D03*
X688100Y308600D03*
X674700Y339200D03*
X705800Y301600D03*
X697352Y330500D03*
Y335500D03*
X667900Y339000D03*
X670800Y292600D03*
X686600Y335600D03*
X695000Y289500D03*
X686140Y298260D03*
X724000Y291700D03*
X697521Y320500D03*
Y325500D03*
X704404Y310875D03*
Y315875D03*
X697120Y300349D03*
Y305349D03*
X711900Y327700D03*
X712400Y324400D03*
X706800Y281900D03*
X710272Y281911D03*
X695700Y346300D03*
X684194Y351206D03*
X679194D03*
X674194D03*
X669194D03*
X683417Y364972D03*
X674194Y358467D03*
X730000Y254675D03*
X736000Y303400D03*
X737912Y315500D03*
X729405Y290725D03*
X737750Y298894D03*
X732000Y380000D03*
X805600Y403900D03*
X797000Y404700D03*
X1323500Y68000D03*
X1321841Y63000D03*
X1323500Y71500D03*
X1298422Y74000D03*
X1327168Y61483D03*
X1304685Y78827D03*
X1298754Y83233D03*
X1309700Y83300D03*
X1304940Y32350D03*
X1220953Y67900D03*
X1241732Y36049D03*
X1248425D03*
X1235039D03*
X1241732Y46914D03*
X1238385Y67749D03*
X1251771Y65699D03*
X1248425D03*
Y46957D03*
X1245078Y67749D03*
X1241732Y84714D03*
Y73849D03*
X1248425Y84757D03*
Y73849D03*
X1235039Y84714D03*
Y73849D03*
Y46914D03*
X1268111Y58040D03*
X1220953Y-7700D03*
Y30100D03*
X1238385Y29949D03*
X1245078D03*
X1251771Y16999D03*
X1248425Y27899D03*
X1269700Y13078D03*
X1241732Y-1751D03*
X1238385Y-7851D03*
X1241732Y9114D03*
X1248425Y-1751D03*
Y-9901D03*
X1251771D03*
X1245078Y-7851D03*
X1248425Y9157D03*
X1269800Y-5822D03*
X1235039Y9114D03*
Y-1751D03*
X1161417Y36049D03*
X1168110D03*
X1174803Y35999D03*
X1181496Y36049D03*
X1204921D03*
X1198228D03*
X1218307D03*
X1211614Y35999D03*
X1168110Y46914D03*
X1161417D03*
X1174803D03*
X1177763Y67749D03*
X1171456D03*
X1164763D03*
X1174803Y84714D03*
X1168110D03*
Y73849D03*
X1161417D03*
X1174803Y73799D03*
X1161417Y84714D03*
X1181346Y46914D03*
X1198228D03*
X1204921D03*
X1184142Y67900D03*
X1201574Y67749D03*
X1211614Y46914D03*
X1218157D03*
X1211614Y73799D03*
X1218307Y73849D03*
X1218157Y84714D03*
X1211614D03*
X1214574Y67749D03*
X1208267D03*
X1181346Y84714D03*
X1181496Y73849D03*
X1198228D03*
X1204921D03*
X1198228Y84714D03*
X1204921D03*
X1161417Y9114D03*
X1168110D03*
X1174803D03*
X1171456Y-7851D03*
X1164763D03*
X1177763D03*
X1168110Y-1751D03*
X1161417D03*
X1174803Y-1801D03*
X1164763Y29949D03*
X1171456D03*
X1177763D03*
X1181496Y-1751D03*
X1181346Y9114D03*
X1204921D03*
X1198228D03*
X1184142Y-7700D03*
X1201574Y-7851D03*
X1204921Y-1751D03*
X1198228D03*
X1218307D03*
X1211614Y-1801D03*
X1214574Y-7851D03*
X1208267D03*
X1218157Y9114D03*
X1211614D03*
X1184142Y30100D03*
X1201574Y29949D03*
X1208267D03*
X1214574D03*
X1098100Y51000D03*
X1098300Y89900D03*
X1107874Y36049D03*
X1137992Y35999D03*
X1144685Y36049D03*
X1131299D03*
X1124606D03*
X1110520Y67900D03*
X1104141Y67749D03*
X1107724Y46914D03*
X1107874Y73849D03*
X1107724Y84714D03*
X1127952Y67749D03*
X1137992Y46914D03*
X1144535D03*
X1134645Y67749D03*
X1140952D03*
X1147331Y67900D03*
X1131299Y46914D03*
X1124606D03*
X1131299Y73849D03*
X1124606D03*
X1131299Y84714D03*
X1124606D03*
X1137992Y73799D03*
X1144535Y84714D03*
X1137992D03*
X1144685Y73849D03*
X1097352Y-7180D03*
X1097900Y31900D03*
X1097834Y28100D03*
X1104141Y-7851D03*
X1110520Y-7700D03*
X1107874Y-1751D03*
X1101181Y-1801D03*
X1107724Y9114D03*
X1101181D03*
X1110520Y30100D03*
X1104141Y29949D03*
X1131299Y9114D03*
X1124606D03*
X1137992D03*
X1144535D03*
X1127952Y-7851D03*
X1124606Y-1751D03*
X1131299D03*
X1134645Y-7851D03*
X1147331Y-7700D03*
X1140952Y-7851D03*
X1137992Y-1801D03*
X1144685Y-1751D03*
X1147331Y30100D03*
X1134645Y29949D03*
X1140952D03*
X1127952D03*
X1035900Y98800D03*
X1050983Y103116D03*
X1064427D03*
X1077304Y103100D03*
X1057734Y103116D03*
X1071120D03*
X1050985Y35957D03*
X1087797D03*
X1094490D03*
X1054331D03*
X1077757D03*
X1064371D03*
X1084450D03*
X1044292D03*
X1061024D03*
X1057792Y51000D03*
Y69900D03*
X1083116Y51000D03*
X1070976D03*
X1083116Y69900D03*
X1070976D03*
X1044100Y54700D03*
X1071064Y46922D03*
Y73757D03*
X1054331Y65822D03*
X1050985Y73757D03*
X1087797D03*
X1064371Y65822D03*
X1094488D03*
X1054331Y73757D03*
X1077757D03*
X1064371D03*
X1071064Y65822D03*
X1084450Y73757D03*
X1087797Y65822D03*
X1054331Y54857D03*
X1050985Y46922D03*
X1087797D03*
X1064371Y54857D03*
X1081102Y54842D03*
X1094488Y54859D03*
Y46922D03*
X1047637Y54842D03*
X1054331Y46922D03*
X1077757D03*
X1064371D03*
X1071064Y54857D03*
X1057677Y54842D03*
X1084450Y46922D03*
X1074409Y54842D03*
X1087795Y54859D03*
X1061024Y73757D03*
Y46922D03*
X1043800Y-9700D03*
X1057792Y13200D03*
Y32100D03*
X1083116Y13200D03*
Y32100D03*
X1070976Y13200D03*
Y32100D03*
X1071062Y-1817D03*
X1071064Y9122D03*
X1054331Y28022D03*
X1064371D03*
X1094488D03*
X1071064D03*
X1087797D03*
X1054331Y17057D03*
X1050985Y9122D03*
X1087797D03*
X1064371Y17057D03*
X1081102Y17042D03*
X1094488Y17059D03*
Y9122D03*
X1054331D03*
X1077757D03*
X1064371D03*
X1071064Y17057D03*
X1057677Y17042D03*
X1084450Y9122D03*
X1074409Y17042D03*
X1087795Y17059D03*
X1061024Y9122D03*
X974015Y35957D03*
Y65814D03*
Y73757D03*
Y54857D03*
Y46914D03*
X977362Y35957D03*
X984055D03*
X1004134D03*
X997441D03*
X994094D03*
X987401D03*
X983900Y51000D03*
Y69900D03*
X1014350Y73000D03*
X1030400Y56500D03*
X1031600Y42900D03*
X977362Y73757D03*
X984055D03*
X980708Y65814D03*
X1004133Y65822D03*
X1004134Y73757D03*
X1000787Y65822D03*
X997441Y73757D03*
X994094D03*
Y65822D03*
X987401Y73757D03*
X990748Y65822D03*
X984054Y65814D03*
X977362Y46914D03*
X984054D03*
X980708Y54857D03*
X1004134D03*
X1004133Y46922D03*
X1000787Y54857D03*
X997441Y46922D03*
X994094D03*
Y54857D03*
X987401Y46914D03*
X990748Y54857D03*
X984055D03*
X974015Y28014D03*
Y17057D03*
Y9114D03*
X983900Y13200D03*
Y32100D03*
X1026700Y1700D03*
X980708Y28014D03*
X1004133Y28022D03*
X1000787D03*
X994094D03*
X990748D03*
X984054Y28014D03*
X977362Y9114D03*
X984054D03*
X980708Y17057D03*
X1004134D03*
X1004133Y9122D03*
X1000787Y17057D03*
X997441Y9122D03*
X994094D03*
Y17057D03*
X987401Y9114D03*
X990748Y17057D03*
X984055D03*
X913779Y36049D03*
Y46914D03*
Y73849D03*
Y84714D03*
X920472Y35999D03*
X927165Y36049D03*
X950590D03*
X943897D03*
X957283Y35957D03*
X960629D03*
X967322D03*
X923432Y67749D03*
X929811Y67900D03*
X917125Y67749D03*
X927015Y73849D03*
X920472Y73799D03*
Y84714D03*
Y46914D03*
X927015D03*
Y84714D03*
X957558Y50729D03*
X953936Y67749D03*
X950590Y46914D03*
X970800Y50860D03*
X947243Y67749D03*
X943897Y46914D03*
X970942Y69900D03*
X943897Y84714D03*
Y73849D03*
X950590D03*
Y84714D03*
X957774Y87394D03*
X957200Y73800D03*
X957283Y54857D03*
X970669Y65814D03*
X963976D03*
X970669Y54857D03*
X963976D03*
X960629Y46914D03*
X967322Y73757D03*
Y46914D03*
X913779Y-1751D03*
Y9114D03*
X923432Y-7851D03*
X929811Y-7700D03*
X917125Y-7851D03*
X927165Y-1751D03*
X920472Y-1801D03*
X927015Y9114D03*
X920472D03*
X923432Y29949D03*
X917125D03*
X929811Y30100D03*
X947243Y-7851D03*
X950590Y-1751D03*
X957283Y-1843D03*
X953936Y-7851D03*
X943897Y-1751D03*
Y9114D03*
X950590D03*
X957283Y9300D03*
X953936Y29949D03*
X957600Y13200D03*
X957700Y32100D03*
X970800Y13200D03*
X970942Y32100D03*
X947243Y29949D03*
X957765Y-7180D03*
X957283Y28014D03*
Y17057D03*
X970669Y28014D03*
X963976D03*
X970669Y17057D03*
X963976D03*
X960629Y9114D03*
X967322D03*
X849810Y67749D03*
X870275Y36049D03*
X876968D03*
X853543D03*
X883661Y35999D03*
X890354Y36049D03*
X907086D03*
X876968Y46914D03*
X873621Y67749D03*
X856189Y67900D03*
X853393Y46914D03*
X870275D03*
X876968Y84714D03*
Y73849D03*
X870275D03*
X853543D03*
X870275Y84714D03*
X853393D03*
X910432Y67749D03*
X893000Y67900D03*
X890204Y46914D03*
X886621Y67749D03*
X880314D03*
X883661Y46914D03*
Y73799D03*
X907086Y84714D03*
Y46914D03*
X890204Y84714D03*
X890354Y73849D03*
X907086D03*
X883661Y84714D03*
X849810Y-7851D03*
Y29949D03*
X870275Y9114D03*
X876968D03*
Y-1751D03*
X873621Y-7851D03*
X856189Y-7700D03*
X853543Y-1751D03*
X870275D03*
X853393Y9114D03*
X873621Y29949D03*
X856189Y30100D03*
X910432Y-7851D03*
X883661Y-1801D03*
X880314Y-7851D03*
X886621D03*
X907086Y-1751D03*
X890354D03*
X893000Y-7700D03*
X883661Y9114D03*
X907086D03*
X890204D03*
X910432Y29949D03*
X893000Y30100D03*
X886621Y29949D03*
X880314D03*
X810039Y35999D03*
X803346Y36049D03*
X816732D03*
X796653D03*
X846850Y35999D03*
X833464Y36049D03*
X840157D03*
X796653Y46914D03*
X816582D03*
X799999Y67749D03*
X812999D03*
X806692D03*
X803346Y46914D03*
X810039D03*
X816582Y73849D03*
X796653D03*
X810039Y73799D03*
X803346Y73849D03*
X816582Y84714D03*
X803346D03*
X810039D03*
X796653D03*
X819378Y67900D03*
X833464Y46914D03*
X840157D03*
X836810Y67749D03*
X843503D03*
X846850Y46914D03*
Y73799D03*
Y84714D03*
X840157Y73849D03*
X833464D03*
X840157Y84714D03*
X833464D03*
X803346Y-1751D03*
X810039Y-1801D03*
X812999Y-7851D03*
X806692D03*
X799999D03*
X816582Y9114D03*
X796653D03*
X810039D03*
X803346D03*
X816732Y-1751D03*
X796653D03*
X799999Y29949D03*
X806692D03*
X812999D03*
X833464Y9114D03*
X840157D03*
X819378Y-7700D03*
X843503Y-7851D03*
X836810D03*
X846850Y-1801D03*
X833464Y-1751D03*
X840157D03*
X846850Y9114D03*
X819378Y30100D03*
X836810Y29949D03*
X843503D03*
X779921Y35983D03*
X773228D03*
Y46914D03*
X779771D03*
X776188Y67749D03*
X769881Y66000D03*
X782567Y67900D03*
X769881Y54839D03*
X773228Y84714D03*
X779771D03*
X779921Y73849D03*
X773228Y73799D03*
X769881Y46957D03*
X755500Y8700D03*
X779771Y9114D03*
X773228D03*
Y-1801D03*
X779921Y-1751D03*
X776188Y-7851D03*
X769881Y-9901D03*
X782567Y-7700D03*
X769881Y27899D03*
X782567Y30100D03*
X769881Y16839D03*
X776188Y29949D03*
X760100Y17255D03*
X769881Y9157D03*
X1307600Y620100D03*
X1296295Y615596D03*
X1301384Y618119D03*
X1316100Y543400D03*
X1220953Y606700D03*
X1241732Y612649D03*
X1238385Y606549D03*
X1248425Y612649D03*
X1251771Y604499D03*
X1248425D03*
X1245078Y606549D03*
X1251771Y593599D03*
X1235039Y612649D03*
X1220953Y531100D03*
Y568900D03*
X1251771Y528899D03*
X1248425D03*
X1241732Y547914D03*
Y537049D03*
X1238385Y530949D03*
X1269800Y532978D03*
X1248425Y537049D03*
X1245078Y530949D03*
X1248425Y547957D03*
X1241732Y574849D03*
Y585714D03*
X1238385Y568749D03*
X1268500Y555800D03*
X1248425Y585757D03*
Y574849D03*
Y566699D03*
X1245078Y568749D03*
X1235039Y537049D03*
Y547914D03*
Y585714D03*
Y574849D03*
X1273200Y582200D03*
X1277200Y539100D03*
X1241732Y510114D03*
X1269000Y514700D03*
X1251771Y517999D03*
X1248425Y510157D03*
X1235039Y510114D03*
X1181496Y612649D03*
X1218307D03*
X1211614Y612599D03*
X1204921Y612649D03*
X1198228D03*
X1168110D03*
X1161417D03*
X1174803Y612599D03*
X1171456Y606549D03*
X1164763D03*
X1177763D03*
X1214574D03*
X1208267D03*
X1184142Y606700D03*
X1201574Y606549D03*
X1161417Y547914D03*
X1168110D03*
X1174803D03*
X1177763Y530949D03*
X1168110Y537049D03*
X1164763Y530949D03*
X1161417Y537049D03*
X1171456Y530949D03*
X1174803Y536999D03*
Y574799D03*
X1161417Y574849D03*
X1171456Y568749D03*
X1168110Y585714D03*
X1161417D03*
X1168110Y574849D03*
X1164763Y568749D03*
X1174803Y585714D03*
X1177763Y568749D03*
X1181496Y537049D03*
X1181346Y547914D03*
X1211614Y536999D03*
X1214574Y530949D03*
X1184142Y531100D03*
X1198228Y547914D03*
X1204921D03*
X1201574Y530949D03*
X1204921Y537049D03*
X1198228D03*
X1218307D03*
X1211614Y547914D03*
X1208267Y530949D03*
X1218157Y547914D03*
X1181346Y585714D03*
X1181496Y574849D03*
X1218157Y585714D03*
X1218307Y574849D03*
X1208267Y568749D03*
X1214574D03*
X1211614Y574799D03*
Y585714D03*
X1184142Y568900D03*
X1198228Y585714D03*
Y574849D03*
X1204921Y585714D03*
Y574849D03*
X1201574Y568749D03*
X1168110Y510114D03*
X1161417D03*
X1174803D03*
X1181346D03*
X1211614D03*
X1218157D03*
X1204921D03*
X1198228D03*
X1097352Y607220D03*
X1137992Y612599D03*
X1144685Y612649D03*
X1124606D03*
X1131299D03*
X1107874D03*
X1110520Y606700D03*
X1104141Y606549D03*
X1147331Y606700D03*
X1134645Y606549D03*
X1140952D03*
X1127952D03*
X1101181Y612599D03*
X1098300Y553100D03*
X1098118Y549843D03*
X1097899Y574773D03*
X1097834Y569200D03*
X1104141Y530949D03*
X1107724Y547914D03*
X1101181D03*
X1110520Y531100D03*
X1107874Y537049D03*
X1104141Y568749D03*
X1101181Y585714D03*
X1107724D03*
X1107874Y574849D03*
X1110520Y568900D03*
X1101181Y574799D03*
X1137992Y547914D03*
X1144535D03*
X1131299D03*
X1124606D03*
X1131299Y537049D03*
X1124606D03*
X1127952Y530949D03*
X1147331Y531100D03*
X1134645Y530949D03*
X1140952D03*
X1137992Y536999D03*
X1144685Y537049D03*
X1134645Y568749D03*
X1137992Y585714D03*
X1144535D03*
X1140952Y568749D03*
X1137992Y574799D03*
X1144685Y574849D03*
X1147331Y568900D03*
X1131299Y585714D03*
X1124606D03*
X1131299Y574849D03*
X1127952Y568749D03*
X1124606Y574849D03*
X1101181Y510114D03*
X1107724D03*
X1124606D03*
X1131299D03*
X1137992D03*
X1144535D03*
X1057792Y589800D03*
X1070242D03*
X1083108D03*
X1071062Y612560D03*
X1054331Y593657D03*
X1064371D03*
X1081102Y593642D03*
X1094488Y593659D03*
X1047637Y593642D03*
X1071064Y593657D03*
X1057677Y593642D03*
X1087795Y593659D03*
X1054331Y529022D03*
X1071064D03*
X1057792Y552000D03*
Y533100D03*
Y570900D03*
X1070976Y552000D03*
Y533100D03*
X1084003Y532904D03*
X1083116Y552000D03*
X1070976Y570900D03*
X1083116D03*
X1071064Y547922D03*
Y585722D03*
X1050985Y536957D03*
X1087797D03*
X1094490D03*
X1054331D03*
X1077757D03*
X1064371D03*
X1084450D03*
X1054331Y555857D03*
Y566822D03*
X1050984Y547922D03*
X1050985Y574757D03*
X1087797Y547922D03*
Y574757D03*
X1064371Y566822D03*
X1094488D03*
X1094490Y574757D03*
X1064371Y555857D03*
X1081102Y555842D03*
X1094488Y555859D03*
Y547922D03*
X1047637Y555842D03*
X1054331Y547922D03*
Y574757D03*
X1077757Y547922D03*
Y574757D03*
X1064371Y547922D03*
Y574757D03*
X1071064Y555857D03*
Y566822D03*
X1057677Y555842D03*
X1084450Y547922D03*
Y574757D03*
X1087797Y566822D03*
X1074409Y555842D03*
X1087795Y555859D03*
X1044292Y574757D03*
X1050985Y585722D03*
X1087797D03*
X1094488D03*
X1054331D03*
X1077757D03*
X1064371D03*
X1084450D03*
X1061024Y536957D03*
Y574757D03*
Y547922D03*
Y585722D03*
X1035750Y503006D03*
X1084800Y499400D03*
X974015Y593657D03*
X983900Y589800D03*
X980708Y593657D03*
X1004134D03*
X1000787D03*
X994094D03*
X990748D03*
X984055D03*
X974015Y529014D03*
Y536957D03*
Y555857D03*
Y566814D03*
Y547914D03*
Y574757D03*
Y585714D03*
X1013500Y529200D03*
X980708Y529014D03*
X1004133Y529022D03*
X1000787D03*
X994094D03*
X990748D03*
X984054Y529014D03*
X983900Y533100D03*
Y552000D03*
Y570900D03*
X1026500Y577500D03*
X977362Y536957D03*
X984055D03*
X1004134D03*
X997441D03*
X994094D03*
X987401D03*
X977362Y547914D03*
Y574757D03*
X984054Y547914D03*
X984055Y574757D03*
X980708Y555857D03*
Y566814D03*
X1004134Y555857D03*
X1004133Y566822D03*
Y547922D03*
X1004134Y574757D03*
X1000787Y555857D03*
Y566822D03*
X997441Y547922D03*
Y574757D03*
X994094Y547922D03*
Y574757D03*
Y555857D03*
Y566822D03*
X987401Y547914D03*
Y574757D03*
X990748Y555857D03*
Y566822D03*
X984055Y555857D03*
X984054Y566814D03*
X977362Y585714D03*
X984054D03*
X1004133Y585722D03*
X997441D03*
X994094D03*
X987401Y585714D03*
X1034200Y506956D03*
X913779Y612449D03*
X970731Y589800D03*
X923432Y606549D03*
X917125D03*
X927015Y612449D03*
X920472Y612399D03*
X929811Y606700D03*
X953936Y606549D03*
X957283Y611600D03*
X950590Y612249D03*
X947243Y606549D03*
X943897Y612249D03*
X957765Y607220D03*
X970669Y593657D03*
X963976D03*
X913779Y537049D03*
Y547914D03*
Y574849D03*
Y585714D03*
X957806Y528863D03*
X970669Y529014D03*
X929811Y531100D03*
X917125Y530949D03*
X927015Y537049D03*
X923432Y530949D03*
X920472Y536999D03*
X927015Y547914D03*
X920472D03*
X929811Y568900D03*
X920472Y574799D03*
X927015Y585714D03*
X920472D03*
X917125Y568749D03*
X923432D03*
X927015Y574849D03*
X957600Y533100D03*
X970942D03*
X957701Y552000D03*
X970731D03*
X950590Y537049D03*
X957283Y536957D03*
X953936Y530949D03*
X957283Y548200D03*
X950590Y547914D03*
X947243Y530949D03*
X943897Y537049D03*
Y547914D03*
X957600Y570900D03*
X970942D03*
X950590Y574849D03*
Y585714D03*
X957283Y574757D03*
X953936Y568749D03*
X943897Y574849D03*
X947243Y568749D03*
X943897Y585714D03*
X957283Y555857D03*
X957592Y566743D03*
X960629Y536957D03*
X970669Y555857D03*
Y566814D03*
X963976D03*
X960629Y574757D03*
X963976Y555857D03*
X960629Y547914D03*
Y585714D03*
X967322Y536957D03*
Y574757D03*
Y547914D03*
Y585714D03*
X913779Y510114D03*
X920472D03*
X927015D03*
X950590D03*
X943897D03*
X957774Y512794D03*
X957283Y518057D03*
X849810Y606549D03*
X890354Y612649D03*
X883661Y612599D03*
X907086Y612649D03*
X870275D03*
X876968D03*
X853543D03*
X856189Y606700D03*
X873621Y606549D03*
X910432D03*
X893000Y606700D03*
X880314Y606549D03*
X886621D03*
X849810Y530949D03*
Y568749D03*
X873621Y530949D03*
X876968Y537049D03*
Y547914D03*
X870275D03*
X853393D03*
X870275Y537049D03*
X853543D03*
X856189Y531100D03*
X853393Y585714D03*
X870275D03*
X873621Y568749D03*
X876968Y574849D03*
Y585714D03*
X870275Y574849D03*
X853543D03*
X856189Y568900D03*
X890354Y537049D03*
X893000Y531100D03*
X910432Y530949D03*
X907086Y537049D03*
X886621Y530949D03*
X883661Y536999D03*
X880314Y530949D03*
X883661Y547914D03*
X890204D03*
X907086D03*
X880314Y568749D03*
X886621D03*
X883661Y574799D03*
Y585714D03*
X890354Y574849D03*
X893000Y568900D03*
X890204Y585714D03*
X910432Y568749D03*
X907086Y574849D03*
Y585714D03*
X876968Y510114D03*
X870275D03*
X853393D03*
X890204D03*
X883661D03*
X907086D03*
X846850Y612599D03*
X840157Y612649D03*
X833464D03*
X810039Y612599D03*
X803346Y612649D03*
X796653D03*
X816582D03*
X806692Y606549D03*
X812999D03*
X799999D03*
X819378Y606700D03*
X843503Y606549D03*
X836810D03*
X816582Y537049D03*
Y547914D03*
X810039Y536999D03*
X806692Y530949D03*
X812999D03*
X803346Y537049D03*
X796653D03*
X799999Y530949D03*
X810039Y547914D03*
X796653D03*
X803346D03*
X810039Y585714D03*
X806692Y568749D03*
X810039Y574799D03*
X812999Y568749D03*
X803346Y585714D03*
X796653D03*
X799999Y568749D03*
X796653Y574849D03*
X803346D03*
X816582Y585714D03*
Y574849D03*
X819378Y531100D03*
X836810Y530949D03*
X833464Y537049D03*
X846850Y547914D03*
X833464D03*
X840157D03*
X846850Y536999D03*
X843503Y530949D03*
X840157Y537049D03*
X819378Y568900D03*
X840157Y585714D03*
X833464D03*
X840157Y574849D03*
X833464D03*
X836810Y568749D03*
X846850Y585714D03*
Y574799D03*
X843503Y568749D03*
X816582Y510114D03*
X810039D03*
X796653D03*
X803346D03*
X846850D03*
X840157D03*
X833464D03*
X727000Y606600D03*
X779921Y612649D03*
X773228Y612599D03*
X755000Y614500D03*
X769700Y604900D03*
X776188Y606549D03*
X782567Y606700D03*
X739307Y598850D03*
X755800Y604600D03*
X769500Y612583D03*
X733032Y604000D03*
X727400Y571300D03*
X727106Y586550D03*
X769818Y529200D03*
X755000Y574800D03*
X752500Y585150D03*
X773228Y536999D03*
X763677Y547783D03*
X776188Y530949D03*
X782567Y531100D03*
X779921Y537049D03*
X773228Y547914D03*
X779771D03*
X769881Y555700D03*
X773228Y574799D03*
X782567Y568900D03*
X769700Y566900D03*
X776188Y568749D03*
X779921Y574849D03*
X773228Y585714D03*
X779771D03*
X769500Y536983D03*
X755000Y566000D03*
X769500Y547900D03*
Y574700D03*
Y585700D03*
X732600Y573950D03*
X779771Y510114D03*
X773228D03*
X769881Y517900D03*
X763544Y522236D03*
X769500Y510100D03*
X712600Y571900D03*
X716300Y569400D03*
X913700Y242260D03*
X944507Y220809D03*
X937747D03*
X930987Y228610D03*
X937747Y224709D03*
X934367Y230559D03*
X937747Y228610D03*
X927607Y222760D03*
X947887D03*
X920847Y242260D03*
X927607Y226660D03*
X951267Y224709D03*
X930987D03*
X934367Y222760D03*
X971546Y244209D03*
X927607Y238360D03*
X930987Y236409D03*
X927607Y242260D03*
X934367Y238360D03*
X937747Y244209D03*
Y240309D03*
X930987Y244209D03*
X934367Y242260D03*
X944507Y232509D03*
X947887Y230559D03*
X951267Y244209D03*
X954647Y242260D03*
X944507Y236409D03*
X951267Y232509D03*
X961406Y234460D03*
X964786Y236409D03*
X947887Y242260D03*
X954647Y238360D03*
X944507Y240309D03*
X954647Y234460D03*
X947887Y238360D03*
X951267Y236409D03*
X961406Y242260D03*
X964786Y244209D03*
X771232Y214033D03*
X742897Y229573D03*
X760304Y235827D03*
X768560Y244055D03*
X769019Y276400D03*
X762616Y270113D03*
X761480Y242720D03*
X771650Y246451D03*
Y278451D03*
X759700Y232000D03*
X756114Y316209D03*
X762842Y302434D03*
X765730Y335064D03*
X771700Y342501D03*
X757956Y328095D03*
X758952Y384100D03*
X765007Y348363D03*
X913787Y253960D03*
Y265660D03*
Y257860D03*
Y261760D03*
Y328060D03*
X927607Y253960D03*
X934367D03*
X937747Y252009D03*
X930987D03*
X924227D03*
X917467D03*
Y259809D03*
X924227D03*
X930987D03*
X920847Y265660D03*
X930987Y275409D03*
X937747D03*
Y271509D03*
Y255909D03*
X934367Y277360D03*
X930987Y271509D03*
X934367Y273460D03*
X927607Y269560D03*
X917467Y263709D03*
X924227Y267609D03*
X934367Y265660D03*
X924227Y263709D03*
Y275409D03*
X927607Y277360D03*
X920847Y273460D03*
Y269560D03*
X924227Y255909D03*
X947887Y253960D03*
X974926D03*
X941127D03*
X958026Y252009D03*
X968166Y277360D03*
X951267Y275409D03*
X961406Y277360D03*
X958026Y263709D03*
X968166Y269560D03*
X974926Y265660D03*
X961406Y261760D03*
X958026Y255909D03*
X951267Y259809D03*
X958026D03*
X954647Y277360D03*
Y265660D03*
X951267Y267609D03*
X954647Y273460D03*
X958026Y275409D03*
X954647Y269560D03*
X961406D03*
X964786Y283209D03*
X971546D03*
Y275409D03*
Y263709D03*
X974926Y269560D03*
X941127Y277360D03*
Y265660D03*
X944507Y275409D03*
Y263709D03*
X941127Y269560D03*
Y257860D03*
Y261760D03*
X947887Y277360D03*
Y265660D03*
X971546Y259809D03*
Y255909D03*
X964786Y279310D03*
X974926Y273460D03*
Y281260D03*
X968166D03*
X920847Y257860D03*
Y261760D03*
Y253960D03*
X917467Y255909D03*
X930987Y267609D03*
X937747Y263709D03*
X927607Y257860D03*
X930987Y255909D03*
X934367Y269560D03*
X937747Y267609D03*
X927607Y261760D03*
X934367Y257860D03*
X937747Y259809D03*
X927607Y265660D03*
X934367Y261760D03*
X930987Y263709D03*
X947887Y261760D03*
X954647Y257860D03*
X974926D03*
Y261760D03*
X944507Y252009D03*
X951267Y263709D03*
X954647Y261760D03*
X944507Y255909D03*
X951267Y252009D03*
X954647Y253960D03*
X964786Y263709D03*
Y275409D03*
X944507Y259809D03*
X951267Y255909D03*
X964786Y267609D03*
Y271509D03*
X947887Y257860D03*
X961406Y265660D03*
Y273460D03*
X971546Y267609D03*
Y271509D03*
X958026Y267609D03*
Y271509D03*
X968166Y265660D03*
Y273460D03*
X934367Y285160D03*
Y300760D03*
X927607D03*
Y308560D03*
X934367D03*
X927607Y285160D03*
Y292959D03*
X934367D03*
X920847Y328060D03*
X924227Y322209D03*
X927607Y320260D03*
X930987Y318309D03*
X934367Y316360D03*
X927607D03*
X924227Y326110D03*
X961406Y292959D03*
Y285160D03*
X954647Y292959D03*
Y285160D03*
X968166Y292959D03*
Y300760D03*
X964786Y310509D03*
X954647Y308560D03*
X961406D03*
X954647Y300760D03*
X961406D03*
X974926D03*
X947887Y308560D03*
X941127D03*
Y300760D03*
X947887D03*
X941127Y285160D03*
Y292959D03*
X947887D03*
Y285160D03*
X974926Y292959D03*
X978306Y252009D03*
X991826Y259809D03*
X985066D03*
X981686Y269560D03*
Y281260D03*
X995206Y269560D03*
X985066Y267609D03*
X991826Y263709D03*
X988446Y265660D03*
X998586Y263709D03*
X991826Y271509D03*
X995206Y273460D03*
X991826Y283209D03*
Y279310D03*
Y275409D03*
X988446Y281260D03*
X985066Y283209D03*
X978306D03*
Y267609D03*
Y259809D03*
X995206Y265660D03*
X991826Y267609D03*
X1001965Y261760D03*
X1012105Y255909D03*
X1015485Y253960D03*
X1018865Y252009D03*
X1005345Y259809D03*
X1008725Y257860D03*
X978306Y255909D03*
Y263709D03*
X988446Y257860D03*
Y261760D03*
X985066Y255909D03*
Y263709D03*
X981686Y253960D03*
Y265660D03*
Y257860D03*
Y261760D03*
Y292959D03*
Y300760D03*
X988446D03*
X991826Y310509D03*
X988446Y292959D03*
X991826Y314409D03*
X1094731Y346546D03*
X1091351Y348497D03*
X832300Y402863D03*
X827800D03*
X824000D03*
X847577Y381842D03*
X971546Y333909D03*
Y326110D03*
X961406Y331960D03*
Y328060D03*
X964786Y333909D03*
Y326110D03*
X968166Y331960D03*
Y324160D03*
X947887Y339760D03*
X951267Y341709D03*
X968166Y335860D03*
Y328060D03*
X944507Y337809D03*
Y341709D03*
X951267Y333909D03*
X954647Y335860D03*
X947887D03*
X954647Y339760D03*
X937747Y337809D03*
X930987Y333909D03*
X934367Y335860D03*
X927607Y331960D03*
Y335860D03*
X934367Y339760D03*
Y328060D03*
X937747Y330009D03*
X927607Y339760D03*
X930987Y341709D03*
Y330009D03*
X937747Y333909D03*
X917467Y337809D03*
X920847Y339760D03*
Y335860D03*
X944507Y333909D03*
X941127Y335860D03*
Y339760D03*
Y328060D03*
Y331960D03*
X947887Y328060D03*
Y331960D03*
X944507Y322209D03*
X958026Y326110D03*
X964786Y322209D03*
X968166Y320260D03*
X971546Y322209D03*
X954647Y328060D03*
Y331960D03*
X951267Y337809D03*
X958026Y330009D03*
X951267D03*
X971546D03*
X964786D03*
X971546Y337809D03*
X961406Y324160D03*
X958026Y341709D03*
Y337809D03*
Y333909D03*
X930987Y337809D03*
X934367Y324160D03*
Y331960D03*
X924227Y341709D03*
Y337809D03*
Y333909D03*
X917467Y341709D03*
Y333909D03*
X937747Y326110D03*
Y341709D03*
X913787Y335860D03*
Y339760D03*
X930987Y353409D03*
X927607Y351460D03*
X930987Y349509D03*
X927607Y359260D03*
Y355360D03*
X934367Y347560D03*
X937747Y349509D03*
X920847Y347560D03*
Y351460D03*
X917167Y361209D03*
X920847Y355360D03*
X924227Y357309D03*
Y361209D03*
Y353409D03*
Y345609D03*
Y349509D03*
X917467D03*
Y353409D03*
X930987Y345609D03*
X934367Y351460D03*
X927607Y347560D03*
X937747Y345609D03*
X954647Y343660D03*
X917467Y345609D03*
X920847Y343660D03*
X941127D03*
X947887D03*
X927607D03*
X934367D03*
X913787Y347560D03*
Y351460D03*
Y355360D03*
Y343660D03*
X985066Y333909D03*
X988446Y335860D03*
X981686D03*
X1001965D03*
X998586Y333909D03*
X991826Y322209D03*
X995206Y324160D03*
X988446Y331960D03*
X995206D03*
X991826Y330009D03*
X985066D03*
X981686Y331960D03*
X978306Y326110D03*
Y330009D03*
Y333909D03*
X991826Y326110D03*
X995206Y328060D03*
Y335860D03*
X991826Y333909D03*
X974926Y331960D03*
Y328060D03*
Y335860D03*
Y324160D03*
X1096981Y383896D03*
Y391696D03*
Y379996D03*
Y387796D03*
Y356596D03*
Y364396D03*
Y360496D03*
X1035765Y374860D03*
Y386560D03*
Y378760D03*
Y367060D03*
Y363160D03*
Y370959D03*
Y382660D03*
Y355360D03*
X1042524D03*
X1045904Y357309D03*
X1039145D03*
X1045904Y384609D03*
X1093601Y381947D03*
Y389747D03*
X1090221Y383896D03*
Y387796D03*
X1042524Y386560D03*
X1039145Y384609D03*
X1049284Y390460D03*
X1045904Y380709D03*
X1049284Y378760D03*
X1045904Y369010D03*
X1039145Y372909D03*
X1052664Y380709D03*
X1049284Y374860D03*
X1073322Y389747D03*
Y393647D03*
X1083462Y383896D03*
Y387796D03*
X1073322Y378047D03*
Y381947D03*
X1080082D03*
Y389747D03*
X1076702Y383896D03*
Y391696D03*
Y379996D03*
Y387796D03*
X1042524Y378760D03*
Y374860D03*
X1039145Y380709D03*
X1045904Y372909D03*
X1052664Y361209D03*
X1039145D03*
X1049284Y367060D03*
Y363160D03*
X1042524Y367060D03*
X1052664Y372909D03*
Y369010D03*
X1076702Y364396D03*
X1073322Y370247D03*
X1086841Y366347D03*
Y370247D03*
X1073322Y358547D03*
Y366347D03*
X1083462Y364396D03*
Y372197D03*
X1093601Y362447D03*
X1090221Y356596D03*
Y360496D03*
X1080082Y366347D03*
Y370247D03*
Y362447D03*
Y374146D03*
X1049284Y359260D03*
X1042524Y363160D03*
X1039145Y369010D03*
X1045904Y361209D03*
X1052664Y357309D03*
X1049284Y370959D03*
X1042524D03*
X1045904Y365109D03*
X1039145D03*
X1052664D03*
Y392410D03*
X1040265Y394359D03*
X1049284Y382660D03*
X1042524D03*
Y390460D03*
X1056176Y402471D03*
X1041395Y402800D03*
X1061039Y359351D03*
X1060963Y370959D03*
X1061055Y363160D03*
X1052664Y353409D03*
X1064371Y367060D03*
X1052664Y396309D03*
X1060694Y394359D03*
Y390460D03*
X1049284Y386560D03*
X1060694D03*
Y382660D03*
Y378760D03*
X1048154Y402900D03*
X1086841Y378047D03*
X1090221Y376096D03*
X1093601Y374146D03*
Y370247D03*
X1049284Y355360D03*
X1080082Y358547D03*
X1083462Y356596D03*
X1052500Y400400D03*
X974926Y351460D03*
Y359260D03*
X981686Y343660D03*
X988446D03*
X998586Y345609D03*
X1001965Y343660D03*
X991826Y384609D03*
X991500Y396301D03*
X1022245Y390460D03*
X995206Y386560D03*
X978306Y353409D03*
Y361209D03*
Y349509D03*
Y357309D03*
X985066Y353409D03*
Y357309D03*
X981686Y351460D03*
Y359260D03*
X1022245Y386560D03*
X998586Y388509D03*
X991826Y380709D03*
X1000800Y402800D03*
X995206Y378760D03*
X998586Y380709D03*
X1025625Y372909D03*
X1018865Y384609D03*
X995206Y367060D03*
X998586Y372909D03*
X991826D03*
X988446Y374860D03*
Y370959D03*
Y378760D03*
X1018865Y372909D03*
X1012105D03*
X1022245Y378760D03*
X1012105Y380709D03*
X1022245Y374860D03*
X1015485D03*
X1025625Y380709D03*
X1015485Y378760D03*
X1032385Y384609D03*
X1029005Y386560D03*
X1018865Y380709D03*
X1001965Y378760D03*
Y374860D03*
X1032385Y380709D03*
Y372909D03*
X1029005Y378760D03*
Y374860D03*
X1008725Y386560D03*
X1012105Y384609D03*
X1008725Y378760D03*
X1005345Y380709D03*
X1008725Y374860D03*
X1005345Y372909D03*
X998586Y369010D03*
X1001965Y367060D03*
X1005345Y384609D03*
X1025625D03*
X995206Y355360D03*
X998586Y357309D03*
X1029005Y367060D03*
X1015485Y355360D03*
X995206Y351460D03*
X998586Y361209D03*
X995206Y363160D03*
X991826Y357309D03*
Y369010D03*
Y361209D03*
X1018865Y369010D03*
X1012105D03*
X1018865Y361209D03*
X1012105D03*
X1022245Y367060D03*
X1015485D03*
X1022245Y363160D03*
X1015485D03*
X1032385Y369010D03*
Y361209D03*
X985066Y345609D03*
X1025625Y361209D03*
X1018865Y357309D03*
X1001965Y351460D03*
Y363160D03*
X1025625Y357309D03*
X1022245Y355360D03*
X1029005Y363160D03*
X1008725Y355360D03*
X1012105Y357309D03*
X1008725Y363160D03*
Y367060D03*
X1005345Y361209D03*
Y369010D03*
X1001965Y355360D03*
X1005345Y357309D03*
X1008725Y351460D03*
X1025625Y369010D03*
X988446Y367060D03*
X998586Y365109D03*
Y353409D03*
X991826Y365109D03*
X995206Y370959D03*
X991826Y353409D03*
X998586Y392410D03*
X988446Y382660D03*
X995206D03*
X1005345Y365109D03*
X1008725Y370959D03*
X1001965D03*
X1005345Y353409D03*
X1018865Y365109D03*
X1012105D03*
X1025625D03*
X1022245Y370959D03*
X1015485D03*
X1018865Y353409D03*
X1012105D03*
X1025625D03*
X1029005Y370959D03*
X1032385Y365109D03*
X1007595Y402800D03*
X1008725Y382660D03*
X1001965D03*
X1005345Y392410D03*
X1029005Y390460D03*
X1025625Y392410D03*
X1022245Y382660D03*
X1015485D03*
X1012105Y392410D03*
X1018865D03*
X1029005Y382660D03*
X1027875Y402800D03*
X1005345Y345609D03*
X1032385Y353409D03*
X998586Y384609D03*
X985066Y376809D03*
X981686Y374860D03*
X995206D03*
X978306Y372909D03*
X981686Y370959D03*
X978306Y369010D03*
X985066D03*
X981686Y367060D03*
X985066Y365109D03*
X988446Y363160D03*
X1032385Y357309D03*
X1029005Y355360D03*
X1015485Y351460D03*
X1022245D03*
X1029005D03*
X991826Y349509D03*
X1012105D03*
X995206Y347560D03*
X1001965D03*
X1008725D03*
X937747Y372909D03*
X930987Y369010D03*
Y380709D03*
X927607Y378760D03*
X937747Y369010D03*
X934367Y367060D03*
Y378760D03*
X927607Y374860D03*
X947887D03*
Y382660D03*
X958026Y376809D03*
Y380709D03*
X944507Y376809D03*
Y380709D03*
X954647Y374860D03*
Y382660D03*
X934367Y374860D03*
X951267Y376809D03*
X927607Y370959D03*
X951267Y384609D03*
X937747Y376809D03*
X951267Y372909D03*
X930987D03*
X951267Y380709D03*
X971546Y353409D03*
Y357309D03*
X934367Y386560D03*
Y394359D03*
X944507Y388509D03*
Y392410D03*
X930987Y388509D03*
Y392410D03*
X941127Y386560D03*
Y394359D03*
X937747Y388509D03*
Y396309D03*
Y384609D03*
Y392410D03*
X951267Y365109D03*
X947887Y367060D03*
X954647Y355360D03*
X951267Y353409D03*
X944507Y361209D03*
Y365109D03*
X968166Y363160D03*
X961406Y367060D03*
X971546Y372909D03*
X968166Y374860D03*
X964786Y361209D03*
X961406Y363160D03*
X971546Y369010D03*
X964786Y372909D03*
X954647Y359260D03*
X947887Y355360D03*
X951267Y361209D03*
X968166Y367060D03*
X944507Y357309D03*
X961406Y370959D03*
X954647Y363160D03*
X971546Y365109D03*
X947887Y359260D03*
X964786Y369010D03*
Y353409D03*
X961406Y355360D03*
Y351460D03*
X924227Y400209D03*
X930987D03*
X920847Y394359D03*
X917467Y392410D03*
X944507Y400209D03*
X964786Y384609D03*
Y380709D03*
X920847Y398260D03*
X927607D03*
X924227Y396309D03*
X1022245Y207159D03*
X991826Y205210D03*
X1022245Y211060D03*
X995206Y207159D03*
X991826Y209109D03*
X998586Y205210D03*
X1018865Y213009D03*
X998586Y216909D03*
X1001965Y218860D03*
X995206D03*
X991826Y213009D03*
X988446Y214960D03*
X1025625Y216909D03*
X1015485Y218860D03*
X1022245D03*
X1012105Y216909D03*
X1032385Y213009D03*
X1035765Y211060D03*
X1029005Y207159D03*
X1018865Y216909D03*
X1032385D03*
X1029005Y218860D03*
X1008725Y211060D03*
X1012105Y213009D03*
X1008725Y218860D03*
X1005345Y216909D03*
Y213009D03*
X1035765Y218860D03*
X1025625Y213009D03*
X988446Y218860D03*
X995206Y214960D03*
X1001965D03*
X1035765D03*
X1015485D03*
X1022245D03*
X1012105Y205210D03*
X1025625Y205211D03*
X1029005Y214960D03*
X1035765Y207159D03*
X1005345Y205210D03*
X1008725Y214960D03*
X991826Y216909D03*
X985066Y220809D03*
X988446Y207158D03*
X995206Y211060D03*
X998586Y213009D03*
X988446Y230560D03*
X991826Y224709D03*
X995206Y230559D03*
X1025625Y224709D03*
X988446Y222760D03*
X1022245D03*
X1015485D03*
X1018865Y224709D03*
X1012105D03*
X1035765Y222760D03*
X1001965D03*
X998586Y224709D03*
X1032385D03*
X1029005Y222760D03*
X1008725D03*
X1005345Y224709D03*
X998586Y228610D03*
X1001965Y230559D03*
X998586Y236409D03*
Y240309D03*
X1029005Y230559D03*
X1015485Y242260D03*
X1001965Y234460D03*
X995206Y242260D03*
Y234460D03*
X991826Y240309D03*
Y228610D03*
Y236409D03*
X1022245Y234460D03*
X1015485D03*
X1022245Y230559D03*
X1015485D03*
X1018865Y236409D03*
X1012105D03*
X1018865Y228610D03*
X1012105D03*
X1032385D03*
Y236409D03*
X1025625D03*
X1018865Y240309D03*
X1025625D03*
X1035765Y230559D03*
X1022245Y242260D03*
X1029005Y234460D03*
X1008725Y242260D03*
X1012105Y240309D03*
X1008725Y230559D03*
Y234460D03*
X1005345Y228610D03*
Y236409D03*
X1001965Y242260D03*
X1005345Y240309D03*
X1035765Y234460D03*
X1025625Y228610D03*
X998586Y244209D03*
Y232509D03*
X991826D03*
X995206Y226660D03*
X1032385Y232509D03*
X1035765Y226660D03*
X1018865Y244209D03*
X1012105D03*
X1018865Y232509D03*
X1015485Y226660D03*
X1022245D03*
X1012105Y232509D03*
X1025625D03*
X1029005Y226660D03*
X1005345Y244209D03*
X1008725Y226660D03*
X1005345Y232509D03*
X1001965Y226660D03*
X995206Y222760D03*
X981686D03*
X978306Y224709D03*
X981686Y226660D03*
X985066Y228610D03*
Y232509D03*
X1032385Y240309D03*
X1035765Y242260D03*
X1029005D03*
X1032385Y244209D03*
X1025625D03*
X1035765Y246160D03*
X1029005D03*
X1049284Y207159D03*
X1042524Y211060D03*
X1039145Y213009D03*
X1045904D03*
Y216909D03*
X1049284Y218860D03*
X1042524D03*
X1039145Y216909D03*
X1042524Y214960D03*
X1049284D03*
Y211060D03*
X1045904Y244209D03*
Y240309D03*
Y228610D03*
X1039145Y224709D03*
X1049284Y222760D03*
X1042524D03*
X1045904Y224709D03*
X1039145Y236409D03*
X1049284Y230559D03*
Y234460D03*
X1042524Y230559D03*
X1049284Y238360D03*
X1042524Y234460D03*
X1039145Y228610D03*
X1045904Y236409D03*
X1042524Y226660D03*
X1039145Y232509D03*
X1049284Y226660D03*
X1045904Y232509D03*
X1049284Y242260D03*
X1039145Y240309D03*
X1042524Y242260D03*
X1039145Y244209D03*
X1042524Y246160D03*
X1049284D03*
X1268404Y246304D03*
X1270478Y243490D03*
X1205139Y282496D03*
X1178099D03*
X1184859D03*
X1191619D03*
X1174719Y284447D03*
X1164580Y294196D03*
Y290296D03*
Y286396D03*
X1161200Y284447D03*
X1178099Y286396D03*
X1181479Y288347D03*
X1188239Y284447D03*
X1201759D03*
X1198379Y286396D03*
X1205439Y286596D03*
X1208819Y284447D03*
X1184859Y286396D03*
X1191619D03*
X1194999Y284447D03*
X1181479D03*
X1161200Y237647D03*
X1171339Y220096D03*
X1178099D03*
X1181479Y222047D03*
X1188239D03*
X1194999D03*
X1184859Y220096D03*
X1198379D03*
X1201759Y222047D03*
X1191619Y220096D03*
X1205139D03*
X1174719Y222047D03*
X1164580Y235696D03*
X1167960Y229847D03*
X1164580Y223996D03*
Y227896D03*
Y239596D03*
X1178099Y247396D03*
X1161200Y241547D03*
X1164580Y247396D03*
X1161200Y249347D03*
X1171339Y247396D03*
X1178099Y243496D03*
X1171339Y235696D03*
Y231797D03*
X1178099Y227896D03*
Y235696D03*
X1174719Y237647D03*
X1167960Y253247D03*
X1174719D03*
X1164580Y270796D03*
X1171339Y274696D03*
X1174719Y280547D03*
X1171339Y266896D03*
X1164580Y278596D03*
X1171339Y259096D03*
X1178099Y274696D03*
X1191619Y239596D03*
X1188239Y225947D03*
X1184859Y235696D03*
X1188239Y237647D03*
X1184859Y247396D03*
X1188239Y249347D03*
X1201759Y229847D03*
Y225947D03*
Y233746D03*
X1198379Y235696D03*
Y243496D03*
X1201759Y241547D03*
Y249347D03*
X1198379Y239596D03*
X1194999Y225947D03*
Y233746D03*
X1184859Y239596D03*
Y251296D03*
X1212199D03*
X1208519Y233746D03*
X1215700Y223600D03*
X1194999Y264947D03*
Y268847D03*
Y272747D03*
Y280547D03*
X1188239Y257147D03*
X1208519Y272747D03*
X1208819Y280547D03*
X1181479Y261047D03*
Y268847D03*
Y276646D03*
X1212199Y274696D03*
X1208519Y264947D03*
X1184859Y259096D03*
X1191619Y274696D03*
X1205139D03*
X1198379Y278596D03*
X1201759Y261047D03*
X1198379Y255196D03*
X1201759Y257147D03*
X1167960Y261047D03*
X1174719D03*
X1164580Y251296D03*
X1167960Y272747D03*
X1171339Y255196D03*
Y251296D03*
X1161200Y245447D03*
X1164580Y243496D03*
X1174719Y272747D03*
X1167960Y249347D03*
X1181479Y257147D03*
X1178099Y255196D03*
X1161200Y253247D03*
X1174719Y268847D03*
X1167960Y241547D03*
Y245447D03*
Y237647D03*
X1171339Y239596D03*
X1174719Y249347D03*
Y245447D03*
X1205139Y255196D03*
X1208519Y249347D03*
X1201759Y253247D03*
X1205139Y243496D03*
X1212199Y239596D03*
X1205139Y235696D03*
X1212199Y227896D03*
X1208519Y225947D03*
X1201759Y280547D03*
X1198379Y274696D03*
X1201759Y272747D03*
X1205139Y270796D03*
X1201759Y264947D03*
X1205139Y262996D03*
X1208519Y257147D03*
Y253247D03*
X1205139Y251296D03*
X1208519Y241547D03*
Y237647D03*
X1205139Y239596D03*
X1212199Y231797D03*
Y223996D03*
X1205139Y278596D03*
X1201759Y276646D03*
Y268847D03*
X1208519D03*
X1205139Y266896D03*
Y259096D03*
Y223996D03*
X1198379D03*
X1205139Y227896D03*
X1184859Y262996D03*
X1191619Y259096D03*
X1194999Y261047D03*
Y257147D03*
X1188239Y253247D03*
X1194999Y249347D03*
X1198379Y247396D03*
X1191619Y243496D03*
X1188239Y241547D03*
X1181479Y245447D03*
X1184859Y278596D03*
X1188239Y276646D03*
Y280547D03*
X1181479Y272747D03*
X1188239Y268847D03*
X1191619Y266896D03*
X1181479Y280547D03*
X1188239Y261047D03*
X1191619Y262996D03*
X1198379Y259096D03*
X1191619Y255196D03*
Y251296D03*
X1194999Y253247D03*
Y245447D03*
Y241547D03*
X1188239Y245447D03*
X1184859Y243496D03*
Y274696D03*
X1191619Y278596D03*
X1184859Y270796D03*
X1188239Y272747D03*
Y264947D03*
X1174719Y229847D03*
X1167960Y225947D03*
X1174719Y233746D03*
X1181479Y229847D03*
X1184859Y227896D03*
Y231797D03*
X1191619Y235696D03*
Y227896D03*
X1198379Y231797D03*
X1161200Y233746D03*
Y229847D03*
X1171339Y227896D03*
Y223996D03*
X1174719Y225947D03*
X1178099Y231797D03*
X1181479Y233746D03*
Y225947D03*
X1188239Y229847D03*
Y233746D03*
X1191619Y231797D03*
X1194999Y229847D03*
X1161200Y225947D03*
X1164580Y231797D03*
X1174719Y257147D03*
X1178099Y259096D03*
X1167960Y268847D03*
Y264947D03*
X1161200Y214247D03*
Y206446D03*
X1167960Y206447D03*
Y218147D03*
X1171339Y208397D03*
X1174719Y218147D03*
Y206447D03*
X1178099Y208397D03*
Y216196D03*
X1161200Y210346D03*
Y218147D03*
X1181479Y206447D03*
X1188239Y210346D03*
Y206447D03*
X1201759Y218147D03*
X1205759Y206682D03*
X1198379Y212296D03*
X1194999Y210346D03*
X1184859Y204496D03*
X1188239Y214247D03*
X1181479D03*
X1178099Y212296D03*
X1184859Y208397D03*
X1191619Y216196D03*
X1194999Y214247D03*
Y218147D03*
X1164580Y212296D03*
Y208397D03*
X1167960Y214247D03*
X1174719Y210346D03*
X1184859Y216196D03*
X1181479Y210346D03*
X1184859Y212296D03*
X1188239Y218147D03*
X1191619Y212296D03*
X1198379Y216196D03*
X1164580D03*
X1167960Y210346D03*
X1171339Y212296D03*
X1174719Y214247D03*
X1127400Y342947D03*
X1130780Y344896D03*
X1127400Y354647D03*
X1134160Y346847D03*
X1130780Y352696D03*
X1151060Y282496D03*
X1137540D03*
X1119521Y305896D03*
X1130780Y290296D03*
X1127400Y288347D03*
X1130780Y309797D03*
Y301996D03*
X1127400Y303947D03*
Y307847D03*
X1157820Y290296D03*
X1151060Y298096D03*
Y290296D03*
X1144300Y286396D03*
Y294196D03*
X1157820D03*
X1140920Y300047D03*
X1134160Y292247D03*
Y300047D03*
X1140920Y292247D03*
X1144300Y309797D03*
X1137540D03*
X1147680Y303947D03*
X1154440Y307847D03*
X1130780Y313696D03*
X1134160Y323446D03*
X1137540Y317596D03*
X1147680Y327347D03*
X1140920Y331247D03*
X1154440Y315647D03*
X1147680Y319547D03*
X1127400Y315647D03*
X1130780Y329296D03*
X1151060Y305896D03*
X1144300Y301996D03*
X1134160Y303947D03*
X1137540Y298096D03*
X1099241Y220096D03*
Y227896D03*
Y223996D03*
Y251296D03*
Y247396D03*
Y255196D03*
Y259096D03*
Y231797D03*
Y243496D03*
Y235696D03*
Y239596D03*
X1119521Y220096D03*
X1147680Y222047D03*
X1136420D03*
X1157820Y220096D03*
X1106001D03*
X1116141Y222047D03*
X1102621D03*
X1112761Y220096D03*
X1126280D03*
X1122900Y222047D03*
X1133040Y220096D03*
X1109381Y222047D03*
X1129660D03*
X1151060Y220096D03*
X1144300D03*
X1154440Y222047D03*
X1102621Y229847D03*
X1109381Y233746D03*
X1112761Y231797D03*
Y223996D03*
X1116141Y237647D03*
X1109381D03*
X1106001Y223996D03*
X1102621Y237647D03*
Y245447D03*
X1112761Y251296D03*
X1116141Y245447D03*
X1106001Y243496D03*
X1112761D03*
X1109381Y241547D03*
X1106001Y251296D03*
X1119521Y223996D03*
Y227896D03*
Y247396D03*
Y251296D03*
X1106001Y231797D03*
X1116141Y229847D03*
Y264947D03*
X1111631Y271300D03*
X1106001Y262996D03*
Y259096D03*
X1119521Y270796D03*
X1118391Y274997D03*
X1119521Y255196D03*
X1102621Y261047D03*
Y257147D03*
X1109381Y261047D03*
X1116141Y257147D03*
X1112761Y259096D03*
X1129660Y237647D03*
X1126280Y223996D03*
Y231797D03*
X1122900Y229847D03*
Y237647D03*
X1129660Y233746D03*
Y241547D03*
X1126280Y251296D03*
Y243496D03*
X1122900Y245447D03*
X1144300Y243496D03*
X1151060Y247396D03*
X1154440Y245447D03*
X1144300Y247396D03*
Y251296D03*
X1136420Y245447D03*
X1154440Y241547D03*
X1136420D03*
X1157820Y239596D03*
X1144300Y235696D03*
X1136420Y229847D03*
Y233746D03*
Y225947D03*
Y237647D03*
X1133040Y223996D03*
Y235696D03*
Y243496D03*
Y251296D03*
X1147680Y225947D03*
X1151060Y223996D03*
X1147680Y233746D03*
X1154440Y229847D03*
X1157820Y223996D03*
Y231797D03*
X1154440Y253247D03*
X1130780Y278596D03*
X1129660Y261047D03*
X1130780Y274696D03*
X1126280Y259096D03*
X1122900Y257147D03*
X1157820Y278596D03*
Y270796D03*
X1151060Y266896D03*
Y274696D03*
X1137540D03*
X1151060Y259096D03*
X1144300Y255196D03*
X1133040Y259096D03*
X1134160Y268847D03*
X1136420Y257147D03*
X1144300Y278596D03*
Y270796D03*
X1137540Y278596D03*
X1147680Y264947D03*
X1106001Y227896D03*
X1116141Y225947D03*
X1102621D03*
X1112761Y227896D03*
X1126280D03*
X1133040D03*
Y231797D03*
X1122900Y225947D03*
X1109381Y229847D03*
X1129660Y225947D03*
X1109381D03*
X1129660Y229847D03*
X1116141Y233746D03*
Y241547D03*
X1126280Y235696D03*
Y239596D03*
X1112761Y235696D03*
Y239596D03*
X1122900Y233746D03*
Y241547D03*
X1119521Y231797D03*
Y243496D03*
Y235696D03*
Y239596D03*
X1106001Y235696D03*
Y239596D03*
X1102621Y233746D03*
Y241547D03*
X1106001Y247396D03*
Y255196D03*
X1116141Y249347D03*
Y253247D03*
X1102621Y249347D03*
Y253247D03*
X1112761Y247396D03*
Y255196D03*
X1126280Y247396D03*
Y255196D03*
X1136420Y249347D03*
Y253247D03*
X1122900Y249347D03*
Y253247D03*
X1133040Y247396D03*
Y255196D03*
X1109381Y245447D03*
X1129660D03*
X1109381Y257147D03*
X1129660D03*
X1109381Y249347D03*
X1129660D03*
X1109381Y253247D03*
X1129660D03*
X1151060Y243496D03*
X1144300Y239596D03*
X1151060Y235696D03*
X1144300Y227896D03*
X1154440Y233746D03*
X1147680Y229847D03*
X1154440Y237647D03*
X1157820Y227896D03*
X1147680Y241547D03*
Y237647D03*
X1151060Y239596D03*
X1144300Y231797D03*
X1151060D03*
Y227896D03*
X1157820Y235696D03*
X1099241Y216196D03*
Y212296D03*
X1116141Y206446D03*
X1109381Y214247D03*
X1116141Y218147D03*
X1106001Y212296D03*
X1102621Y218147D03*
Y214247D03*
X1119521Y216196D03*
X1119520Y212296D03*
X1106001Y216196D03*
X1112761D03*
X1129660Y206447D03*
X1126280Y216196D03*
Y212296D03*
X1122900Y214247D03*
Y218147D03*
X1129660Y214247D03*
X1147950Y209900D03*
X1136420Y218147D03*
Y210346D03*
Y214247D03*
X1151060Y212296D03*
X1157820D03*
X1133040Y216196D03*
X1109381Y218147D03*
X1129660D03*
X1144300Y216196D03*
Y212296D03*
X1147680Y218147D03*
X1154440Y214247D03*
X1157820Y216196D03*
X1147680Y214247D03*
X1151060Y216196D03*
X1154440Y218147D03*
X1078962Y220096D03*
X1085721D03*
X1095861Y222047D03*
X1082341D03*
X1092481Y220096D03*
X1089101Y222047D03*
X1065242Y220096D03*
X1075582Y222047D03*
X1072202Y220096D03*
X1068822Y222047D03*
X1095861Y229847D03*
X1068822Y233746D03*
X1065242Y235696D03*
Y223996D03*
X1068822Y237647D03*
Y249347D03*
X1065242Y247396D03*
X1068822Y241547D03*
X1072202Y243496D03*
Y251296D03*
X1092481Y223996D03*
Y231797D03*
X1089101Y233746D03*
Y237647D03*
X1095861D03*
Y245447D03*
X1078962Y251296D03*
X1082341Y245447D03*
Y249347D03*
X1078962Y247396D03*
X1092481Y243496D03*
X1075582Y245447D03*
X1085721Y251296D03*
X1075582Y249347D03*
X1085721Y243496D03*
X1089101Y241547D03*
X1085721Y223996D03*
X1075582Y229847D03*
X1082341D03*
X1078962Y227896D03*
Y223996D03*
X1085721Y231797D03*
X1082341Y237647D03*
X1075582D03*
X1072202Y231797D03*
Y223996D03*
X1089101Y253247D03*
X1092481Y255196D03*
X1095861Y257147D03*
X1085721Y227896D03*
X1095861Y225947D03*
X1082341D03*
X1092481Y227896D03*
X1089101Y229847D03*
Y225947D03*
X1075582D03*
X1065242Y227896D03*
Y231797D03*
X1072202Y227896D03*
X1068822Y225947D03*
Y229847D03*
X1075582Y233746D03*
Y241547D03*
X1085721Y235696D03*
Y239596D03*
X1072202Y235696D03*
Y239596D03*
X1082341Y233746D03*
Y241547D03*
X1095861Y233746D03*
Y241547D03*
X1092481Y235696D03*
Y239596D03*
X1078962Y231797D03*
Y243496D03*
Y235696D03*
Y239596D03*
X1072202Y216196D03*
X1065242Y208397D03*
X1068822Y214247D03*
X1065242Y212296D03*
Y204496D03*
X1095861Y218147D03*
X1089101Y214247D03*
Y210346D03*
X1092481Y216196D03*
X1095861Y206446D03*
X1075582D03*
Y218147D03*
X1082341D03*
X1078962Y216196D03*
X1078961Y212296D03*
X1082341Y214247D03*
X1085721Y212296D03*
Y216196D03*
X1089101Y218147D03*
X1065242Y216196D03*
X1068822Y218147D03*
X1315496Y361190D03*
X1167960Y342947D03*
X1174719D03*
X1212199Y344896D03*
X1181479Y342947D03*
X1178099Y344896D03*
X1167960Y370247D03*
X1164580Y372197D03*
X1171339Y356596D03*
Y360496D03*
X1164580Y356596D03*
X1171339Y348796D03*
X1174719Y354647D03*
X1161200Y370247D03*
X1171339Y372197D03*
X1167960Y362447D03*
X1178099Y364396D03*
X1171339Y399496D03*
X1164580Y403396D03*
X1178099D03*
X1167960Y389747D03*
X1161200Y397546D03*
X1167960Y397547D03*
X1174719Y393647D03*
X1161200Y378047D03*
X1164580Y379996D03*
X1174719Y381947D03*
X1194999Y346847D03*
Y354647D03*
X1209219Y370247D03*
X1212199Y356597D03*
Y352696D03*
X1181479Y346847D03*
X1188239Y366347D03*
X1194999D03*
X1191619Y348796D03*
X1184859Y356596D03*
X1191619Y360496D03*
X1201759Y350747D03*
X1205139Y360496D03*
X1181479Y374146D03*
Y389747D03*
X1209769Y374146D03*
X1184859Y383896D03*
X1188239Y393647D03*
X1201759Y389747D03*
X1197258Y397546D03*
X1194999Y385847D03*
X1188239Y378047D03*
X1201759D03*
X1208819Y393647D03*
Y381897D03*
X1174719Y346847D03*
X1178099Y348796D03*
Y352696D03*
X1161200Y335147D03*
Y339047D03*
X1164580Y329296D03*
Y333196D03*
Y337096D03*
X1167960Y339047D03*
Y327347D03*
X1161200Y331247D03*
Y327347D03*
X1178099Y337096D03*
X1164580Y321496D03*
X1161200Y323446D03*
X1167960D03*
X1164580Y325396D03*
X1171339D03*
X1174719Y335147D03*
X1194999D03*
Y331247D03*
X1208519Y339047D03*
X1181479Y327347D03*
Y335147D03*
X1184859Y321496D03*
X1188239Y339047D03*
Y335147D03*
X1184859Y329296D03*
X1191619Y321496D03*
X1198379Y325396D03*
Y340996D03*
X1205139Y333196D03*
X1184859Y337096D03*
X1178099Y340996D03*
X1181479Y339047D03*
X1113881Y405347D03*
X1134160D03*
X1147680Y342947D03*
X1154440D03*
X1144300Y344896D03*
X1151060D03*
X1113881Y350747D03*
Y358547D03*
X1117261Y348796D03*
X1110501Y352696D03*
X1107121Y346847D03*
Y354647D03*
Y358547D03*
Y362447D03*
X1110501Y364396D03*
X1113881Y366347D03*
X1117261Y372197D03*
Y368296D03*
X1110501Y372197D03*
X1113881Y401447D03*
X1110501Y391696D03*
Y395595D03*
X1107121Y389747D03*
Y385847D03*
X1113881D03*
Y397546D03*
Y393647D03*
Y378047D03*
X1117261Y376096D03*
X1110501Y379996D03*
X1107121Y381947D03*
X1151060Y368296D03*
X1147680Y366347D03*
X1120641Y350747D03*
Y358547D03*
Y366347D03*
X1127400Y362447D03*
X1134160Y366347D03*
Y370247D03*
X1151060Y356596D03*
Y360496D03*
X1144300D03*
Y356596D03*
X1147680Y346847D03*
Y350747D03*
X1151060Y352696D03*
Y348796D03*
X1147680Y358547D03*
X1157820Y360496D03*
X1154440Y358547D03*
Y354647D03*
X1157820Y352696D03*
X1147680Y354647D03*
X1144300Y348796D03*
X1154440Y346847D03*
X1140920Y362447D03*
X1154440Y366347D03*
X1144300Y372197D03*
X1137540D03*
Y368296D03*
X1140920Y366347D03*
Y370247D03*
X1151060Y364396D03*
X1144300D03*
X1137540D03*
X1147680Y362447D03*
X1124021Y372197D03*
X1130780D03*
X1124021Y364396D03*
X1137540Y403396D03*
Y399496D03*
X1124021Y391696D03*
X1130780Y395596D03*
X1127400Y385847D03*
Y389747D03*
X1130780Y391696D03*
X1124021Y379996D03*
X1127400Y381947D03*
X1130780Y379996D03*
X1137540Y395597D03*
X1140920Y397546D03*
X1137540Y376096D03*
X1157820Y387796D03*
X1140920Y378047D03*
Y381947D03*
X1147680Y393647D03*
X1120641Y385847D03*
Y393647D03*
Y378047D03*
Y401447D03*
X1140920Y374146D03*
X1151060Y395597D03*
Y391696D03*
X1147680Y385847D03*
Y397546D03*
X1151060Y379996D03*
X1154440Y378047D03*
Y381947D03*
X1140920Y389747D03*
X1134160Y393647D03*
Y385847D03*
Y378047D03*
X1140920Y385847D03*
X1144300Y391696D03*
X1113881Y381947D03*
Y389747D03*
X1124021Y383896D03*
Y387796D03*
X1110501Y383896D03*
Y387796D03*
X1120641Y381947D03*
Y389747D03*
X1134160Y381947D03*
Y389747D03*
X1144300Y395597D03*
Y399496D03*
X1130780Y383896D03*
Y387796D03*
X1140920Y401447D03*
Y393647D03*
X1117261Y379996D03*
X1137540D03*
X1117261Y391696D03*
X1137540D03*
X1117261Y383896D03*
X1137540D03*
X1117261Y387796D03*
X1137540D03*
X1124021Y368296D03*
Y376096D03*
X1130780Y364396D03*
X1134160Y374146D03*
X1120641Y370247D03*
Y374146D03*
X1130780Y368296D03*
Y376096D03*
X1127400Y370247D03*
Y378047D03*
Y366347D03*
Y374146D03*
X1113881Y370247D03*
Y374146D03*
X1110501Y368296D03*
Y376096D03*
X1113881Y354647D03*
Y362447D03*
X1124021Y360496D03*
X1110501Y356596D03*
Y360496D03*
X1120641Y354647D03*
Y362447D03*
X1107121Y370247D03*
X1117261Y356596D03*
X1107121Y378047D03*
X1117261Y364396D03*
X1107121Y366347D03*
X1117261Y352696D03*
X1107121Y374146D03*
X1117261Y360496D03*
Y340996D03*
X1157820Y337096D03*
Y333196D03*
X1151060Y340996D03*
X1157820Y329296D03*
X1154440Y335147D03*
X1144300Y340996D03*
X1157820Y325396D03*
X1154440Y339047D03*
X1355100Y427500D03*
Y432500D03*
X1370100Y442500D03*
X1365100D03*
X1375100D03*
X1364856Y366666D03*
X1375201Y396303D03*
X1365731Y360698D03*
X1378207Y394568D03*
X1371600Y368700D03*
X1380872Y378098D03*
X1380900Y383164D03*
X1364260Y331619D03*
X1336336Y333825D03*
X1306290Y298255D03*
X1205500Y309797D03*
X1198379D03*
X1194999Y296147D03*
Y300047D03*
Y307847D03*
Y303947D03*
X1191619Y298096D03*
X1181479Y300047D03*
Y311747D03*
Y307847D03*
Y303947D03*
X1184859Y294196D03*
X1191619D03*
X1184859Y309797D03*
X1188239Y311747D03*
X1184859Y301996D03*
X1205439Y298096D03*
Y305896D03*
X1208826Y319544D03*
X1198379Y313696D03*
X1205439Y294196D03*
X1970270Y474640D03*
X1961500Y561700D03*
Y582700D03*
X1963500Y521000D03*
X1906200Y607800D03*
X1916050Y604450D03*
X1924000Y611391D03*
X1927000Y614500D03*
X1955400Y530500D03*
X1906050Y569100D03*
X1923600Y554200D03*
X1915593Y576807D03*
X1953500Y551900D03*
X1905000Y533900D03*
X1955790Y499790D03*
X1952500Y508000D03*
X1938410Y490650D03*
X1905010Y479410D03*
X1915100Y480050D03*
X1929480Y472880D03*
X1957100Y502990D03*
X1942000Y440500D03*
X1837534Y579322D03*
X1839126Y583354D03*
X1889800Y580200D03*
X1842500Y534500D03*
X1844100Y551000D03*
X1878450Y548650D03*
X1896500Y555300D03*
X1879800Y579000D03*
X1870892Y583245D03*
X1874825Y564125D03*
X1894299Y557790D03*
X1861080Y537090D03*
X1878000Y539000D03*
X1858528Y544528D03*
X1875850Y567200D03*
X1885100Y584300D03*
X1837200Y525700D03*
X1857480Y466800D03*
X1861300D03*
X1881285Y467049D03*
X1872908Y471338D03*
X1877518Y527560D03*
X1852340Y509140D03*
X1870138Y485732D03*
X1877407Y479046D03*
X1857450Y473654D03*
X1855206Y471112D03*
X1836281Y589122D03*
X1829051Y591299D03*
X1811500Y603500D03*
X1779000Y598900D03*
X1782700Y610900D03*
X1795000Y599600D03*
X1791323Y594030D03*
X1816584Y530542D03*
X1781510Y546362D03*
X1786500Y562200D03*
X1828700Y540252D03*
X1786900Y552500D03*
X1806200Y582900D03*
X1828700Y569474D03*
X1828875Y563674D03*
X1828824Y557663D03*
X1807958Y565690D03*
X1783700Y579200D03*
X1809600Y582800D03*
X1811100Y586800D03*
X1816458Y587480D03*
X1793100Y578500D03*
X1780394Y561076D03*
X1792805Y574675D03*
X1832500Y539500D03*
X1829000Y536315D03*
X1832200Y567760D03*
X1832301Y467005D03*
X1779303Y497246D03*
X1804000Y498176D03*
X1796400Y498000D03*
X1810350Y525650D03*
X1809700Y506875D03*
X1820400Y501100D03*
X1813500Y526500D03*
X1825900Y523500D03*
X1795200Y525700D03*
X1750739Y618718D03*
X1724092Y618700D03*
X1772158Y610960D03*
X1746052Y614796D03*
X1750399Y603201D03*
X1739714Y604967D03*
X1757319Y606953D03*
X1716950Y603450D03*
X1756417Y563840D03*
X1728245Y585244D03*
X1767455Y571695D03*
X1733000Y560000D03*
X1730814Y568814D03*
X1749000Y552863D03*
X1718000Y587723D03*
X1753807Y548183D03*
X1757478Y548192D03*
X1764300Y570900D03*
X1734663Y467005D03*
X1722000Y513000D03*
X1654100Y615790D03*
X1653970Y607340D03*
X1667277Y535221D03*
X1698600Y584800D03*
X1709183Y588700D03*
X1699900Y512300D03*
X1672265Y473600D03*
X1671050Y487000D03*
Y490850D03*
X1652991Y318741D03*
X1592934Y592396D03*
X1615862Y605507D03*
X1594110Y611510D03*
X1626518Y528029D03*
X1631975Y527700D03*
X1644800Y532800D03*
X1636848Y533794D03*
X1638674Y556178D03*
X1646700Y480300D03*
X1627622Y524928D03*
X1621010Y435870D03*
X1634500Y418500D03*
X1603650Y415469D03*
X1646540Y441240D03*
X1639750Y445477D03*
X1634400Y412900D03*
X1630150Y427663D03*
X1639774Y439486D03*
X1640625Y429460D03*
X1591912Y391052D03*
X1608850Y343835D03*
X1607443Y398649D03*
X1613474Y391105D03*
X1620447Y373926D03*
X1619889Y352841D03*
X1603307Y393224D03*
X1609271Y348166D03*
X1613452Y387098D03*
X1608764Y322440D03*
X1631015Y328350D03*
X1608489Y252095D03*
X1600810Y266006D03*
X1636914Y270900D03*
X1596300Y250320D03*
X1631300Y280400D03*
X1617498Y273433D03*
X1622000Y279495D03*
X1545000Y591100D03*
X1535565Y591658D03*
X1563827Y621376D03*
X1554800Y620910D03*
X1572950Y593950D03*
X1565389Y585721D03*
X1546025Y404554D03*
X1534325D03*
X1538225D03*
X1542125D03*
X1549950Y404490D03*
X1557725Y404554D03*
X1540700Y410450D03*
X1551875Y407934D03*
X1555775D03*
X1530425Y384274D03*
X1528475Y380894D03*
Y401174D03*
Y387654D03*
X1529829Y362655D03*
X1528475Y394414D03*
X1530425Y377514D03*
Y391034D03*
Y397794D03*
X1586400Y392900D03*
X1567475Y380894D03*
Y387654D03*
X1582420Y377830D03*
X1582350Y374567D03*
X1582124Y381164D03*
X1573000Y391161D03*
X1571366Y401154D03*
X1582000Y396250D03*
X1567475Y394414D03*
X1582500Y369600D03*
X1573521Y365500D03*
X1538225Y377514D03*
X1549925D03*
X1555775Y380894D03*
Y387654D03*
X1549925Y384274D03*
Y391034D03*
X1561625Y384274D03*
Y391034D03*
Y377514D03*
X1555775Y401174D03*
X1561625Y397794D03*
X1549925D03*
X1555775Y394414D03*
X1544075D03*
X1538225Y397794D03*
Y391034D03*
X1544075Y387654D03*
Y380894D03*
X1538225Y384274D03*
X1532375Y394414D03*
Y387654D03*
Y380894D03*
X1553825Y377514D03*
X1533589Y366361D03*
X1553825Y391034D03*
X1546025D03*
X1581822Y365770D03*
X1569584Y378002D03*
X1563575Y394414D03*
X1557725Y397794D03*
X1571375Y387654D03*
X1569425Y397794D03*
X1563575Y401174D03*
X1569425Y391034D03*
X1553825Y397794D03*
X1542300Y376717D03*
X1546025Y397794D03*
X1551875Y394414D03*
Y387654D03*
X1565525Y384274D03*
X1557725Y377514D03*
X1559675Y401174D03*
X1542125Y397794D03*
X1565525Y391034D03*
X1547975Y394414D03*
X1540175Y387654D03*
Y380894D03*
Y401174D03*
X1547975Y387654D03*
X1536275Y401174D03*
Y387654D03*
X1534325Y384274D03*
X1536275Y380894D03*
X1534325Y397794D03*
X1540175Y394414D03*
X1534325Y391034D03*
X1582600Y389300D03*
X1559675Y387654D03*
Y394414D03*
X1551875Y380894D03*
X1557725Y391034D03*
X1536275Y394414D03*
X1563575Y387654D03*
X1567475Y401174D03*
X1551875D03*
X1565525Y397794D03*
Y377514D03*
X1559675Y380894D03*
X1571375Y394414D03*
X1532375Y401174D03*
X1563575Y380894D03*
X1534325Y377514D03*
X1530033Y340799D03*
X1552900Y281700D03*
X1580150Y329483D03*
X1539400Y320200D03*
X1557250Y315410D03*
X1554800Y290600D03*
X1587800Y308200D03*
X1550800Y296200D03*
X1532850Y303950D03*
X1548024Y322145D03*
X1537500Y292800D03*
X1575645Y320664D03*
X1548334Y325497D03*
X1543864Y311399D03*
X1528460Y244371D03*
X1530200Y257200D03*
X1563440Y250955D03*
X1582699Y252646D03*
X1567000Y259560D03*
X1579867Y265445D03*
X1568120Y251710D03*
X1571876Y255800D03*
X1470353Y592128D03*
X1468101Y573963D03*
X1510925Y404554D03*
X1487525D03*
X1491425D03*
X1518700Y406500D03*
X1503125Y404554D03*
X1482000Y406909D03*
X1507025Y404554D03*
X1499225D03*
X1522625D03*
X1501175Y407934D03*
X1485250Y408017D03*
X1505075Y407934D03*
X1497273Y407610D03*
X1489475Y407934D03*
X1493375D03*
X1467597Y363000D03*
X1469000Y345850D03*
X1472680Y380630D03*
X1482000Y399035D03*
X1503125Y377514D03*
X1491425D03*
X1526525D03*
X1514825D03*
X1524575Y401174D03*
X1514825Y397794D03*
X1508975Y394414D03*
X1503125Y397794D03*
X1491425D03*
X1497275Y394414D03*
Y387654D03*
X1491425Y384274D03*
X1497275Y380894D03*
X1503125Y391034D03*
Y384274D03*
X1508975Y380894D03*
Y387654D03*
X1514825Y391034D03*
X1520675Y380894D03*
Y387654D03*
X1514825Y384274D03*
X1526525Y391034D03*
Y384274D03*
X1491425Y391034D03*
X1483950Y401650D03*
X1508975Y401174D03*
X1497275D03*
X1519626Y365817D03*
X1473255Y376254D03*
X1482000Y387224D03*
Y383287D03*
X1478500Y365500D03*
X1474500D03*
X1507025Y391034D03*
X1493375Y380894D03*
X1505075D03*
X1501175Y394414D03*
X1499225Y391034D03*
Y384274D03*
X1487525Y397794D03*
X1493375Y394414D03*
X1489475D03*
X1487525Y384274D03*
X1489475Y387654D03*
X1499225Y377514D03*
X1495325Y391034D03*
X1493375Y387654D03*
X1505075Y394414D03*
X1501175Y387654D03*
X1495325Y377514D03*
X1524575Y394414D03*
X1487525Y377514D03*
X1472940Y384030D03*
X1505075Y387654D03*
Y401174D03*
X1501175D03*
X1522625Y391034D03*
X1495325Y397794D03*
X1499225D03*
X1493375Y401174D03*
X1489475D03*
X1507025Y384274D03*
X1501175Y380894D03*
X1522625Y397794D03*
X1516775Y380894D03*
X1526659Y397500D03*
X1524575Y380894D03*
X1522476Y361907D03*
X1507025Y377514D03*
X1520675Y394414D03*
X1522625Y377514D03*
X1518725Y397794D03*
Y391034D03*
Y384274D03*
X1510925Y397794D03*
X1512875Y401174D03*
Y394414D03*
X1514925Y358844D03*
X1495325Y384274D03*
X1483868Y390233D03*
X1520675Y401174D03*
X1516775D03*
Y394414D03*
X1510925Y377514D03*
X1512875Y380894D03*
X1515328Y363389D03*
X1518725Y377514D03*
X1522625Y384274D03*
X1510925Y391034D03*
X1516775Y387654D03*
X1512875D03*
X1510925Y384274D03*
X1489475Y380894D03*
X1524575Y387654D03*
X1503878Y364717D03*
X1466970Y320235D03*
X1470649Y295649D03*
X1472500Y341074D03*
X1470649Y289351D03*
X1521817Y330937D03*
X1526000Y341000D03*
X1511900Y287500D03*
X1487426Y330100D03*
X1517600Y320940D03*
X1473231Y320250D03*
X1499723Y300106D03*
X1497179Y306372D03*
X1508455Y313041D03*
X1523935Y318901D03*
X1493400Y300800D03*
X1484100Y330115D03*
X1482550Y333600D03*
X1482585Y340856D03*
X1487000Y333300D03*
X1499987Y288487D03*
X1496628Y288440D03*
X1497509Y303120D03*
X1518060Y317520D03*
X1493268Y293943D03*
X1482386Y336926D03*
X1495300Y297300D03*
X1493290Y287984D03*
X1478524Y318900D03*
X1493500Y304400D03*
X1514100Y321792D03*
X1467040Y260357D03*
X1491407Y258353D03*
X1525650Y248700D03*
X1496030Y267665D03*
X1486574Y267127D03*
X1507003Y272249D03*
X1492753Y273724D03*
X1469829Y266909D03*
X1504461Y274426D03*
X1489546Y279902D03*
X1474096Y256706D03*
X1413600Y531300D03*
X1419600Y531500D03*
X1426870Y530800D03*
X1431690Y521530D03*
X1435479Y423107D03*
X1439000Y423000D03*
X1464124Y353776D03*
X1412220Y388360D03*
X1459033Y395334D03*
X1446700Y387900D03*
X1413735Y391302D03*
X1445100Y374900D03*
X1453900Y353350D03*
X1413400Y361300D03*
X1456000Y360700D03*
X1453251Y356676D03*
X1464351Y295649D03*
Y289351D03*
X1440910Y316693D03*
X1458400Y318500D03*
X1408250Y333000D03*
X1463610Y321329D03*
X1443500Y327900D03*
X1462776Y318200D03*
X1407274Y245652D03*
X1430365Y262624D03*
X1448500Y257700D03*
X1426905Y267045D03*
X1433057Y257388D03*
X1466006Y265300D03*
X1461400Y264700D03*
X1426658Y274252D03*
X1403027Y520231D03*
X1392144Y364617D03*
X1389450Y372250D03*
X1392805Y360466D03*
X1394760Y394720D03*
X1396470Y330014D03*
X1392400Y330800D03*
X1400400Y335400D03*
X1368200Y284000D03*
X1399852Y252353D03*
X1308887Y285015D03*
X1335400Y284900D03*
X1279393Y247602D03*
X1279950Y229338D03*
X1432619Y34830D03*
X1966542Y179606D03*
X1965900Y184600D03*
X1967817Y201029D03*
X1971200Y152500D03*
X1965057Y176447D03*
X1962800Y143700D03*
X1943800Y241800D03*
X1943900Y238500D03*
X1925600Y242700D03*
X1945156Y160236D03*
X1940500Y157600D03*
X1937100Y206800D03*
X1944500Y183900D03*
X1905074Y198163D03*
X1933898Y216707D03*
X1950994Y173745D03*
X1939316Y173600D03*
X1917568Y201215D03*
X1940240Y169970D03*
X1939550Y165600D03*
X1925400Y196300D03*
X1929090Y193190D03*
X1939400Y198400D03*
X1934100Y193400D03*
X1935600Y176300D03*
X1932837Y186700D03*
X1950983Y147344D03*
X1906438Y-15968D03*
X1895330Y64390D03*
X1875100Y51300D03*
X1880986Y53299D03*
X1847000Y86500D03*
X1842250Y84000D03*
Y90750D03*
X1818500Y159500D03*
X1816348Y163437D03*
X1820648D03*
X1778900Y165800D03*
X1827150Y97800D03*
X1821350Y98270D03*
X1820648Y155537D03*
X1816348D03*
X1800000Y132627D03*
X1800264Y143789D03*
X1811348Y143448D03*
X1801366Y151937D03*
X1796059Y104402D03*
X1803400Y114000D03*
X1808226Y136171D03*
X1830316Y102163D03*
X1787373Y120188D03*
X1788200Y93000D03*
Y89000D03*
Y85000D03*
X1827000Y87000D03*
X1824240Y83680D03*
X1827100Y81600D03*
X1788216Y59197D03*
X1832449Y-8950D03*
X1782371Y26832D03*
X1828824Y3699D03*
X1819800Y2100D03*
X1819837Y21700D03*
X1714189Y159550D03*
X1736689D03*
X1732189D03*
X1718689D03*
X1723189D03*
X1727689D03*
X1741189D03*
X1745689D03*
X1750189D03*
X1758650Y158650D03*
X1767250Y99500D03*
Y104500D03*
X1770850Y109500D03*
X1754600Y109200D03*
X1748425Y119190D03*
X1713550Y56000D03*
X1715100Y70500D03*
X1716900Y87900D03*
X1757054Y66059D03*
X1771459Y52695D03*
X1765900Y83700D03*
X1768450Y77376D03*
X1720600Y70200D03*
X1748500Y79500D03*
X1725474Y69250D03*
X1750400Y47400D03*
X1720500Y52440D03*
X1757998Y73637D03*
X1708250Y164950D03*
X1674019Y175990D03*
X1654685Y121790D03*
X1664500Y99000D03*
X1672200Y112200D03*
X1664135Y131239D03*
X1657835D03*
Y156436D03*
X1678400Y103000D03*
X1674800Y103100D03*
X1659038Y95111D03*
X1702513Y79885D03*
X1692573Y85833D03*
X1669350Y69962D03*
X1700710Y73292D03*
X1693900Y73300D03*
X1678627Y54616D03*
X1684248Y56746D03*
X1690500Y73950D03*
X1661900Y92400D03*
X1672427Y9700D03*
X1664823Y13287D03*
X1675800Y4100D03*
X1680033Y-16711D03*
X1591950Y158250D03*
X1590569Y152464D03*
X1595335Y98135D03*
X1632020Y97871D03*
X1628788Y97800D03*
X1593241Y134295D03*
X1598300Y116477D03*
X1598449Y120760D03*
X1600000Y104243D03*
X1648000Y100597D03*
X1613741Y112341D03*
X1608500Y72688D03*
X1606730Y84230D03*
X1632000Y83000D03*
X1625451Y84288D03*
X1605184Y61044D03*
X1595943Y71522D03*
X1603138Y65890D03*
X1635900Y83000D03*
X1637700Y67400D03*
X1599000Y61500D03*
X1596050Y75400D03*
X1632006Y94500D03*
X1640900Y66900D03*
X1597867Y93900D03*
X1597987Y79500D03*
X1596900Y84500D03*
X1602000D03*
X1632000Y73500D03*
X1621100Y69600D03*
X1646400Y13400D03*
X1615000Y12000D03*
X1619100Y6500D03*
X1588176Y157600D03*
X1573473Y37216D03*
X1554573D03*
X1564023D03*
X1542179Y39695D03*
X1545572Y38188D03*
X1589500Y-600D03*
X1489311Y34830D03*
X1497711Y34427D03*
X1479863Y34830D03*
X1470414D03*
X1470862Y38209D03*
X1527700Y6963D03*
X1495611Y13466D03*
X1485242Y4589D03*
X1460965Y34830D03*
X1451516D03*
X1545023Y161675D03*
X1541421Y106742D03*
X1500703Y158233D03*
X1488300Y158300D03*
Y161700D03*
X1488350Y149450D03*
X1523719Y149488D03*
X1473354Y153246D03*
X1476761Y152725D03*
X1490178Y112315D03*
X1524284Y112773D03*
X1474717Y110370D03*
X1511700Y84600D03*
X1840149Y244425D03*
X1843449D03*
X1854374Y248790D03*
X1763300Y250100D03*
G54D58*
X1638131Y475946D03*
G54D50*
X483432Y212296D03*
X525111Y202547D03*
X531871D03*
X480052Y210346D03*
X483432Y239596D03*
X528491Y321496D03*
X525111Y319547D03*
X521731Y329296D03*
X525111Y323446D03*
X487932Y356596D03*
X542011Y344896D03*
Y356596D03*
X552151Y342947D03*
X548771Y344896D03*
X555531D03*
X552151Y346847D03*
X548771Y387796D03*
X552151Y385847D03*
X555531Y352696D03*
Y348796D03*
X552151Y354647D03*
X558911Y350747D03*
X559211Y366347D03*
X555531Y379996D03*
X552151Y381947D03*
X558911Y354647D03*
X552151Y362447D03*
X545391Y350747D03*
X548771Y348796D03*
X542011Y340996D03*
Y337096D03*
Y333196D03*
Y329296D03*
Y325396D03*
X552151Y331247D03*
Y335147D03*
X548771Y333196D03*
X552151Y339047D03*
X555531Y340996D03*
X545391Y327347D03*
Y339047D03*
X562591Y340996D03*
X558911Y339047D03*
X562591Y337096D03*
X555531D03*
X535251Y344896D03*
X538631Y342947D03*
X531871D03*
X528491Y344896D03*
X511592Y362447D03*
X514972Y368296D03*
X508212Y364396D03*
X498072Y378047D03*
X494692Y379996D03*
Y387796D03*
X518352Y350747D03*
Y354647D03*
X511592Y358547D03*
X514972Y360496D03*
Y364396D03*
X511592Y366347D03*
X508212Y368296D03*
Y372197D03*
X504832Y374146D03*
X501452Y376096D03*
X498072Y381947D03*
X494692Y383896D03*
X518352Y346847D03*
X521731Y352696D03*
X511592Y354647D03*
X498072Y374146D03*
X528491Y387796D03*
X521731D03*
Y391696D03*
X518352Y393647D03*
X514972Y395597D03*
X511592Y389747D03*
X528491Y379996D03*
Y383896D03*
X525111Y385847D03*
X521731Y383896D03*
X525111Y389747D03*
X521731Y395597D03*
X514972Y391696D03*
Y387796D03*
X528491Y376096D03*
X531871Y381947D03*
X535251Y348796D03*
X538631Y346847D03*
Y354647D03*
Y358547D03*
Y362447D03*
X531871D03*
Y366347D03*
X535251Y372197D03*
Y379996D03*
X538631Y350747D03*
X535251Y360496D03*
X531871Y358547D03*
X535251Y364396D03*
Y368296D03*
X538631Y374146D03*
X531871Y378047D03*
X525111Y346847D03*
X528491Y348796D03*
Y352696D03*
X511592Y401447D03*
X508212Y383896D03*
X514972Y376096D03*
X504832Y401446D03*
X531871Y331247D03*
X528491Y333196D03*
X518352Y335147D03*
X521731Y340996D03*
Y337096D03*
X538631Y331247D03*
Y327347D03*
X535251Y340996D03*
X538631Y323446D03*
X535251Y337096D03*
X528491Y340996D03*
X531871Y339047D03*
X941127Y324160D03*
X937747Y322209D03*
X947887Y324160D03*
G54D47*
X1854501Y195587D03*
X1944882Y605708D03*
X1952756D03*
X1944882Y597834D03*
X1952756D03*
Y589960D03*
X1944882Y582086D03*
X1952756D03*
X1944882Y574212D03*
X1952756D03*
X1944882Y566338D03*
X1952756D03*
X1944882Y558464D03*
Y589960D03*
X1952756Y558464D03*
X1859854Y501441D03*
G54D38*
X-4488Y425472D03*
X99980Y136909D03*
X1779504Y-5000D03*
X1809504Y-15000D03*
X1799504Y-5000D03*
Y-15000D03*
X1789504Y-5000D03*
Y-15000D03*
X1819504Y-5000D03*
Y-15000D03*
X1809504Y-5000D03*
X1743503Y-15000D03*
X1733503Y-5000D03*
Y-15000D03*
X1723503Y-5000D03*
Y-15000D03*
X1753503Y-5000D03*
Y-15000D03*
X1743503Y-5000D03*
X1769504D03*
Y-15000D03*
X1713503Y-5000D03*
X1703503D03*
Y-15000D03*
X1575000D03*
X1565000D03*
X1555000D03*
X1545000D03*
X1535000D03*
X1472000Y-5000D03*
Y-15000D03*
X1525000D03*
X1515000D03*
X1505000D03*
X1482000D03*
X1492000Y-5000D03*
Y-15000D03*
X1482000Y-5000D03*
X1462000D03*
Y-15000D03*
X1452000Y-5000D03*
Y-15000D03*
X1442000Y-5000D03*
Y-15000D03*
G54D23*
X40500Y-42250D03*
Y-52250D03*
X60500Y-42250D03*
X80500D03*
X100500D03*
X60500Y-52250D03*
X80500D03*
X100500D03*
X120500Y-42250D03*
X140500D03*
X120500Y-52250D03*
X140500D03*
X467246Y-52301D03*
Y-42301D03*
X487246Y-52301D03*
Y-42301D03*
X507246Y-52301D03*
Y-42301D03*
X527246Y-52301D03*
Y-42301D03*
X547246Y-52301D03*
Y-42301D03*
X567246Y-52301D03*
Y-42301D03*
X798984Y-52057D03*
Y-42057D03*
X818984Y-52057D03*
Y-42057D03*
X838984Y-52057D03*
Y-42057D03*
X858984Y-52057D03*
Y-42057D03*
X878984Y-52057D03*
Y-42057D03*
X898984Y-52057D03*
Y-42057D03*
X1135583Y-52285D03*
Y-42285D03*
X1155583Y-52285D03*
Y-42285D03*
X1392258Y-52257D03*
Y-42257D03*
X1412258Y-52257D03*
Y-42257D03*
X1432258Y-52257D03*
Y-42257D03*
X1452258Y-52257D03*
Y-42257D03*
X12290Y264640D03*
G54D53*
X1773347Y545059D03*
Y528523D03*
X1674921D03*
G54D46*
X1724807Y451179D03*
X1851250Y584622D03*
Y576748D03*
Y568874D03*
Y561000D03*
G54D41*
X638541Y454425D03*
X1288068Y171945D03*
Y454425D03*
X1872343Y29874D03*
G54D35*
X40512Y458744D03*
G54D27*
X-15748Y116969D03*
Y132717D03*
Y373110D03*
Y388858D03*
X787Y132717D03*
X28740Y124843D03*
Y140591D03*
X787Y388858D03*
X28740Y380984D03*
Y396732D03*
G54D37*
X30512Y467244D03*
X40512D03*
G54D33*
X27559Y204370D03*
X3937Y313504D03*
X-3937D03*
X-11811D03*
X3937Y337126D03*
X-3937D03*
X-11811D03*
X35433D03*
X27559D03*
X19685D03*
X35433Y313504D03*
X27559D03*
X19685D03*
G54D52*
X1809665Y618663D03*
X1819665D03*
X1829665D03*
G54D28*
X-14488Y434094D03*
X-4488D03*
X5512D03*
X15512D03*
X89980Y145531D03*
X99980D03*
X109980D03*
X119980D03*
G54D60*
X1466694Y375787D03*
G54D56*
X1705772Y567874D03*
G54D42*
X637793Y514079D03*
Y532955D03*
Y551879D03*
X744293Y69778D03*
Y88678D03*
Y50878D03*
Y514079D03*
Y551879D03*
X637793Y-5822D03*
Y13078D03*
X94683Y69778D03*
Y50878D03*
Y31978D03*
Y13078D03*
X637793Y608555D03*
Y570755D03*
Y589679D03*
X94683Y532955D03*
Y570755D03*
Y589679D03*
Y551879D03*
X1287403Y69778D03*
Y50878D03*
Y-5822D03*
Y31978D03*
Y13078D03*
X744293Y-5822D03*
Y13078D03*
X1287403Y608555D03*
Y532955D03*
Y551879D03*
X744293Y608555D03*
Y570755D03*
Y589679D03*
G54D32*
X-7874Y216181D03*
Y325315D03*
G54D31*
X18228Y178386D03*
X-1969D03*
X44291D03*
G54D22*
X-3937Y-43307D03*
X1956693D03*
X-3937Y646063D03*
X1956693D03*
G54D62*
X1950000Y220787D03*
G54D57*
X1611283Y615236D03*
G54D25*
X1699600Y454297D03*
Y235400D03*
X1955506Y454297D03*
G54D26*
X133563Y183126D03*
G54D61*
X1454685Y338189D03*
G54D59*
X1613069Y302692D03*
G54D40*
X326772Y163582D03*
Y439173D03*
X500000Y163582D03*
Y439173D03*
X602362Y387992D03*
X976378Y163582D03*
Y439173D03*
X1149606Y163582D03*
Y439173D03*
X224410Y301378D03*
X602362Y214764D03*
X874016Y301378D03*
X1251969Y214764D03*
Y387992D03*
%LPD*%
G75*
G36*
G01X1026900Y61200D02*
X1021500Y66600D01*
Y87400D01*
X1022200Y88100D01*
X1027700D01*
X1031900Y83900D01*
Y62500D01*
X1030600Y61200D01*
X1026900D01*
G37*
G36*
G01X1023300Y514600D02*
X1019900Y518000D01*
Y541100D01*
X1016100Y544900D01*
Y546188D01*
G02X1016668Y546551I400J0D01*
G03Y549277I632J1363D01*
G02X1016100Y549640I-168J363D01*
G01Y553967D01*
G02X1016567Y554361I400J0D01*
G03Y557323I252J1481D01*
G02X1016100Y557717I-67J394D01*
G01Y561500D01*
X1018100Y563500D01*
X1025600D01*
X1028500Y560600D01*
Y544700D01*
X1028600Y544600D01*
Y516500D01*
X1026700Y514600D01*
X1023300D01*
G37*
G36*
G01X1456127Y274284D02*
G03X1453677Y274285I-1225J-681D01*
G02X1452978I-350J194D01*
G03X1452434Y274828I-1224J-683D01*
G02Y275528I194J350D01*
G03X1450528Y277434I-681J1225D01*
G02X1449828I-350J194D01*
G03X1449285Y277978I-1226J-680D01*
G02Y278677I194J350D01*
G03X1449283Y281128I-682J1225D01*
G02Y281827I195J349D01*
G03X1449829Y282373I-680J1226D01*
G02X1450528I349J-195D01*
G03X1452978Y282370I1226J680D01*
G02X1453677I349J-195D01*
G03X1454221Y281827I1224J683D01*
G02Y281127I-194J-350D01*
G03X1456127Y279221I681J-1225D01*
G02X1456827I350J-194D01*
G03X1457370Y278677I1226J680D01*
G02Y277978I-194J-350D01*
G03X1457371Y275528I682J-1225D01*
G02Y274828I-194J-350D01*
G03X1456827Y274284I681J-1225D01*
G02X1456127I-350J194D01*
G37*
G36*
G01X1449828Y302629D02*
G03X1449284Y303173I-1225J-681D01*
G02Y303873I194J350D01*
G03X1449285Y306323I-681J1225D01*
G02Y307022I194J350D01*
G03X1449284Y309472I-682J1225D01*
G02Y310172I194J350D01*
G03X1449828Y310716I-681J1225D01*
G02X1450528I350J-194D01*
G03X1452978Y310715I1225J681D01*
G02X1453677I349J-194D01*
G03X1456127Y310716I1225J682D01*
G02X1456827I350J-194D01*
G03X1457371Y310172I1225J681D01*
G02Y309472I-194J-350D01*
G03X1457370Y307022I681J-1225D01*
G02Y306323I-194J-350D01*
G03X1456827Y305779I683J-1224D01*
G02X1456127I-350J194D01*
G03X1454221Y303873I-1225J-681D01*
G02Y303173I-194J-350D01*
G03X1453677Y302630I680J-1226D01*
G02X1452978I-350J194D01*
G03X1450528Y302629I-1225J-682D01*
G02X1449828I-350J194D01*
G37*
G36*
G01X1459277Y305779D02*
G03X1458734Y306323I-1226J-680D01*
G02Y307022I194J350D01*
G03X1458733Y309472I-682J1225D01*
G02Y310172I194J350D01*
G03X1459277Y310716I-681J1225D01*
G02X1459977I350J-194D01*
G03X1462427Y310715I1225J681D01*
G02X1463126I349J-194D01*
G03X1463669Y310172I1225J682D01*
G02Y309473I-194J-350D01*
G03Y307022I681J-1226D01*
G02Y306323I-195J-350D01*
G03X1463126Y305780I682J-1225D01*
G02X1462427I-350J194D01*
G03X1459977Y305779I-1225J-682D01*
G02X1459277I-350J194D01*
G37*
G36*
G01X1447600Y401500D02*
X1443795Y405305D01*
X1443927Y405446D01*
G03X1444081Y407303I-1097J1026D01*
G02X1444170Y407840I334J221D01*
G03X1443383Y410525I-918J1189D01*
G02X1443200Y410725I17J199D01*
G01Y435866D01*
G02X1443911Y436117I400J0D01*
G03X1446119Y436155I1089J883D01*
G02X1446767Y436143I320J-241D01*
G03Y437857I1233J857D01*
G02X1446119Y437845I-328J229D01*
G03X1443911Y437883I-1119J-845D01*
G02X1443200Y438134I-311J251D01*
G01Y441156D01*
G02X1443866Y441454I400J0D01*
G03X1445878Y441604I934J1046D01*
G02X1446504Y441591I308J-255D01*
G03Y443409I1196J909D01*
G02X1445878Y443396I-318J242D01*
G03X1443866Y443546I-1078J-896D01*
G02X1443200Y443844I-266J298D01*
G01Y446439D01*
G02X1443800Y446785I400J0D01*
G03X1445619Y447155I700J1215D01*
G02X1446267Y447143I320J-241D01*
G03Y448857I1233J857D01*
G02X1445619Y448845I-328J229D01*
G03X1443800Y449215I-1119J-845D01*
G02X1443200Y449561I-200J346D01*
G01Y476558D01*
G03Y478688I-1059J1065D01*
G01Y482281D01*
X1443217Y482319D01*
G03Y483529I-1375J605D01*
G01X1443200Y483567D01*
Y488268D01*
G03Y490178I-1159J955D01*
G01Y493468D01*
G03Y495378I-1159J955D01*
G01Y562700D01*
X1446188Y565688D01*
X1514200D01*
X1515184Y564704D01*
Y532085D01*
G02X1514636Y531714I-400J0D01*
G03X1513255Y531516I-518J-1303D01*
G02X1512649Y531657I-246J315D01*
G03X1510152Y531707I-1261J-612D01*
G02X1509572Y531568I-352J189D01*
G03X1507556Y531113I-799J-1152D01*
G02X1506852Y531132I-347J199D01*
G03X1504666Y531546I-1252J-632D01*
G02X1504134I-266J298D01*
G03Y529454I-934J-1046D01*
G02X1504666I266J-298D01*
G03X1506816Y529803I934J1046D01*
G02X1507520Y529784I347J-199D01*
G03X1510008Y529754I1252J632D01*
G02X1510588Y529893I352J-189D01*
G03X1512251Y529940I800J1152D01*
G02X1512857Y529799I246J-315D01*
G03X1514636Y529108I1261J612D01*
G02X1515184Y528737I148J-371D01*
G01Y489288D01*
G02X1514793Y488888I-400J0D01*
G03Y486084I32J-1402D01*
G02X1515184Y485684I-9J-400D01*
G01Y482528D01*
G02X1514793Y482128I-400J0D01*
G03X1515499Y479497I32J-1402D01*
G01X1515631Y479569D01*
X1516066Y479134D01*
G02X1516004Y478517I-282J-283D01*
G03X1517946Y476575I771J-1171D01*
G02X1518563Y476637I334J-220D01*
G01X1519155Y476045D01*
G02X1518840Y475363I-283J-283D01*
G03X1520122Y474081I-115J-1397D01*
G02X1520804Y474396I399J32D01*
G01X1521221Y473979D01*
X1521224Y473902D01*
G03X1522561Y472565I1401J64D01*
G01X1522638Y472562D01*
X1523595Y471605D01*
X1523483Y471465D01*
G03X1525454Y469494I1092J-879D01*
G01X1525594Y469606D01*
X1526068Y469132D01*
G02X1525949Y468484I-283J-283D01*
G03X1527803Y466630I576J-1278D01*
G02X1528451Y466749I365J-164D01*
G01X1528600Y466600D01*
Y465426D01*
G02X1528409Y465226I-200J0D01*
G03Y462426I66J-1400D01*
G02X1528600Y462226I-9J-200D01*
G01Y458666D01*
G02X1528409Y458466I-200J0D01*
G03X1527362Y456214I66J-1400D01*
G02X1527289Y455655I-318J-243D01*
G03X1528188Y453145I858J-1109D01*
G02X1528600Y452745I12J-400D01*
G01Y446102D01*
X1528601Y446101D01*
Y443899D01*
X1528698Y443802D01*
Y443385D01*
X1529870Y442214D01*
X1529858Y442117D01*
G03X1531417Y440558I1392J-167D01*
G01X1531514Y440570D01*
X1531885Y440198D01*
X1534385D01*
X1535198Y439385D01*
Y434685D01*
X1535402Y434482D01*
Y434133D01*
X1536397Y433138D01*
X1540181D01*
X1542911Y430408D01*
X1542790Y430267D01*
G03X1542998Y428236I1060J-918D01*
G01Y427314D01*
G03Y425086I852J-1114D01*
G01Y421999D01*
X1542300Y421300D01*
X1540770D01*
G03X1540630I-70J-1400D01*
G01X1537620D01*
G03X1537480I-70J-1400D01*
G01X1534470D01*
G03X1534330I-70J-1400D01*
G01X1531320D01*
G03X1531180I-70J-1400D01*
G01X1525020D01*
G03X1524880I-70J-1400D01*
G01X1521870D01*
G03X1521730I-70J-1400D01*
G01X1520097D01*
X1519673Y420876D01*
X1519533Y420989D01*
G03X1517561Y419018I-882J-1089D01*
G01X1517674Y418878D01*
X1516522Y417726D01*
X1516382Y417840D01*
G03X1514819Y415525I-882J-1089D01*
G02Y414825I-194J-350D01*
G03X1515270Y412217I681J-1225D01*
G01X1515333Y412207D01*
X1515520Y412020D01*
X1515100Y411600D01*
X1513152D01*
G03X1511548I-802J-1150D01*
G01X1510002D01*
G03X1509881Y411675I-798J-1152D01*
G02Y412375I194J350D01*
G03X1508519I-681J1225D01*
G02Y411675I-194J-350D01*
G03X1508398Y411600I677J-1227D01*
G01X1500605D01*
X1500561Y411739D01*
G03X1497889I-1336J-425D01*
G01X1497845Y411600D01*
X1496705D01*
X1496661Y411739D01*
G03X1493989I-1336J-425D01*
G01X1493945Y411600D01*
X1492805D01*
X1492761Y411739D01*
G03X1490089I-1336J-425D01*
G01X1490045Y411600D01*
X1488905D01*
X1488861Y411739D01*
G03X1486189I-1336J-425D01*
G01X1486145Y411600D01*
X1483182D01*
G03X1480818I-1182J-754D01*
G01X1478123D01*
X1472923Y416800D01*
X1467500D01*
X1461700Y411000D01*
Y403900D01*
X1459300Y401500D01*
X1447600D01*
G37*
G36*
G01X1484472Y302629D02*
G03X1482022Y302630I-1225J-681D01*
G02X1481323I-349J194D01*
G03X1480779Y303173I-1224J-683D01*
G02Y303873I194J350D01*
G03X1478873Y305779I-681J1225D01*
G02X1478173I-350J194D01*
G03X1477630Y306323I-1226J-680D01*
G02Y307022I194J350D01*
G03X1477629Y309472I-682J1225D01*
G02Y310172I194J350D01*
G03X1478173Y310716I-681J1225D01*
G02X1478873I350J-194D01*
G03X1481323Y310715I1225J681D01*
G02X1482022I350J-194D01*
G03X1482566Y310172I1224J683D01*
G02Y309472I-194J-350D01*
G03X1484472Y307566I681J-1225D01*
G02X1485172I350J-194D01*
G03X1485715Y307022I1226J680D01*
G02Y306323I-194J-350D01*
G03X1485716Y303873I682J-1225D01*
G02Y303173I-194J-350D01*
G03X1485172Y302629I681J-1225D01*
G02X1484472I-350J194D01*
G37*
G36*
G01X1566000Y405200D02*
X1564412Y406788D01*
X1564554Y406930D01*
X1564555Y406931D01*
G03X1562572Y408914I-980J1003D01*
G01X1562571Y408913D01*
X1562429Y408771D01*
X1561887Y409313D01*
G02X1562049Y409978I282J283D01*
G03X1560289Y411738I-424J1336D01*
G02X1559624Y411576I-382J120D01*
G01X1558300Y412900D01*
X1556917D01*
G02X1556663Y413609I0J400D01*
G03X1554887I-888J1085D01*
G02X1554633Y412900I-254J-309D01*
G01X1553017D01*
G02X1552763Y413609I0J400D01*
G03X1550987I-888J1085D01*
G02X1550733Y412900I-254J-309D01*
G01X1543000D01*
X1542087Y413813D01*
X1542075Y413873D01*
G03X1539975Y414800I-1375J-273D01*
G01X1538275D01*
G03X1536825I-725J-1200D01*
G01X1534926D01*
X1534892Y414813D01*
G03X1533908I-492J-1313D01*
G01X1533874Y414800D01*
X1533600D01*
X1531000Y412200D01*
Y408208D01*
X1530997Y408190D01*
G03Y407678I1378J-256D01*
G01X1531000Y407660D01*
Y406900D01*
X1530700Y406600D01*
X1528100D01*
X1523800Y410900D01*
Y411962D01*
G02X1524366Y412325I400J-1D01*
G03X1526197Y412959I584J1275D01*
G02X1526896Y412981I356J-183D01*
G03X1527419Y412475I1203J720D01*
G02Y411775I-194J-350D01*
G03X1528781I681J-1225D01*
G02Y412475I194J350D01*
G03X1526853Y414341I-681J1225D01*
G02X1526154Y414319I-356J183D01*
G03X1524366Y414875I-1204J-719D01*
G02X1523800Y415238I-166J364D01*
G01Y417900D01*
X1524300Y418400D01*
X1542100D01*
X1543518Y419818D01*
X1543600D01*
X1543882Y420100D01*
X1546813D01*
G03X1548697I942J1038D01*
G01X1549300D01*
X1550017Y420817D01*
G02X1550675Y420672I283J-283D01*
G03X1551791Y422546I1315J486D01*
G02X1551334Y422942I-57J396D01*
G01Y424454D01*
X1551338Y424474D01*
G03Y425032I-1374J279D01*
G01X1551334Y425052D01*
Y426418D01*
G02X1551765Y426816I400J-1D01*
G03X1553275Y428281I110J1398D01*
G02X1553675Y428700I400J19D01*
G01X1561775D01*
G02X1562175Y428281I0J-400D01*
G03X1564975I1400J-67D01*
G02X1565375Y428700I400J19D01*
G01X1582466D01*
G02X1582858Y428222I0J-400D01*
G03X1582833Y428026I1375J-275D01*
G02X1582547Y427857I-200J11D01*
G03X1583311Y426307I-608J-1263D01*
G02X1583820Y426607I391J-82D01*
G03X1585608Y428222I413J1340D01*
G02X1586000Y428700I392J78D01*
G01X1587210D01*
X1589588Y431078D01*
X1589696Y431052D01*
G03X1591500Y432856I341J1463D01*
G01X1591474Y432964D01*
X1601635Y443125D01*
X1601771Y443035D01*
G03X1603852Y445116I829J1252D01*
G01X1603762Y445252D01*
X1611828Y453318D01*
X1611890Y453328D01*
G03X1613119Y454557I-252J1481D01*
G01X1613129Y454619D01*
X1616402Y457892D01*
Y462479D01*
X1616421Y462519D01*
G03Y463795I-1360J638D01*
G01X1616402Y463835D01*
Y468243D01*
G02X1616603Y468443I200J0D01*
G03X1617792Y469022I4J1502D01*
G02X1618422I315J-246D01*
G03Y470868I1185J923D01*
G02X1617792I-315J246D01*
G03X1616603Y471447I-1185J-923D01*
G02X1616402Y471647I-1J200D01*
G01Y474280D01*
G02X1616991Y474633I400J0D01*
G03X1618568Y474731I709J1324D01*
G02X1619177Y474537I231J-326D01*
G03X1619737Y476176I1323J463D01*
G02X1619137Y476395I-217J336D01*
G03X1618483Y477239I-1437J-438D01*
G02X1618408Y477863I208J342D01*
G01X1619834Y479289D01*
Y479318D01*
X1619902Y479385D01*
Y480815D01*
X1619852Y480865D01*
Y497327D01*
G02X1620558Y497585I400J0D01*
G03Y499649I1225J1032D01*
G02X1619852Y499907I-306J258D01*
G01Y500065D01*
X1608048Y511868D01*
Y526214D01*
X1608049Y526227D01*
G03X1607915Y528878I-7694J940D01*
G01X1607910Y528900D01*
Y532923D01*
X1590900Y549933D01*
Y565200D01*
X1590950Y565250D01*
Y570050D01*
X1592300Y571400D01*
X1598922D01*
X1598938Y571397D01*
G03X1599402I232J1383D01*
G01X1599418Y571400D01*
X1600314D01*
Y568325D01*
G03X1600865Y567157I1512J-1D01*
G02X1600920Y566594I-254J-309D01*
G03X1602952Y566729I1080J-894D01*
G02X1602931Y567295I272J293D01*
G03X1603327Y568156I-1106J1030D01*
G01X1603336Y568240D01*
Y568325D01*
X1603337D01*
X1603336D01*
Y569998D01*
G02X1604019Y570281I400J0D01*
G01X1605724Y568576D01*
X1605713Y568481D01*
G03X1607429Y563808I5570J-606D01*
G02X1607233Y563125I-275J-291D01*
G03X1606022Y561645I300J-1481D01*
G01Y557644D01*
G03X1608053Y556225I1511J0D01*
G02X1608554Y556016I137J-376D01*
G03X1609530Y557969I1275J583D01*
G02X1609044Y558359I-86J391D01*
G01Y559681D01*
G02X1609586Y560055I400J0D01*
G03X1611421Y561777I494J1312D01*
G02X1611769Y562292I382J117D01*
G03X1611890Y562304I-492J5581D01*
G01X1611986Y562314D01*
X1621000Y553300D01*
Y526985D01*
G02X1620486Y526602I-400J0D01*
G03Y523530I-456J-1536D01*
G02X1621000Y523147I114J-383D01*
G01Y512700D01*
X1633400Y500300D01*
Y474654D01*
G02X1633218Y474455I-200J0D01*
G03X1632069Y471909I141J-1596D01*
G02X1632012Y471373I-322J-237D01*
G03X1633015Y468573I1063J-1199D01*
G02X1633400Y468173I-15J-400D01*
G01Y457300D01*
X1631832Y455732D01*
G02X1631266Y455733I-283J283D01*
G03X1631219Y455778I-1062J-1062D01*
G02Y456072I136J147D01*
G03X1629068Y456188I-1019J1103D01*
G02Y455662I-302J-263D01*
G03X1629135Y453615I1132J-988D01*
G02X1629157Y453074I-283J-282D01*
G03X1629099Y453001I1146J-970D01*
G01X1629090Y452990D01*
X1622173Y446073D01*
X1622036Y446171D01*
G03X1620081Y444216I-810J-1145D01*
G01X1620179Y444079D01*
X1612866Y436766D01*
X1612745Y436812D01*
G03X1610938Y435005I-495J-1312D01*
G01X1610984Y434884D01*
X1594138Y418038D01*
Y413762D01*
G03Y411638I1062J-1062D01*
G01Y410207D01*
X1593556Y409625D01*
G02X1592886Y409810I-282J283D01*
G03X1591302Y410937I-1456J-370D01*
G02X1590897Y411482I-33J398D01*
G03X1588486Y413143I-1397J553D01*
G02X1587960Y413131I-270J295D01*
G03X1588014Y410868I-960J-1155D01*
G02X1588540Y410880I270J-295D01*
G03X1589628Y410538I961J1155D01*
G02X1590033Y409993I33J-398D01*
G03X1591060Y407984I1397J-553D01*
G02X1591245Y407314I-98J-388D01*
G01X1589131Y405200D01*
X1584594D01*
X1584551Y405343D01*
G03X1581865I-1343J-402D01*
G01X1581822Y405200D01*
X1570669D01*
G03X1568181I-1244J-646D01*
G01X1566000D01*
G37*
G36*
G01X1544798Y421102D02*
X1544000Y421900D01*
Y424797D01*
X1544156Y424832D01*
G03Y427568I-306J1368D01*
G01X1544000Y427603D01*
Y427947D01*
X1544156Y427982D01*
G03Y430718I-306J1368D01*
G01X1543978Y430758D01*
X1540596Y434140D01*
X1538969D01*
G02X1538654Y434786I0J400D01*
G03X1536811Y436841I-1104J864D01*
G02X1536200Y437181I-211J340D01*
G01Y439800D01*
X1535495Y440505D01*
G02X1535472Y441046I283J283D01*
G03X1535625Y441269I-1074J901D01*
G02X1536325I350J-194D01*
G03X1538775I1225J681D01*
G02X1539475I350J-194D01*
G03X1541925I1225J681D01*
G02X1542625I350J-194D01*
G03X1543209Y440703I1226J680D01*
G02X1543231Y440004I-183J-356D01*
G03Y437596I719J-1204D01*
G02X1543209Y436897I-205J-343D01*
G03X1544569Y436854I641J-1247D01*
G02X1544591Y437553I205J343D01*
G03Y440047I-641J1247D01*
G02X1544569Y440746I183J356D01*
G03X1544531Y443175I-719J1204D01*
G02Y443875I194J350D01*
G03X1543169I-681J1225D01*
G02Y443175I-194J-350D01*
G03X1542625Y442631I681J-1225D01*
G02X1541925I-350J194D01*
G03X1539475I-1225J-681D01*
G02X1538775I-350J194D01*
G03X1536325I-1225J-681D01*
G02X1535625I-350J194D01*
G03X1533175I-1225J-681D01*
G02X1532475I-350J194D01*
G03X1530547Y443163I-1225J-681D01*
G01X1530414Y443086D01*
X1529700Y443800D01*
Y450013D01*
G02X1530355Y450321I400J0D01*
G03X1532475Y450719I895J1079D01*
G02X1533175I350J-194D01*
G03X1535625I1225J681D01*
G02X1536325I350J-194D01*
G03X1538775I1225J681D01*
G02X1539475I350J-194D01*
G03X1541925I1225J681D01*
G02X1542625I350J-194D01*
G03Y452081I1225J681D01*
G02X1541925I-350J194D01*
G03X1541335Y452650I-1226J-680D01*
G02X1541325Y453357I182J356D01*
G03X1541450Y455742I-672J1231D01*
G02X1541344Y456292I227J329D01*
G03X1539378Y455912I-1169J774D01*
G02X1539484Y455362I-227J-329D01*
G03X1540018Y453338I1169J-774D01*
G02X1540028Y452631I-182J-356D01*
G03X1539475Y452081I673J-1230D01*
G02X1538775I-350J194D01*
G03X1536325I-1225J-681D01*
G02X1535625I-350J194D01*
G03X1533175I-1225J-681D01*
G02X1532475I-350J194D01*
G03X1530355Y452479I-1225J-681D01*
G02X1529700Y452787I-255J308D01*
G01Y456382D01*
X1529722Y456425D01*
G03Y457707I-1247J641D01*
G01X1529700Y457750D01*
Y458674D01*
G02X1530172Y459067I400J0D01*
G03Y461825I253J1379D01*
G02X1529700Y462218I-72J393D01*
G01Y463142D01*
X1529722Y463185D01*
G03Y464467I-1247J641D01*
G01X1529700Y464510D01*
Y465434D01*
G02X1530172Y465827I400J0D01*
G03X1529336Y468089I253J1379D01*
G02X1528742Y468058I-311J252D01*
G01X1528296Y468504D01*
G02X1528556Y469186I283J283D01*
G03X1527075Y470667I-81J1400D01*
G02X1526393Y470407I-399J23D01*
G01X1525954Y470846D01*
X1525941Y470902D01*
G03X1524891Y471952I-1366J-316D01*
G01X1524835Y471965D01*
X1523722Y473078D01*
X1523808Y473213D01*
G03X1521872Y475149I-1183J753D01*
G01X1521737Y475063D01*
X1521296Y475504D01*
G02X1521378Y476133I283J283D01*
G03X1519462Y478049I-703J1213D01*
G02X1518833Y477967I-346J201D01*
G01X1516222Y480578D01*
X1516226Y480666D01*
G03X1516203Y480982I-1401J57D01*
G01X1516200Y481000D01*
Y482313D01*
G02X1516639Y482711I400J0D01*
G03Y485501I136J1395D01*
G02X1516200Y485899I-39J398D01*
G01Y487212D01*
X1516203Y487230D01*
G03Y487742I-1378J256D01*
G01X1516200Y487760D01*
Y561196D01*
G02X1516911Y561447I400J0D01*
G03Y563213I1089J883D01*
G02X1516200Y563464I-311J251D01*
G01Y568700D01*
X1519700Y572200D01*
X1564882D01*
G03X1565016Y572065I1060J918D01*
G02X1564999Y571751I-132J-150D01*
G03X1564439Y570936I801J-1150D01*
G02X1563913Y570657I-388J96D01*
G03X1562457Y568333I-481J-1317D01*
G02X1562461Y567761I-278J-288D01*
G03X1562660Y565607I987J-995D01*
G02X1562738Y565015I-225J-331D01*
G03X1562671Y564931I1062J-916D01*
G02X1562359Y564919I-161J119D01*
G03X1560287Y564969I-1059J-919D01*
G02X1559732Y564947I-289J277D01*
G03X1559813Y562931I-932J-1047D01*
G02X1560368Y562953I289J-277D01*
G03X1562313Y563031I932J1047D01*
G02X1562868Y563053I289J-277D01*
G03X1565193Y563943I932J1047D01*
G02X1565593Y564298I397J-45D01*
G03X1566646Y566634I7J1402D01*
G02Y567166I298J266D01*
G03X1566681Y568992I-1046J933D01*
G02X1566726Y569547I309J254D01*
G03X1566854Y571525I-926J1053D01*
G02X1566885Y572084I300J264D01*
G03X1566942Y572140I-954J1028D01*
G01X1567001Y572200D01*
X1567308D01*
X1578900Y560608D01*
X1578898Y560524D01*
G03X1580324Y559098I1402J-24D01*
G01X1580408Y559100D01*
X1589898Y549610D01*
Y549518D01*
X1594408Y545009D01*
Y532137D01*
G03X1598834Y519564I5947J-4972D01*
G01X1598894Y519552D01*
X1599113Y519333D01*
X1599177Y519323D01*
X1607046Y511454D01*
Y511453D01*
X1618850Y499650D01*
Y491338D01*
G02X1618284Y490975I-400J1D01*
G03X1616727Y490710I-584J-1275D01*
G02X1616173I-277J288D01*
G03Y488690I-973J-1010D01*
G02X1616727I277J-288D01*
G03X1618284Y488425I973J1010D01*
G02X1618850Y488062I166J-364D01*
G01Y480450D01*
X1618900Y480400D01*
Y479804D01*
X1618832Y479737D01*
Y479732D01*
X1615856Y476756D01*
G02X1615242Y476814I-283J283D01*
G03X1612546Y476347I-1242J-844D01*
G02X1612014Y476075I-387J101D01*
G03X1612845Y474351I-508J-1307D01*
G02X1613389Y474598I382J-119D01*
G03X1614790Y474692I612J1372D01*
G02X1615400Y474352I210J-340D01*
G01Y470839D01*
G03X1615351Y470769I1206J-896D01*
G02X1614791Y470658I-334J219D01*
G03X1614778Y468334I-791J-1158D01*
G02X1615400Y468001I222J-333D01*
G01Y465058D01*
G02X1615013Y464658I-400J0D01*
G03Y461656I48J-1501D01*
G02X1615400Y461256I-13J-400D01*
G01Y458320D01*
X1612827Y455747D01*
X1612686Y455885D01*
G03X1610562Y453761I-1048J-1076D01*
G02X1610560Y453480I-143J-139D01*
G01X1602851Y445771D01*
X1602756Y445781D01*
G03X1602364Y445770I-154J-1494D01*
G02X1601901Y446152I-63J395D01*
G03X1600636Y444617I-1501J-52D01*
G02X1601099Y444235I63J-395D01*
G03X1601106Y444131I1501J49D01*
G01X1601116Y444036D01*
X1590860Y433780D01*
X1590730Y433848D01*
G03X1588960Y433562I-693J-1333D01*
G02X1588372Y433578I-287J279D01*
G03X1587212Y431091I-1134J-985D01*
G02X1587488Y430408I-6J-400D01*
G01X1586781Y429702D01*
X1552085D01*
X1552084Y429700D01*
X1551424D01*
X1551119Y429395D01*
X1551102Y429384D01*
G03X1550732Y429026I773J-1170D01*
G01X1550722Y429012D01*
X1550320Y428610D01*
Y426554D01*
G02X1549930Y426155I-400J1D01*
G03Y423351I34J-1402D01*
G02X1550320Y422952I-10J-400D01*
G01Y422820D01*
X1548602Y421102D01*
X1544798D01*
G37*
G36*
G01X1587351Y18500D02*
X1584077Y21774D01*
Y36420D01*
G03Y38012I-1154J796D01*
G01Y39600D01*
X1588377Y43900D01*
X1657329D01*
G03X1659871I1271J800D01*
G01X1798096D01*
X1798148Y43778D01*
G03X1800728I1290J550D01*
G01X1800780Y43900D01*
X1866350D01*
X1866900Y43350D01*
Y40983D01*
G03Y38575I719J-1204D01*
G01Y21803D01*
X1865084Y19986D01*
X1849128D01*
G02X1848815Y20636I-1J400D01*
G03X1846313I-1251J1000D01*
G02X1846000Y19986I-312J-250D01*
G01X1842727D01*
G02X1842424Y20648I0J400D01*
G03X1840042Y22468I-1135J983D01*
G02X1839388Y22453I-332J223D01*
G03X1839300Y22561I-1285J-957D01*
G01Y25147D01*
X1839411Y25203D01*
G03X1838007Y28082I-711J1435D01*
G01X1837879Y28021D01*
X1835300Y30600D01*
X1770900D01*
X1765822Y25522D01*
X1763360D01*
G03X1762181Y23065I0J-1512D01*
G02X1762142Y22523I-313J-250D01*
G03X1761724Y21770I957J-1024D01*
G02X1761198Y21470I-392J77D01*
G03X1760677Y21556I-503J-1425D01*
G01X1756976Y21518D01*
G03X1755760Y19132I17J-1511D01*
G02X1755434Y18500I-326J-232D01*
G01X1587351D01*
G37*
%LPC*%
G75*
G36*
G01X1024615Y75306D02*
G02X1023185I-715J-1206D01*
G03Y75994I-204J344D01*
G02X1024615I715J1206D01*
G03Y75306I204J-344D01*
G37*
G36*
G01X1027510Y540027D02*
G03Y539473I288J-277D01*
G02X1025490I-1010J-973D01*
G03Y540027I-288J277D01*
G02X1027510I1010J973D01*
G37*
G36*
G01X1448806Y545659D02*
G03X1448196Y545641I-297J-268D01*
G02X1448138Y547583I-1174J937D01*
G03X1448748Y547601I297J268D01*
G02X1448806Y545659I1174J-937D01*
G37*
G36*
G01X1482927Y538690D02*
G03X1482373I-277J-288D01*
G02Y540710I-973J1010D01*
G03X1482927I277J288D01*
G02Y538690I973J-1010D01*
G37*
G36*
G01X1459798Y532547D02*
G03X1460402Y532525I312J251D01*
G02X1460331Y530557I1098J-1025D01*
G03X1459727Y530579I-312J-251D01*
G02X1459798Y532547I-1098J1025D01*
G37*
G36*
G01X1482713Y530068D02*
G03X1482187I-263J-302D01*
G02Y532332I-987J1132D01*
G03X1482713I263J302D01*
G02Y530068I987J-1132D01*
G37*
G36*
G01X1483227Y523190D02*
G03X1482673I-277J-288D01*
G02Y525210I-973J1010D01*
G03X1483227I277J288D01*
G02Y523190I973J-1010D01*
G37*
G36*
G01X1460140Y522578D02*
G03X1459531Y522505I-274J-291D01*
G02X1459317Y524293I-1174J766D01*
G03X1459926Y524366I274J291D01*
G02X1460140Y522578I1174J-766D01*
G37*
G36*
G01X1507320Y516655D02*
G03X1507113Y516413I-12J-200D01*
G02X1505569Y517508I-1370J-296D01*
G03X1505916Y517958I-49J397D01*
G02X1507441Y519657I1489J197D01*
G01X1507444Y519656D01*
X1509966D01*
X1509969Y519657D01*
G02X1510644Y519514I35J-1502D01*
G03X1511166Y519686I170J362D01*
G02X1511877Y517719I1234J-666D01*
G03X1511365Y517518I-150J-371D01*
G02X1509969Y516653I-1360J637D01*
G01X1509966Y516654D01*
X1507444D01*
X1507441Y516653D01*
G02X1507320Y516655I-36J1502D01*
G37*
G36*
G01X1483213Y514568D02*
G03X1482687I-263J-302D01*
G02Y516832I-987J1132D01*
G03X1483213I263J302D01*
G02Y514568I987J-1132D01*
G37*
G36*
G01X1498094Y517624D02*
X1500619D01*
G02Y514620I36J-1502D01*
G01X1498091D01*
G02X1497993Y514621I-34J1502D01*
G03X1497576Y514222I-17J-400D01*
G02X1496160Y515623I-1402J-1D01*
G03X1496555Y516044I-4J400D01*
G02X1498091Y517624I1500J78D01*
G01X1498094D01*
G37*
G36*
G01X1460140Y514014D02*
G03X1460081Y513441I246J-315D01*
G02X1458008Y513652I-1146J-971D01*
G03X1458067Y514225I-246J315D01*
G02X1460200Y516328I1146J971D01*
G03X1460726I263J302D01*
G02Y514064I987J-1132D01*
G03X1460200I-263J-302D01*
G02X1460140Y514014I-991J1128D01*
G37*
G36*
G01X1483659Y508533D02*
G03X1483443Y508292I-21J-199D01*
G02X1481939Y506473I-1468J-317D01*
G01X1481936Y506474D01*
X1479414D01*
X1479411Y506473D01*
G02X1478563Y506712I-34J1502D01*
G03X1478003Y506580I-216J-337D01*
G02X1477495Y508517I-1203J720D01*
G03X1478047Y508678I198J347D01*
G02X1479411Y509477I1328J-703D01*
G01X1479414Y509476D01*
X1481936D01*
X1481939Y509477D01*
G02X1481997I29J-1502D01*
G03X1482403Y509888I6J400D01*
G02X1485206Y509906I1401J40D01*
G03X1485624Y509500I400J-6D01*
G02X1485729Y509502I81J-1500D01*
G01X1488257D01*
G02X1489694Y508542I36J-1502D01*
G03X1490258Y508335I373J144D01*
G02X1489647Y506537I671J-1231D01*
G03X1489073Y506717I-366J-162D01*
G02X1488257Y506498I-782J1283D01*
G01X1485729D01*
G02X1484194Y508100I-36J1502D01*
G03X1483797Y508526I-399J26D01*
G02X1483659Y508533I2J1402D01*
G37*
G36*
G01X1512628Y503048D02*
Y503038D01*
G02X1511126Y501536I-1502J0D01*
G01X1508625D01*
G02X1508626Y504540I0J1502D01*
G01X1511126D01*
G02X1512628Y503048I0J-1502D01*
G37*
G36*
G01X1510691Y497863D02*
G03X1510080Y497857I-303J-261D01*
G02X1510061Y499667I-1080J894D01*
G03X1510672Y499673I303J261D01*
G02X1510691Y497863I1080J-894D01*
G37*
G36*
G01X1491455Y489341D02*
G03X1491749Y488850I387J-102D01*
G02X1490070Y487845I-324J-1364D01*
G03X1489776Y488336I-387J102D01*
G02X1491455Y489341I324J1364D01*
G37*
G36*
G01X1449553Y485874D02*
G03X1449150Y485457I-4J-400D01*
G02X1447764Y486797I-1401J-62D01*
G03X1448167Y487214I4J400D01*
G02X1450553Y488274I1401J62D01*
G03X1451119Y488278I281J285D01*
G02X1451077Y486212I1069J-1055D01*
G03X1450512Y486239I-296J-269D01*
G02X1449553Y485874I-944J1037D01*
G37*
G36*
G01X1455573Y464404D02*
G03X1455027I-273J-292D01*
G02X1452917Y464459I-1027J1096D01*
G03X1452356Y464475I-289J-277D01*
G02Y466525I-956J1025D01*
G03X1452917Y466541I272J293D01*
G02X1455027Y466596I1083J-1041D01*
G03X1455573I273J292D01*
G02X1457683Y466541I1027J-1096D01*
G03X1458244Y466525I289J277D01*
G02X1460156I956J-1025D01*
G03X1460717Y466541I272J293D01*
G02X1462827Y466596I1083J-1041D01*
G03X1463373I273J292D01*
G02X1465483Y466541I1027J-1096D01*
G03X1466044Y466525I289J277D01*
G02Y464475I956J-1025D01*
G03X1465483Y464459I-272J-293D01*
G02X1463373Y464404I-1083J1041D01*
G03X1462827I-273J-292D01*
G02X1460717Y464459I-1027J1096D01*
G03X1460156Y464475I-289J-277D01*
G02X1458244I-956J1025D01*
G03X1457683Y464459I-272J-293D01*
G02X1455573Y464404I-1083J1041D01*
G37*
G36*
G01Y458704D02*
G03X1455027I-273J-292D01*
G02X1452917Y458759I-1027J1096D01*
G03X1452356Y458775I-289J-277D01*
G02Y460825I-956J1025D01*
G03X1452917Y460841I272J293D01*
G02X1455027Y460896I1083J-1041D01*
G03X1455573I273J292D01*
G02X1457683Y460841I1027J-1096D01*
G03X1458244Y460825I289J277D01*
G02X1460156I956J-1025D01*
G03X1460717Y460841I272J293D01*
G02X1462827Y460896I1083J-1041D01*
G03X1463373I273J292D01*
G02X1465483Y460841I1027J-1096D01*
G03X1466044Y460825I289J277D01*
G02Y458775I956J-1025D01*
G03X1465483Y458759I-272J-293D01*
G02X1463373Y458704I-1083J1041D01*
G03X1462827I-273J-292D01*
G02X1460717Y458759I-1027J1096D01*
G03X1460156Y458775I-289J-277D01*
G02X1458244I-956J1025D01*
G03X1457683Y458759I-272J-293D01*
G02X1455573Y458704I-1083J1041D01*
G37*
G36*
G01Y453004D02*
G03X1455027I-273J-292D01*
G02X1452917Y453059I-1027J1096D01*
G03X1452356Y453075I-289J-277D01*
G02Y455125I-956J1025D01*
G03X1452917Y455141I272J293D01*
G02X1455027Y455196I1083J-1041D01*
G03X1455573I273J292D01*
G02X1457683Y455141I1027J-1096D01*
G03X1458244Y455125I289J277D01*
G02X1460156I956J-1025D01*
G03X1460717Y455141I272J293D01*
G02X1462827Y455196I1083J-1041D01*
G03X1463373I273J292D01*
G02X1465483Y455141I1027J-1096D01*
G03X1466044Y455125I289J277D01*
G02Y453075I956J-1025D01*
G03X1465483Y453059I-272J-293D01*
G02X1463373Y453004I-1083J1041D01*
G03X1462827I-273J-292D01*
G02X1460717Y453059I-1027J1096D01*
G03X1460156Y453075I-289J-277D01*
G02X1458244I-956J1025D01*
G03X1457683Y453059I-272J-293D01*
G02X1455573Y453004I-1083J1041D01*
G37*
G36*
G01X1463173Y448901D02*
G03X1462627I-273J-292D01*
G02X1460517Y448956I-1027J1096D01*
G03X1459956Y448972I-289J-277D01*
G02Y451022I-956J1025D01*
G03X1460517Y451038I272J293D01*
G02X1462627Y451093I1083J-1041D01*
G03X1463173I273J292D01*
G02X1465283Y451038I1027J-1096D01*
G03X1465844Y451022I289J277D01*
G02X1467811Y450968I956J-1025D01*
G03X1468389I289J277D01*
G02X1470411I1011J-971D01*
G03X1470989I289J277D01*
G02Y449026I1011J-971D01*
G03X1470411I-289J-277D01*
G02X1468389I-1011J971D01*
G03X1467811I-289J-277D01*
G02X1465844Y448972I-1011J971D01*
G03X1465283Y448956I-272J-293D01*
G02X1463173Y448901I-1083J1041D01*
G37*
G36*
G01X1504996Y433308D02*
G03X1504477Y433036I-133J-377D01*
G02X1503591Y434728I-1352J370D01*
G03X1504110Y435000I133J377D01*
G02X1504996Y433308I1352J-370D01*
G37*
G36*
G01X1446178Y432396D02*
G03X1446804Y432409I308J255D01*
G02Y430591I1196J-909D01*
G03X1446178Y430604I-318J-242D01*
G02Y432396I-1078J896D01*
G37*
G36*
G01X1460333Y431616D02*
G03X1460281Y431002I228J-329D01*
G02X1458451Y431116I-981J-1002D01*
G03X1458476Y431732I-242J318D01*
G02X1460526Y433927I1002J1119D01*
G03X1461083I278J287D01*
G02X1463177Y433929I1048J-1076D01*
G03X1463739Y433933I279J286D01*
G02X1465706Y433950I992J-991D01*
G03X1466272Y433960I278J287D01*
G02X1468460Y433936I1083J-1041D01*
G03X1469016Y433904I295J271D01*
G02X1470983Y433768I915J-1062D01*
G03X1471560Y433744I300J265D01*
G02X1471478Y431805I970J-1012D01*
G03X1470901Y431829I-300J-265D01*
G02X1468954Y431837I-969J1013D01*
G03X1468398Y431838I-279J-287D01*
G02X1466254Y431897I-1043J1081D01*
G03X1465688Y431917I-293J-272D01*
G02X1463811Y431884I-957J1025D01*
G03X1463250Y431849I-263J-301D01*
G02X1461083Y431775I-1119J1002D01*
G03X1460526I-278J-287D01*
G02X1460333Y431616I-1048J1076D01*
G37*
G36*
G01X1468940Y426991D02*
G03X1468377Y426976I-274J-291D01*
G02X1466178Y427003I-1087J1037D01*
G03X1465598Y427015I-296J-269D01*
G02X1465588Y428995I-998J985D01*
G03X1466169Y429012I282J283D01*
G02X1468377Y429050I1122J-999D01*
G03X1468940Y429035I289J276D01*
G02X1470852Y429042I960J-1022D01*
G03X1471407Y429053I272J293D01*
G02X1471448Y427034I993J-990D01*
G03X1470893Y427023I-272J-293D01*
G02X1468940Y426991I-993J990D01*
G37*
G36*
G01X1495528Y530151D02*
G02X1495133Y531647I-1328J449D01*
G03X1495778Y531817I266J298D01*
G02X1496173Y530321I1328J-449D01*
G03X1495528Y530151I-266J-298D01*
G37*
G36*
G01X1474542Y525426D02*
G02X1473431Y526778I-1402J-19D01*
G03X1473914Y527175I83J391D01*
G02X1475025Y525823I1402J19D01*
G03X1474542Y525426I-83J-391D01*
G37*
G36*
G01X1489743Y518244D02*
G02X1488278Y519206I-1333J-434D01*
G03X1488631Y519687I-38J398D01*
G02X1490136Y521502I1469J313D01*
G01X1492664D01*
G02X1492757Y521501I30J-1502D01*
G03X1492910Y521838I8J200D01*
G02X1494214Y521427I1020J962D01*
G03X1493960Y520818I82J-391D01*
G02X1492664Y518498I-1260J-818D01*
G01X1490136D01*
G02X1489953Y518505I-34J1502D01*
G03X1489743Y518244I-20J-199D01*
G37*
G36*
G01X1511174Y509182D02*
G02X1510031Y508532I41J-1401D01*
G03X1509671Y509145I-338J214D01*
G02X1509549Y509143I-86J1500D01*
G01X1509546Y509144D01*
X1507772D01*
G03X1507392Y508618I0J-400D01*
G02X1505452Y509444I-1332J-438D01*
G03X1505638Y509981I-173J361D01*
G02X1507021Y512147I1347J664D01*
G01X1507024Y512146D01*
X1509546D01*
X1509549Y512147D01*
G02X1510831Y509806I36J-1502D01*
G03X1511174Y509182I331J-224D01*
G37*
G36*
G01X1498181Y506386D02*
G02X1496892Y506674I-914J-1063D01*
G03X1497099Y507307I-107J385D01*
G02X1498313Y509741I1178J932D01*
G01X1498316Y509740D01*
X1500838D01*
X1500841Y509741D01*
G02Y506737I36J-1502D01*
G01X1500838Y506738D01*
X1498316D01*
X1498313Y506737D01*
X1498308D01*
G03X1498181Y506386I4J-200D01*
G37*
G36*
G01X1483483Y498148D02*
G02X1483451Y499700I-1183J752D01*
G03X1484117Y499714I328J229D01*
G02X1486557Y499582I1183J-752D01*
G03X1487268Y499568I359J177D01*
G02X1487243Y498280I1232J-668D01*
G03X1486532Y498294I-359J-177D01*
G02X1484149Y498162I-1232J668D01*
G03X1483483Y498148I-328J-229D01*
G37*
G36*
G01X1471973Y494854D02*
G02X1471770Y496133I-1330J445D01*
G03X1472470Y496245I321J239D01*
G02X1472673Y494966I1330J-445D01*
G03X1471973Y494854I-321J-239D01*
G37*
G36*
G01X1457378Y487031D02*
G02X1455817Y487025I-776J-1167D01*
G03X1455802Y487697I-224J331D01*
G02X1457388Y487703I788J1279D01*
G03X1457378Y487031I212J-339D01*
G37*
G36*
G01X1483895Y470616D02*
G02X1483894Y469186I1205J-716D01*
G03X1483205I-344J-204D01*
G02X1483206Y470616I-1205J716D01*
G03X1483895I344J204D01*
G37*
G36*
G01X1511165Y455164D02*
G02X1511145Y453875I1235J-664D01*
G03X1510435Y453886I-358J-179D01*
G02X1508116Y455440I-1234J665D01*
G03X1508067Y455998I-309J254D01*
G02X1510059Y456176I909J1068D01*
G03X1510108Y455618I309J-254D01*
G02X1510455Y455175I-908J-1068D01*
G03X1511165Y455164I358J179D01*
G37*
G36*
G01X1504495Y446629D02*
G02X1503769Y448171I-1370J297D01*
G03X1504344Y448442I184J355D01*
G02X1505070Y446900I1370J-297D01*
G03X1504495Y446629I-184J-355D01*
G37*
G36*
G01X1483958Y442059D02*
G02X1483346Y443607I-1355J359D01*
G03X1483945Y443843I212J339D01*
G02X1484557Y442295I1355J-359D01*
G03X1483958Y442059I-212J-339D01*
G37*
G36*
G01X1523025Y441269D02*
G02X1521119Y443175I-1225J681D01*
G03Y443875I-194J350D01*
G02Y446325I681J1225D01*
G03Y447025I-194J350D01*
G02X1520575Y447569I681J1225D01*
G03X1519875I-350J-194D01*
G02X1517425I-1225J681D01*
G03X1516725I-350J-194D01*
G02X1516181Y447025I-1225J681D01*
G03Y446325I194J-350D01*
G02X1514275Y444419I-681J-1225D01*
G03X1513575I-350J-194D01*
G02X1511125I-1225J681D01*
G03X1510425I-350J-194D01*
G02Y445781I-1225J681D01*
G03X1511125I350J194D01*
G02X1513575I1225J-681D01*
G03X1514275I350J194D01*
G02X1514819Y446325I1225J-681D01*
G03Y447025I-194J350D01*
G02X1514777Y449451I681J1225D01*
G03X1514753Y450151I-205J343D01*
G02X1516112Y450199I636J1249D01*
G03X1516136Y449499I205J-343D01*
G02X1516725Y448931I-636J-1249D01*
G03X1517425I350J194D01*
G02X1517996Y449490I1225J-681D01*
G03X1518002Y450195I-186J354D01*
G02X1519896Y452114I673J1230D01*
G03X1520590Y452108I349J196D01*
G02X1522481Y450175I1210J-708D01*
G03Y449475I194J-350D01*
G02X1523025Y448931I-681J-1225D01*
G03X1523725I350J194D01*
G02X1525631Y447025I1225J-681D01*
G03Y446325I194J-350D01*
G02Y443875I-681J-1225D01*
G03Y443175I194J-350D01*
G02X1523725Y441269I-681J-1225D01*
G03X1523025I-350J-194D01*
G37*
G36*
G01X1465770Y419370D02*
G02X1465310Y421175I-1245J644D01*
G03X1465898Y421339I224J331D01*
G02X1468495Y421568I1364J-628D01*
G03X1469143Y421556I328J229D01*
G02X1471258Y421698I1119J-845D01*
G03X1471821Y421693I284J281D01*
G02X1471804Y419702I979J-1004D01*
G03X1471241Y419707I-284J-281D01*
G02X1469143Y419866I-979J1004D01*
G03X1468495Y419854I-320J-241D01*
G02X1466364Y419507I-1233J857D01*
G03X1465770Y419370I-239J-321D01*
G37*
G36*
G01X1624353Y462838D02*
G03X1624133Y462351I161J-366D01*
G02X1621199Y461939I-1433J-451D01*
G03X1620732Y462344I-400J11D01*
G02X1621622Y464567I-232J1383D01*
G03X1622322Y464682I320J240D01*
G02X1624353Y462838I1427J-469D01*
G37*
G36*
G01X1620256Y453770D02*
G03X1620718Y453475I388J98D01*
G02X1619544Y451630I282J-1475D01*
G03X1619082Y451925I-388J-98D01*
G02X1620256Y453770I-282J1475D01*
G37*
G36*
G01X1613259Y441724D02*
G03X1613290Y441177I307J-257D01*
G02X1611161Y441116I-1034J-1089D01*
G03Y441663I-292J274D01*
G02X1613259Y441724I1022J960D01*
G37*
G36*
G01X1559675Y420042D02*
X1555775D01*
G02Y422866I0J1412D01*
G01X1559676D01*
G02X1561086Y421464I-1J-1412D01*
G01Y421370D01*
X1561076Y421286D01*
G02X1559675Y420042I-1401J167D01*
G37*
G36*
G01X1557725Y416662D02*
X1553824D01*
G02X1553825Y419486I1J1412D01*
G01X1554448D01*
G02X1554998Y418963I0J-551D01*
G03X1555016Y418813I777J17D01*
G02X1555159Y418507I-1189J-742D01*
G03X1556391I616J472D01*
G02X1556534Y418813I1332J-436D01*
G03X1556550Y419022I-759J163D01*
G02X1557050Y419486I500J-37D01*
G01X1557725D01*
G02X1559136Y418084I0J-1411D01*
G01Y417990D01*
X1559126Y417906D01*
G02X1557725Y416662I-1401J167D01*
G37*
G36*
G01X1567475Y413282D02*
X1563574D01*
G02X1563575Y416106I1J1412D01*
G01X1564198D01*
G02X1564748Y415583I0J-551D01*
G03X1564766Y415433I777J17D01*
G02X1564909Y415127I-1189J-742D01*
G03X1566141I616J472D01*
G02X1566284Y415433I1332J-436D01*
G03X1566300Y415642I-759J163D01*
G02X1566800Y416106I500J-37D01*
G01X1567475D01*
G02X1568886Y414704I0J-1411D01*
G01Y414610D01*
X1568876Y414526D01*
G02X1567475Y413282I-1401J167D01*
G37*
G36*
G01X1571375Y406522D02*
X1567474D01*
G02X1567475Y409346I1J1412D01*
G01X1568098D01*
G02X1568648Y408823I0J-551D01*
G03X1568666Y408673I777J17D01*
G02X1568809Y408367I-1189J-742D01*
G03X1570041I616J472D01*
G02X1570184Y408673I1332J-436D01*
G03X1570200Y408882I-759J163D01*
G02X1570700Y409346I500J-37D01*
G01X1571375D01*
G02X1572786Y407944I0J-1411D01*
G01Y407850D01*
X1572776Y407766D01*
G02X1571375Y406522I-1401J167D01*
G37*
G36*
G01X1603899Y433762D02*
G02X1602160Y433733I-849J-1239D01*
G03X1602162Y434376I-237J322D01*
G02X1603875Y434405I838J1124D01*
G03X1603899Y433762I250J-313D01*
G37*
G36*
G01X1586980Y421813D02*
G02X1585719Y422818I-1420J-489D01*
G03X1586139Y423346I42J398D01*
G02X1587508Y425336I1420J489D01*
G03X1587895Y425723I-13J400D01*
G02X1589447Y424173I1501J-49D01*
G03X1589060Y423786I13J-400D01*
G02X1587400Y422341I-1501J49D01*
G03X1586980Y421813I-42J-398D01*
G37*
G36*
G01X1534733Y510723D02*
G03X1534654Y510095I203J-345D01*
G02X1532093Y509000I-1059J-1065D01*
G03X1531668Y509391I-400J-8D01*
G02X1532135Y512078I-88J1399D01*
G03X1532676Y512331I158J367D01*
G02X1534733Y510723I1344J-401D01*
G37*
G36*
G01X1568662Y504677D02*
G03X1569135Y505096I74J393D01*
G02X1570261Y502751I3463J220D01*
G03X1569638Y502643I-270J-296D01*
G02X1568662Y504677I-1238J657D01*
G37*
G36*
G01X1556520Y501002D02*
G03Y500448I288J-277D01*
G02X1554500I-1010J-973D01*
G03Y501002I-288J277D01*
G02X1554521Y502968I1010J972D01*
G03X1554502Y503553I-282J284D01*
G02X1554407Y505574I922J1056D01*
G03X1554394Y506137I-290J275D01*
G02X1554306Y508204I1044J1080D01*
G03Y508730I-302J263D01*
G02X1554574Y510945I1132J987D01*
G03X1554674Y511498I-230J327D01*
G02X1556700Y511187I1158J790D01*
G03X1556631Y510630I248J-314D01*
G02X1556570Y508730I-1193J-913D01*
G03Y508204I302J-263D01*
G02X1556470Y506126I-1132J-987D01*
G03X1556452Y505563I275J-291D01*
G02X1556413Y503616I-1028J-953D01*
G03X1556432Y503031I282J-284D01*
G02X1556520Y501002I-922J-1056D01*
G37*
G36*
G01X1543485Y500927D02*
G03Y500373I288J-277D01*
G02X1541465I-1010J-973D01*
G03Y500927I-288J277D01*
G02Y502873I1010J973D01*
G03Y503427I-288J277D01*
G02X1541450Y505356I1010J972D01*
G03X1541434Y505917I-293J272D01*
G02X1541379Y508027I1041J1083D01*
G03Y508573I-292J273D01*
G02X1541414Y510663I1096J1027D01*
G03X1541418Y511224I-283J283D01*
G02X1543468Y511264I1006J976D01*
G03X1543495Y510703I298J-267D01*
G02X1543571Y508573I-1020J-1103D01*
G03Y508027I292J-273D01*
G02X1543516Y505917I-1096J-1027D01*
G03X1543500Y505356I277J-289D01*
G02X1543485Y503427I-1025J-957D01*
G03Y502873I288J-277D01*
G02Y500927I-1010J-973D01*
G37*
G36*
G01X1549310Y500527D02*
G03Y499973I288J-277D01*
G02X1547290I-1010J-973D01*
G03Y500527I-288J277D01*
G02X1547238Y502415I1010J973D01*
G03X1547222Y502954I-303J261D01*
G02X1547259Y505083I1078J1046D01*
G03X1547275Y505644I-277J289D01*
G02Y507556I1025J956D01*
G03X1547259Y508117I-293J272D01*
G02X1547204Y510227I1041J1083D01*
G03Y510773I-292J273D01*
G02X1549396I1096J1027D01*
G03Y510227I292J-273D01*
G02X1549341Y508117I-1096J-1027D01*
G03X1549325Y507556I277J-289D01*
G02Y505644I-1025J-956D01*
G03X1549341Y505083I293J-272D01*
G02X1549378Y502954I-1041J-1083D01*
G03X1549362Y502415I287J-278D01*
G02X1549310Y500527I-1062J-915D01*
G37*
G36*
G01X1527529Y500207D02*
G03X1527514Y499639I274J-291D01*
G02X1525486I-1014J-968D01*
G03X1525471Y500207I-289J277D01*
G02X1524998Y501300I1029J1094D01*
G01Y503764D01*
G02X1525459Y504883I1502J36D01*
G03X1525475Y505444I-277J289D01*
G02X1527525I1025J956D01*
G03X1527541Y504883I293J-272D01*
G02X1528002Y503764I-1041J-1083D01*
G01Y501300D01*
G02X1527529Y500207I-1502J1D01*
G37*
G36*
G01X1532993Y500044D02*
G03X1533547Y499831I373J144D01*
G02X1532872Y498076I633J-1251D01*
G03X1532318Y498289I-373J-144D01*
G02X1530675Y500513I-633J1251D01*
G03Y501067I-288J277D01*
G02X1532253Y503322I1009J973D01*
G03X1532776Y503514I163J365D01*
G02X1532888Y503706I1263J-608D01*
G03X1532777Y504270I-328J228D01*
G02X1534782Y504609I818J1260D01*
G03X1534863Y504040I316J-245D01*
G02X1533471Y501624I-824J-1134D01*
G03X1532948Y501432I-163J-365D01*
G02X1532695Y501067I-1264J606D01*
G03Y500513I288J-277D01*
G02X1532993Y500044I-1011J-972D01*
G37*
G36*
G01X1604781Y488209D02*
G03X1605313Y488186I279J286D01*
G02X1605221Y486096I887J-1086D01*
G03X1604689Y486119I-279J-286D01*
G02X1604781Y488209I-887J1086D01*
G37*
G36*
G01X1600429Y478233D02*
G03X1599828I-301J-264D01*
G02Y480217I-1128J992D01*
G03X1600429I300J264D01*
G02Y478233I1128J-992D01*
G37*
G36*
G01X1595520Y473218D02*
G03X1596145Y473174I330J226D01*
G02X1596056Y471386I1033J-948D01*
G03X1595430Y471403I-320J-240D01*
G02X1595520Y473218I-1150J967D01*
G37*
G36*
G01X1589693Y453068D02*
G03X1590295Y453064I303J261D01*
G02X1590283Y451217I1049J-930D01*
G03X1589681Y451221I-303J-261D01*
G02X1587504Y451319I-1049J930D01*
G03X1586902Y451367I-322J-238D01*
G02X1584927Y451378I-982J1001D01*
G03X1584325Y451338I-284J-282D01*
G02X1584201Y453175I-1117J847D01*
G03X1584803Y453215I284J282D01*
G02X1587048Y453200I1117J-847D01*
G03X1587650Y453152I322J238D01*
G02X1589693Y453068I982J-1001D01*
G37*
G36*
G01X1589919Y441621D02*
G03X1590461Y441606I279J286D01*
G02X1590397Y439397I985J-1134D01*
G03X1589855Y439412I-279J-286D01*
G02X1589919Y441621I-985J1134D01*
G37*
G36*
G01X1565558Y501438D02*
G02X1563954Y501658I-958J-1024D01*
G03X1564042Y502305I-185J355D01*
G02X1564155Y504448I958J1024D01*
G03X1564143Y505096I-241J320D01*
G02X1564150Y507568I857J1234D01*
G03X1564210Y508178I-226J330D01*
G02X1566054Y508041I1000J982D01*
G03X1566023Y507429I241J-319D01*
G02X1565857Y505096I-1023J-1100D01*
G03X1565845Y504448I229J-328D01*
G02X1565646Y502085I-845J-1119D01*
G03X1565558Y501438I185J-355D01*
G37*
G36*
G01X1596016Y494058D02*
G02X1593522Y494530I-1136J822D01*
G03X1592902Y494755I-387J-100D01*
G02X1590840Y495052I-877J1220D01*
G03X1590210I-315J-246D01*
G02Y496898I-1185J923D01*
G03X1590840I315J246D01*
G02X1593492Y496296I1185J-923D01*
G03X1594104Y496048I391J85D01*
G02X1595579Y496095I775J-1168D01*
G03X1596115Y496226I199J347D01*
G02X1598723Y496090I1265J-810D01*
G03X1599437I357J179D01*
G02X1601950Y496358I1343J-674D01*
G03X1602536Y496318I311J251D01*
G02X1602453Y494367I964J-1018D01*
G03X1601865Y494378I-299J-266D01*
G02X1599437Y494742I-1086J1038D01*
G03X1598723I-357J-179D01*
G02X1596559Y494159I-1342J674D01*
G03X1596016Y494058I-219J-335D01*
G37*
G36*
G01X1570800Y480997D02*
G02X1569699Y482101I-1375J-271D01*
G03X1570170Y482571I78J392D01*
G02X1571271Y481467I1375J271D01*
G03X1570800Y480997I-78J-392D01*
G37*
G36*
G01X1589493Y473407D02*
G02Y471333I1087J-1037D01*
G03X1588930Y471348I-289J-276D01*
G02X1586803Y471593I-960J1022D01*
G03X1586137I-333J-222D01*
G02Y473147I-1167J777D01*
G03X1586803I333J222D01*
G02X1588930Y473392I1167J-777D01*
G03X1589493Y473407I274J291D01*
G37*
G36*
G01X1755384Y34253D02*
G02X1756601Y35735I1511J-1D01*
G03X1756873Y36321I-78J392D01*
G02X1756865Y36336I1233J667D01*
G03X1756299Y36484I-352J-190D01*
G02X1754912Y36269I-899J1216D01*
G01X1754909Y36259D01*
X1754718Y36324D01*
X1754704Y36283D01*
G03X1754385Y35757I59J-396D01*
G02X1751822Y34641I-1325J-457D01*
G03X1751214Y34761I-353J-188D01*
G02X1750251Y34414I-964J1164D01*
G01X1746550D01*
G02X1745673Y37156I0J1511D01*
G03X1745687Y37796I-233J325D01*
G02X1745270Y38333I866J1103D01*
G03X1744593Y38421I-365J-162D01*
G02X1742368Y38473I-1093J879D01*
G03X1741742Y38498I-323J-236D01*
G02X1740556Y37975I-1144J988D01*
G01Y37965D01*
X1736654Y38080D01*
X1736483Y38104D01*
G02X1735904Y38315I217J1496D01*
G03X1735298Y38033I-210J-340D01*
G02X1732545Y37911I-1388J199D01*
G03X1731952Y38164I-389J-91D01*
G02X1731184Y37954I-769J1301D01*
G01X1727382D01*
G02X1726597Y38174I0J1511D01*
G03X1726027Y38003I-208J-341D01*
G02X1723365Y38444I-1269J597D01*
G03X1722714Y38709I-398J-44D01*
G02X1721758Y38368I-956J1171D01*
G01X1717958D01*
G02Y41392I0J1512D01*
G01X1721759D01*
G02X1723270Y39890I-1J-1512D01*
G01Y39795D01*
X1723260Y39711D01*
G02X1723229Y39532I-1502J168D01*
G03X1723590Y39376I195J-45D01*
G02X1725423Y39834I1168J-776D01*
G03X1725984Y40035I190J352D01*
G02X1727383Y40976I1400J-570D01*
G01X1731183D01*
G02X1732694Y39475I0J-1511D01*
G01Y39272D01*
X1732966D01*
X1733021Y39317D01*
G02X1734602Y39452I889J-1084D01*
G03X1735197Y39758I197J348D01*
G02X1736742Y41111I1503J-158D01*
G01Y41121D01*
X1740642Y41006D01*
X1740650Y40998D01*
X1740723Y40992D01*
G02X1741859Y40319I-125J-1506D01*
G03X1742483Y40265I333J221D01*
G02X1744782Y39867I1017J-965D01*
G03X1745459Y39779I365J162D01*
G02X1747624Y39804I1093J-879D01*
G03X1748248Y39820I306J258D01*
G02X1750371Y39947I1116J-849D01*
G03X1750917Y39920I287J278D01*
G02X1752488Y40296I1083J-1056D01*
G01X1752491Y40306D01*
X1755896Y39140D01*
Y39138D01*
X1756013Y39082D01*
G02X1756350Y38877I-611J-1383D01*
G01Y38875D01*
X1756360Y38868D01*
X1756362D01*
G02X1756780Y38318I-963J-1166D01*
G03X1757344Y38181I347J199D01*
G02X1758431Y35638I756J-1181D01*
G03X1758185Y35040I95J-389D01*
G02X1758406Y34262I-1290J-787D01*
G01Y30367D01*
X1758397Y30283D01*
G02X1755384Y30452I-1502J169D01*
G01Y34253D01*
G37*
G36*
G01X1857264Y39931D02*
G03X1856693Y39854I-248J-313D01*
G02X1856456Y42004I-1293J946D01*
G03X1857031Y42053I264J301D01*
G02X1859181Y42244I1167J-945D01*
G03X1859725Y42263I262J302D01*
G02X1859803Y40064I1061J-1063D01*
G03X1859259Y40045I-262J-302D01*
G02X1857264Y39931I-1061J1063D01*
G37*
G36*
G01X1809314Y38871D02*
G03X1809318Y38248I253J-310D01*
G02X1807510Y38197I-874J-1096D01*
G03X1807479Y38819I-267J298D01*
G02X1809314Y38871I884J1214D01*
G37*
G36*
G01X1792542Y35377D02*
G03X1792101Y34962I-42J-398D01*
G02X1790782Y36300I-1401J-62D01*
G03X1791204Y36735I24J399D01*
G02X1792542Y35377I1496J136D01*
G37*
G36*
G01X1799199Y36709D02*
G03X1799637Y36285I399J-26D01*
G02X1798372Y34915I137J-1395D01*
G03X1797915Y35317I-400J6D01*
G02X1799199Y36709I-215J1487D01*
G37*
G36*
G01X1854840Y35826D02*
G03X1855424Y35714I342J206D01*
G02X1855083Y33685I909J-1196D01*
G03X1854494Y33770I-333J-222D01*
G02X1854840Y35826I-1027J1230D01*
G37*
G36*
G01X1847518Y35563D02*
G03X1848044Y35562I264J301D01*
G02X1848036Y33298I983J-1135D01*
G03X1847510Y33299I-264J-301D01*
G02X1847518Y35563I-983J1135D01*
G37*
G36*
G01X1828965Y39990D02*
G02X1828078Y38655I615J-1371D01*
G03X1827515Y39030I-400J10D01*
G02X1826048Y39163I-615J1370D01*
G03X1825466Y39016I-226J-330D01*
G02X1824982Y40940I-1336J687D01*
G03X1825564Y41087I226J330D01*
G02X1828402Y40365I1336J-687D01*
G03X1828965Y39990I400J-10D01*
G37*
G36*
G01X1707856Y37356D02*
G02X1706640Y38395I-1356J-356D01*
G03X1707062Y38910I40J398D01*
G02X1708508Y40862I1446J440D01*
G01X1712309D01*
G02X1713820Y39360I-1J-1512D01*
G01Y39265D01*
X1713810Y39181D01*
G02X1712308Y37838I-1502J168D01*
G01X1708508D01*
G02X1708298Y37853I2J1512D01*
G03X1707856Y37356I-55J-396D01*
G37*
G36*
G01X1699272Y41190D02*
X1703074D01*
G02X1704584Y39689I-1J-1511D01*
G01Y39594D01*
X1704575Y39510D01*
G02X1703073Y38168I-1502J169D01*
G01X1699273D01*
G02X1698710Y38276I-2J1511D01*
G03X1698169Y37984I-149J-371D01*
G02X1695438Y37906I-1374J276D01*
G03X1694852Y38152I-387J-101D01*
G02X1694098Y37950I-755J1310D01*
G01X1689098D01*
G02X1688932Y37960I8J1512D01*
G03X1688734Y37666I-22J-199D01*
G02X1687351Y38394I-1234J-666D01*
G03X1687683Y38932I-43J398D01*
G02X1689098Y40974I1416J530D01*
G01X1694098D01*
G02X1695576Y39777I0J-1511D01*
G03X1696151Y39505I391J84D01*
G02X1697252Y39585I644J-1245D01*
G03X1697778Y39904I130J378D01*
G02X1699272Y41190I1494J-225D01*
G37*
G36*
G01X1679231Y37672D02*
G02X1677888Y38398I-1231J-672D01*
G03X1678231Y38936I-32J399D01*
G02X1679648Y40974I1417J526D01*
G01X1684649D01*
G02X1686160Y39472I-1J-1512D01*
G01Y39377D01*
X1686150Y39293D01*
G02X1684648Y37950I-1502J169D01*
G01X1679648D01*
G02X1679434Y37966I5J1512D01*
G03X1679231Y37672I-28J-198D01*
G37*
G36*
G01X1669327Y37479D02*
G02X1668331Y38365I-1318J-479D01*
G03X1668794Y38902I92J389D01*
G02X1670198Y40974I1404J560D01*
G01X1675199D01*
G02X1676710Y39472I-1J-1512D01*
G01Y39377D01*
X1676700Y39293D01*
G02X1675198Y37950I-1502J169D01*
G01X1670198D01*
G02X1669806Y38002I1J1512D01*
G03X1669327Y37479I-103J-386D01*
G37*
G36*
G01X1637398Y38350D02*
X1632398D01*
G02X1631984Y38408I1J1512D01*
G03X1631485Y37932I-110J-385D01*
G02X1629329Y36452I-1364J-323D01*
G03X1628720Y36240I-227J-330D01*
G02X1626461Y37710I-1340J412D01*
G03X1626196Y38412I-262J302D01*
G01X1622645Y38389D01*
G02X1622625Y41411I-10J1511D01*
G01X1627704Y41445D01*
G02X1628334Y41313I12J-1511D01*
G03X1628895Y41630I164J365D01*
G02X1631867Y41701I1491J-181D01*
G03X1632289Y41370I394J68D01*
G02X1632398Y41374I110J-1508D01*
G01X1637399D01*
G02X1638910Y39872I-1J-1512D01*
G01Y39869D01*
G03X1639379Y39481I400J6D01*
G02X1639901Y39474I243J-1381D01*
G03X1640371Y39782I79J392D01*
G02X1641848Y40974I1477J-320D01*
G01X1646849D01*
G02X1648307Y39857I-1J-1512D01*
G03X1648777Y39570I386J104D01*
G02X1649369I296J-1370D01*
G03X1649839Y39857I84J391D01*
G02X1651298Y40974I1459J-395D01*
G01X1656299D01*
G02X1657802Y39611I-1J-1512D01*
G03X1658279Y39264I397J45D01*
G02X1658784Y39274I280J-1374D01*
G03X1659245Y39625I64J395D01*
G02X1660748Y40974I1503J-163D01*
G01X1665749D01*
G02X1667260Y39472I-1J-1512D01*
G01Y39377D01*
X1667250Y39293D01*
G02X1665748Y37950I-1502J169D01*
G01X1662563D01*
G03X1662204Y37375I1J-400D01*
G02X1659608Y36337I-1260J-614D01*
G03X1659078Y36588I-382J-121D01*
G02X1657174Y37674I-519J1302D01*
G03X1656678Y37999I-395J-62D01*
G02X1656298Y37950I-382J1463D01*
G01X1652975D01*
G03X1652612Y37382I0J-400D01*
G02X1649770Y36492I-1362J-632D01*
G03X1649309Y36818I-394J-68D01*
G02X1647745Y37750I-236J1382D01*
G03X1647258Y38007I-379J-128D01*
G02X1646848Y37950I-411J1455D01*
G01X1641848D01*
G02X1641461Y38001I2J1512D01*
G03X1640973Y37722I-103J-387D01*
G02X1638223Y38021I-1350J378D01*
G03X1637735Y38388I-399J-23D01*
G02X1637398Y38350I-337J1474D01*
G37*
G36*
G01X1620382Y36912D02*
G02X1618932Y36396I-332J-1362D01*
G03X1618695Y37029I-319J242D01*
G02X1620166Y37553I305J1471D01*
G03X1620382Y36912I310J-252D01*
G37*
G36*
G01X1819357Y36830D02*
G02X1818427Y35215I443J-1330D01*
G03X1817892Y35507I-391J-81D01*
G02X1816377Y38051I-540J1402D01*
G03X1816342Y38687I-260J305D01*
G02X1818644Y40291I844J1242D01*
G03X1819332Y40123I388J97D01*
G02X1818999Y38766I1125J-995D01*
G03X1818311Y38934I-388J-97D01*
G02X1818161Y38787I-1124J996D01*
G03X1818196Y38151I260J-305D01*
G02X1818835Y37146I-844J-1242D01*
G03X1819357Y36830I395J63D01*
G37*
G36*
G01X1591580Y25295D02*
G02X1591546Y23679I1249J-835D01*
G03X1590872Y23693I-341J-208D01*
G02X1590906Y25309I-1249J835D01*
G03X1591580Y25295I341J208D01*
G37*
G36*
G01X1743152Y24708D02*
X1748153D01*
G02X1749664Y23207I0J-1512D01*
G01Y23112D01*
X1749654Y23028D01*
G02X1749652Y23011I-1502J168D01*
G03X1750025Y22562I397J-50D01*
G02X1748570Y21458I-85J-1399D01*
G03X1748349Y21698I-195J42D01*
G02X1748152Y21686I-190J1499D01*
G01X1743150D01*
G02X1742872Y21712I1J1511D01*
G03X1742399Y21292I-74J-393D01*
G02X1739644Y20843I-1399J-92D01*
G03X1739029Y21070I-387J-102D01*
G02X1738168Y20800I-862J1242D01*
G01X1733168D01*
G02X1732458Y20978I2J1512D01*
G03X1731889Y20743I-187J-353D01*
G02X1731147Y22428I-1339J416D01*
G03X1731705Y22690I170J362D01*
G02X1733168Y23824I1464J-378D01*
G01X1738169D01*
G02X1739644Y22636I-2J-1512D01*
G03X1740249Y22384I391J86D01*
G02X1741196Y22588I751J-1184D01*
G03X1741650Y23029I56J396D01*
G02X1743152Y24708I1502J168D01*
G37*
G54D24*
X1464553Y508872D03*
X1461267Y489790D03*
X1451533Y527867D03*
X1460661Y484891D03*
X1453533Y532667D03*
X1503400Y524663D03*
X1472500Y509810D03*
X1474400Y517200D03*
X1489380Y546030D03*
X1478700Y533700D03*
X1612100Y446000D03*
X1623705Y467855D03*
X1617300Y519000D03*
X1625485Y494188D03*
X1629500Y491500D03*
X1591350Y445300D03*
X1587573D03*
X1587550Y456550D03*
X1585155Y538574D03*
X1611642Y461877D03*
X1596500Y455500D03*
X1637482Y21623D03*
X1779750Y36530D03*
X1837500Y35700D03*
X1826414Y35486D03*
X1803300Y39900D03*
X1812352Y36949D03*
X1838500Y40400D03*
X1841060Y35540D03*
G54D34*
X1581730Y537170D03*
X1789356Y38286D03*
X1847797Y26331D03*
X1850600Y41348D03*
G54D29*
X1026500Y546400D03*
X1448800Y416500D03*
Y427800D03*
X1458300Y442675D03*
X1453700Y501600D03*
X1458060Y495020D03*
X1445750Y539000D03*
X1461500Y540000D03*
X1483400Y438100D03*
X1483115Y454379D03*
X1497275Y414694D03*
X1491425Y418074D03*
X1503125Y424834D03*
X1491425Y433406D03*
X1483818Y430597D03*
X1501219Y416596D03*
X1505442Y443900D03*
X1514825Y460446D03*
X1522625Y467206D03*
X1518725D03*
X1503125D03*
X1522625Y460446D03*
X1526525D03*
X1518725D03*
X1520675Y457066D03*
X1493375Y463826D03*
X1501175D03*
X1497275Y443546D03*
X1495325Y453686D03*
Y446926D03*
X1497275Y450306D03*
Y457066D03*
X1487525Y453686D03*
X1501175Y457066D03*
X1503125Y460446D03*
Y453786D03*
X1507025Y460446D03*
X1510925D03*
X1497275Y436786D03*
X1495325Y440166D03*
X1501175Y436786D03*
X1503125Y440166D03*
X1487525Y418074D03*
X1495325Y433406D03*
Y424834D03*
X1497275Y428214D03*
X1482500Y434600D03*
X1483200Y450455D03*
X1482000Y462028D03*
Y426595D03*
Y422658D03*
Y414783D03*
Y418720D03*
X1472449Y439421D03*
X1489475Y450306D03*
X1491425Y453686D03*
X1493375Y457066D03*
X1499225Y460446D03*
X1493375Y450306D03*
X1489475Y457066D03*
X1495325Y460446D03*
X1497275Y463826D03*
X1483375Y458375D03*
X1512875Y463826D03*
X1510925Y467206D03*
X1507025D03*
X1508975Y463826D03*
X1501175Y421454D03*
Y428214D03*
X1495325Y418074D03*
X1499225Y424834D03*
X1516775Y463826D03*
X1505075D03*
X1524575D03*
X1493375Y414694D03*
X1489475D03*
X1493375Y443546D03*
X1489475D03*
X1491425Y440166D03*
X1487525D03*
X1516775Y457066D03*
X1514825Y467206D03*
X1499225Y440166D03*
X1524575Y457066D03*
X1505075D03*
X1501175Y443546D03*
X1501200Y450600D03*
X1491425Y446926D03*
X1493375Y428214D03*
X1489475D03*
X1493375Y436786D03*
X1489475D03*
X1499225Y446926D03*
Y453686D03*
X1491425Y460446D03*
X1499225Y467206D03*
X1489475Y463826D03*
X1491425Y467206D03*
X1487525Y460446D03*
X1495325Y467206D03*
X1485030Y463690D03*
X1491400Y424600D03*
X1487500D03*
X1489475Y421454D03*
X1493375D03*
X1520675Y463826D03*
X1524950Y429350D03*
X1501490Y504988D03*
X1501934Y513047D03*
X1516775Y470586D03*
X1514825Y473966D03*
X1489475Y484106D03*
X1487525Y487486D03*
X1489475Y470586D03*
X1491425Y473966D03*
X1487525D03*
X1507025Y487486D03*
X1501175Y470586D03*
X1505075D03*
X1510925Y473966D03*
X1508975Y470586D03*
X1510925Y480726D03*
X1508975Y477346D03*
X1499225Y480726D03*
X1476800Y498900D03*
X1482000Y481713D03*
X1520675Y470586D03*
X1512875D03*
X1482200Y477800D03*
X1497275Y470586D03*
Y477346D03*
X1489475D03*
X1499225Y473966D03*
X1493375Y470586D03*
X1495325Y473966D03*
X1493375Y477346D03*
X1491425Y480726D03*
X1501175Y477346D03*
X1512875D03*
X1497275Y484106D03*
X1499225Y487486D03*
X1503125Y473966D03*
X1507025D03*
X1501175Y484106D03*
X1505075D03*
X1503125Y480726D03*
X1505075Y477346D03*
X1508975Y484106D03*
X1507025Y480726D03*
X1510925Y487486D03*
X1512875Y484106D03*
X1493375D03*
X1495325Y480726D03*
Y487486D03*
X1472250Y485100D03*
X1482958Y486118D03*
X1487525Y480726D03*
X1510740Y557860D03*
X1557725Y424834D03*
X1563575Y421454D03*
X1567475D03*
X1571375D03*
X1569425Y418074D03*
X1583208Y412815D03*
X1569425Y411314D03*
X1571375Y414694D03*
X1561625Y424834D03*
X1559675Y414694D03*
X1565525Y418074D03*
X1561625D03*
X1565525Y411314D03*
Y424834D03*
X1569425D03*
X1583208Y416752D03*
X1547000Y416750D03*
X1593400Y432200D03*
X1623814Y471400D03*
X1629530Y496374D03*
X1526525Y473966D03*
X1528475Y477346D03*
X1530425Y473966D03*
X1526525Y487486D03*
X1522625D03*
X1518725Y480726D03*
Y487486D03*
X1530425D03*
X1528475Y484106D03*
X1520675D03*
X1524575Y477346D03*
X1526525Y480726D03*
X1530425D03*
X1524575Y484106D03*
X1522625Y480726D03*
X1567475Y450306D03*
X1565525Y440166D03*
X1571375Y457066D03*
X1567475D03*
X1569425Y460446D03*
X1582200Y456200D03*
X1565525Y431594D03*
X1569425D03*
X1571390Y464480D03*
X1561625Y431594D03*
X1559675Y463826D03*
X1555775Y443546D03*
Y436786D03*
X1547975Y457066D03*
X1549925Y446926D03*
X1551875Y463826D03*
X1553825Y467206D03*
X1546025D03*
X1540175Y463826D03*
X1544075Y457066D03*
X1534325Y460446D03*
X1555775Y463826D03*
X1547975D03*
X1559675Y436786D03*
Y443546D03*
X1557725Y453686D03*
X1551875Y457066D03*
X1555775D03*
X1561625Y460446D03*
X1557725Y446926D03*
X1549938Y453714D03*
X1563575Y457066D03*
X1542125Y460446D03*
X1538225D03*
X1549925Y467206D03*
X1557725D03*
X1569425Y453686D03*
X1561625Y446926D03*
X1551875Y450306D03*
X1536275Y463826D03*
X1532375D03*
X1534325Y467206D03*
X1538225D03*
X1583773Y436137D03*
X1544075Y463826D03*
X1553825Y440166D03*
Y446926D03*
X1561625Y440166D03*
X1557725D03*
X1551875Y436786D03*
X1549925Y440166D03*
X1532349Y455200D03*
X1549925Y460446D03*
X1542125Y467206D03*
X1559595Y450631D03*
X1569425Y446926D03*
X1565525Y453686D03*
X1551875Y443546D03*
X1571375Y436786D03*
X1584200Y462610D03*
X1565525Y467206D03*
X1561625D03*
X1567475Y463826D03*
X1569425Y467206D03*
X1553825Y460446D03*
X1567475Y443546D03*
X1571375D03*
X1563575Y450306D03*
X1567475Y436786D03*
X1569425Y440166D03*
X1565525Y460446D03*
X1563575Y463826D03*
X1582300Y446100D03*
X1565525Y446926D03*
X1559675Y457066D03*
X1546025Y460446D03*
X1580370Y462090D03*
X1557725Y460446D03*
X1582644Y495077D03*
X1568600Y494500D03*
X1567817Y499735D03*
X1569425Y473966D03*
X1571375Y470586D03*
X1565525Y480726D03*
X1570062Y487039D03*
X1587433Y490425D03*
X1567475Y470586D03*
X1553825Y487486D03*
X1546025Y480726D03*
X1549925Y487486D03*
X1555775Y484106D03*
Y477346D03*
X1557725Y473966D03*
X1555775Y470586D03*
X1553825Y473966D03*
X1547975Y470586D03*
X1549925Y473966D03*
X1557725Y480726D03*
X1553825D03*
X1538225Y473966D03*
X1544075Y477346D03*
X1536275Y470586D03*
X1540175Y477346D03*
X1542125Y473966D03*
X1544075Y470586D03*
X1536275Y484106D03*
X1534325Y487486D03*
X1532375Y470586D03*
X1551875D03*
X1549925Y480726D03*
X1551875Y477346D03*
X1546025Y473966D03*
X1547975Y477346D03*
X1559675Y470586D03*
Y484106D03*
X1561625Y480726D03*
X1557725Y487486D03*
X1561625D03*
X1567475Y484106D03*
X1563575D03*
X1559675Y477346D03*
X1565525Y487486D03*
X1563575Y477346D03*
X1571375D03*
X1536275D03*
X1534325Y480726D03*
Y473966D03*
X1538225Y480726D03*
X1532375Y484106D03*
Y477346D03*
X1540175Y470586D03*
X1563575D03*
X1561625Y473966D03*
X1565525D03*
X1567475Y477346D03*
X1542125Y487486D03*
X1540175Y484106D03*
X1546025Y487486D03*
X1551875Y484106D03*
X1538225Y487486D03*
X1542125Y480726D03*
X1544075Y484106D03*
X1547975D03*
X1604200Y464387D03*
X1599900Y487100D03*
X1592200Y37700D03*
X1597800Y24300D03*
X1610450Y37300D03*
X1602840Y37382D03*
X1715259Y35602D03*
X1753903Y22116D03*
X1834300Y41100D03*
%LPD*%
G75*
G54D10*
X-17936Y-49379D03*
Y-53779D03*
Y-44979D03*
Y-40579D03*
X-18079Y-35764D03*
Y-58764D03*
X-17179Y643156D03*
X-17194Y638753D03*
X-17179Y647556D03*
Y660756D03*
Y651956D03*
Y656356D03*
X-13636Y-40479D03*
Y-44879D03*
Y-53679D03*
X-9079Y-50164D03*
X-4679D03*
X-279D03*
X-9079Y-54264D03*
X-4679D03*
X-279D03*
X22964Y-40379D03*
Y-44779D03*
Y-53579D03*
Y-49179D03*
X18964Y-53579D03*
Y-49179D03*
X13964Y-53579D03*
Y-49179D03*
X8964Y-40379D03*
Y-44779D03*
Y-53579D03*
Y-49179D03*
X3964Y-40379D03*
Y-44779D03*
Y-53579D03*
Y-49179D03*
X25921Y-35764D03*
X30321D03*
X43521D03*
X39121D03*
X34721D03*
X8321D03*
X12721D03*
X21521D03*
X17121D03*
X-13679D03*
X-9279D03*
X3921D03*
X-4879D03*
X-479D03*
X17121Y-58764D03*
X21521D03*
X12721D03*
X8321D03*
X34721D03*
X39121D03*
X43521D03*
X30321D03*
X25921D03*
X-479D03*
X-13679D03*
X-4879D03*
X3921D03*
X-13636Y-49279D03*
X-9279Y-58764D03*
X8343Y446875D03*
X1108Y455879D03*
X5743Y446875D03*
Y444275D03*
X-261Y450873D03*
Y453473D03*
X2339Y448273D03*
Y450873D03*
Y453473D03*
X-261Y445673D03*
X2339D03*
X-261Y448273D03*
X22421Y647556D03*
X26821D03*
X31221D03*
X18021D03*
Y643156D03*
X31221D03*
X26821D03*
X22421D03*
X18006Y638753D03*
X9221Y647556D03*
X13621D03*
Y643156D03*
X9221D03*
X4821D03*
Y647556D03*
X22406Y638753D03*
X26806D03*
X31206D03*
X-12794D03*
X-12779Y647556D03*
Y643156D03*
X40006Y638753D03*
X44406D03*
X35606D03*
X35621Y647556D03*
Y643156D03*
X18021Y660756D03*
X35621Y656356D03*
X26821Y660756D03*
X18021Y651956D03*
X31221D03*
X22421Y660756D03*
X26821Y651956D03*
X22421D03*
X4821D03*
X13621D03*
X9221D03*
X-8379Y660756D03*
X4821Y656356D03*
X9221D03*
X13621D03*
X-3979D03*
X421D03*
X13621Y660756D03*
X-3979D03*
X421D03*
X4821D03*
X-12779Y651956D03*
X22421Y656356D03*
X26821D03*
X31221D03*
X18021D03*
X-8379D03*
X-12779D03*
X31221Y660756D03*
X35621Y651956D03*
Y660756D03*
X44421D03*
X40021D03*
X-12779D03*
X9221D03*
X107921Y-58764D03*
X102921D03*
X97921D03*
X92921D03*
X87921D03*
X82921D03*
X77921D03*
X72921D03*
X67921D03*
X62921D03*
X57921D03*
X52921D03*
X47921Y-35764D03*
Y-58764D03*
X107921Y-35764D03*
X102921D03*
X97921D03*
X92921D03*
X87921D03*
X82921D03*
X77921D03*
X72921D03*
X67921D03*
X62921D03*
X57921D03*
X52921D03*
X99000Y230450D03*
Y227450D03*
Y233450D03*
X93800Y236450D03*
X96400D03*
Y230450D03*
Y227450D03*
X93800D03*
Y230450D03*
X96400Y233450D03*
X93800D03*
X99000Y236450D03*
X91200Y227450D03*
Y230450D03*
Y236450D03*
Y233450D03*
X88600D03*
Y236450D03*
Y230450D03*
Y227450D03*
X88200Y250400D03*
Y247400D03*
Y244400D03*
Y253400D03*
Y256300D03*
Y258900D03*
X90800Y244400D03*
Y250400D03*
Y247400D03*
X98600Y250400D03*
Y247400D03*
Y244400D03*
X93400Y250400D03*
Y247400D03*
Y244400D03*
X96000D03*
Y250400D03*
Y247400D03*
X90800Y253400D03*
Y256300D03*
Y258900D03*
X93400Y253400D03*
X96000D03*
X98600D03*
X96000Y258900D03*
X93400D03*
Y256300D03*
X96000D03*
X98600D03*
Y258900D03*
X103700Y397200D03*
X106400D03*
X101000D03*
X109100D03*
Y399900D03*
X101000D03*
X106400D03*
X103700D03*
X104517Y406279D03*
X105761Y409208D03*
X108010Y411479D03*
X93040Y496810D03*
X92990Y494210D03*
X93040Y499410D03*
X98240Y496810D03*
X95640D03*
X98240Y499410D03*
X95640D03*
X87790Y494210D03*
X90390D03*
X90440Y496810D03*
X87840D03*
X90390Y491610D03*
X87790D03*
X90440Y499410D03*
X87840D03*
X95777Y494213D03*
X48806Y638753D03*
X75206D03*
X106006D03*
X70806D03*
X53206D03*
X66406D03*
X92806D03*
X97206D03*
X101606D03*
X57606D03*
X62006D03*
X79606D03*
X84006D03*
X88406D03*
X53221Y660756D03*
X101621D03*
X97221D03*
X92821D03*
X106021D03*
X48821D03*
X70821D03*
X66421D03*
X62021D03*
X57621D03*
X75221D03*
X88421D03*
X84021D03*
X79621D03*
X167921Y-58764D03*
X162921D03*
X157921D03*
X152921D03*
X147921D03*
X142921D03*
X137921D03*
X132921D03*
X127921D03*
X122921D03*
X117921D03*
X112921D03*
X162921Y-35764D03*
X157921D03*
X152921D03*
X147921D03*
X142921D03*
X137921D03*
X132921D03*
X127921D03*
X122921D03*
X117921D03*
X112921D03*
X167921D03*
X166000Y212900D03*
X168600D03*
X164300Y207870D03*
X160800Y212900D03*
X163400D03*
X157800Y207300D03*
X161216Y209533D03*
Y206933D03*
X154500Y205500D03*
X150600Y212900D03*
X151000Y205500D03*
X140889Y211972D03*
X137615Y212039D03*
X143900Y204600D03*
X147500Y205500D03*
X137300Y204500D03*
X140200Y204400D03*
X153200Y212900D03*
X139815Y268974D03*
X137900Y272800D03*
X139800Y237000D03*
X165825Y239543D03*
X168425Y236943D03*
Y239543D03*
X165825Y236943D03*
X163225D03*
X152825D03*
X145025D03*
X147625D03*
X150225D03*
X142425D03*
X122231Y234716D03*
X125564Y237816D03*
X122632D03*
X163225Y239543D03*
X158025Y236943D03*
X155425D03*
X160625D03*
X142371Y244384D03*
X122231Y266716D03*
X122531Y269816D03*
X125463D03*
X142466Y268982D03*
X142700Y276200D03*
X136729Y276386D03*
X139683Y276174D03*
X163225Y242143D03*
X168425Y244743D03*
X165825D03*
X163225D03*
X168425Y242143D03*
X165825D03*
X150700Y276800D03*
X169150Y259470D03*
Y255470D03*
X157633Y268727D03*
X162833D03*
X160233D03*
X165433D03*
X168033Y271327D03*
X162833Y276527D03*
Y273927D03*
Y271327D03*
X165433Y276527D03*
Y273927D03*
Y271327D03*
X159983Y276507D03*
X168033Y276527D03*
Y273927D03*
Y268727D03*
X153300Y276800D03*
X139866Y333016D03*
X160233Y306257D03*
Y308857D03*
Y303657D03*
X157518Y335391D03*
X157745Y332800D03*
X139900Y302400D03*
X142433Y301057D03*
X147633D03*
X150233D03*
X145033D03*
X125500Y333500D03*
X122231Y330716D03*
X122731Y333916D03*
X145200Y341300D03*
X148200D03*
X142465Y332940D03*
X152833Y301057D03*
X163233Y306257D03*
Y308857D03*
X168433Y306257D03*
Y308857D03*
Y301057D03*
X165833D03*
X163233D03*
X160633D03*
X158033D03*
X155433D03*
X169150Y287600D03*
Y291600D03*
X165833Y306257D03*
X163233Y303657D03*
X168433D03*
X165833D03*
Y308857D03*
X151000Y341300D03*
X169150Y323600D03*
Y319600D03*
X160501Y332965D03*
X160274Y335556D03*
X165701Y338165D03*
Y335565D03*
X163101Y332965D03*
X168301D03*
X165701D03*
X163101Y335565D03*
X168301Y340765D03*
Y338165D03*
Y335565D03*
X163101Y338165D03*
Y340765D03*
X165701D03*
X154200Y341100D03*
X125663Y301716D03*
X122231Y298716D03*
X122731Y301716D03*
X139767Y364883D03*
X147833Y364457D03*
X125600Y364900D03*
X122600Y365500D03*
X122331Y362716D03*
X142421Y364908D03*
X145033Y364457D03*
X142863Y402829D03*
X140219Y402894D03*
X137619Y402900D03*
X134992D03*
X142818Y400163D03*
X143073Y397194D03*
X140475Y397310D03*
X140218Y400163D03*
X137529Y400296D03*
X134929D03*
X111561Y398819D03*
X122000Y397600D03*
X125300Y397700D03*
X122231Y394716D03*
X150633Y364457D03*
X167433Y369657D03*
X169150Y355600D03*
Y351600D03*
X167700Y363900D03*
X161833Y364457D03*
X164633D03*
X159033D03*
X156233D03*
X153433D03*
X164633Y369657D03*
X161833D03*
X161933Y372357D03*
X164733D03*
X167533D03*
X166340Y374785D03*
X167670Y383993D03*
Y387993D03*
X110406Y638753D03*
X145606D03*
X141206D03*
X136806D03*
X132406D03*
X158806D03*
X119206D03*
X123606D03*
X114806D03*
X128006D03*
X163206D03*
X154406D03*
X167606D03*
X150006D03*
X132421Y660756D03*
X145621D03*
X141221D03*
X136821D03*
X123621D03*
X114821D03*
X128021D03*
X110421D03*
X119221D03*
X150021D03*
X167621D03*
X163221D03*
X158821D03*
X154421D03*
X182921Y-58764D03*
X177921D03*
X172921D03*
X227921Y-35764D03*
X222921D03*
X217921D03*
X212921D03*
X207921D03*
X202921D03*
X197921D03*
X192921D03*
X187921D03*
X182921D03*
X177921D03*
X227921Y-58764D03*
X222921D03*
X217921D03*
X212921D03*
X207921D03*
X202921D03*
X197921D03*
X192921D03*
X187921D03*
X172921Y-35764D03*
X176300Y211900D03*
X182300Y216108D03*
X179300D03*
Y213208D03*
X176300Y217308D03*
Y214500D03*
X173300Y217700D03*
Y214800D03*
Y211900D03*
X176400Y234300D03*
X176508Y231609D03*
X179400Y234300D03*
X182400D03*
X176400Y239900D03*
X182400D03*
X179400D03*
X173400D03*
Y231400D03*
Y234300D03*
Y237000D03*
X176400D03*
X182400D03*
X179400D03*
X188200Y236800D03*
X188300Y234000D03*
X185250Y239850D03*
X204200Y249500D03*
X201100Y246500D03*
X198200Y249500D03*
Y246500D03*
X201200Y249500D03*
X203900Y246500D03*
X207200Y249500D03*
X185768Y270065D03*
X173835Y277804D03*
X198082Y277995D03*
X203847Y274933D03*
X203947Y277933D03*
X188510Y272666D03*
X176835Y277804D03*
X182935Y278204D03*
Y275604D03*
X191400Y278400D03*
X188475Y270065D03*
X185735Y275604D03*
X188600Y278300D03*
X188535Y275604D03*
X185735Y278204D03*
X195300Y229250D03*
X188100Y239800D03*
X185250Y234250D03*
Y236950D03*
X176835Y275204D03*
X185754Y272689D03*
X179835Y277804D03*
Y275204D03*
X195100Y252000D03*
X201200Y252500D03*
X198200D03*
X204200D03*
X207200D03*
X200947Y277933D03*
X200847Y274933D03*
X200947Y280933D03*
X173835Y275204D03*
X230800Y265200D03*
X224390Y258920D03*
X219500Y254500D03*
X190800Y295500D03*
X196956Y295583D03*
X193800Y295500D03*
X190665Y306877D03*
X198119Y339710D03*
X191792Y327743D03*
X197792Y327643D03*
X194792D03*
X184800Y295500D03*
X187956Y295583D03*
X181800Y295500D03*
X201177Y330728D03*
Y333728D03*
Y336728D03*
X201163Y339476D03*
Y342476D03*
X204177Y336728D03*
X204060Y342527D03*
X204163Y339476D03*
X188654Y330973D03*
Y327973D03*
X197684Y307227D03*
X200251Y306548D03*
X188630Y333923D03*
X190570Y309539D03*
X185630Y333923D03*
X172800Y295500D03*
Y298400D03*
X198182Y280995D03*
X178956Y295583D03*
X175800Y295500D03*
X187900Y306900D03*
X191300Y339800D03*
X172800Y304000D03*
X175800D03*
X178800D03*
X187800D03*
X181800D03*
X184800D03*
X172800Y301100D03*
X175800D03*
X178800D03*
X181800D03*
X187800D03*
X184800D03*
Y298400D03*
X181800D03*
X175800D03*
X178800D03*
X187800D03*
X185300Y336900D03*
X173300Y337000D03*
Y339900D03*
X188300D03*
Y336900D03*
X179300Y337000D03*
X176300Y339900D03*
X179300D03*
X182300D03*
Y337000D03*
X198223Y342430D03*
X176300Y337000D03*
X185300Y339900D03*
X224000Y330900D03*
X229100Y325900D03*
X219000Y335900D03*
X214000Y340900D03*
X197730Y309959D03*
X204060Y345527D03*
X191300Y343248D03*
X173300Y343448D03*
X188300Y343348D03*
X201045Y345449D03*
X198233Y345402D03*
X195233D03*
X176300Y343448D03*
X201045Y348449D03*
X198233Y348402D03*
Y351402D03*
X195233D03*
X173424Y359621D03*
X188424D03*
X188400Y369787D03*
X176400D03*
X179400Y366787D03*
Y369787D03*
X176400Y366787D03*
X173400Y369787D03*
Y366787D03*
X199900Y370400D03*
X182400Y366787D03*
Y369787D03*
X185400Y366787D03*
Y369787D03*
X188400Y366787D03*
X182424Y359621D03*
X185424D03*
X176424D03*
X179424D03*
X182300Y343448D03*
X173471Y363281D03*
X188471D03*
X182471D03*
X185471D03*
X176471D03*
X179471D03*
X174750Y386308D03*
Y383308D03*
X171158Y382768D03*
Y385768D03*
Y388768D03*
X187100Y394000D03*
X190100Y393000D03*
X197411Y374812D03*
X199754Y376090D03*
X174750Y389308D03*
X199900Y373400D03*
X179300Y343448D03*
X185300Y343348D03*
X211606Y638753D03*
X224806D03*
X220406D03*
X216006D03*
X189606D03*
X198406D03*
X202806D03*
X207206D03*
X176406D03*
X172006D03*
X185206D03*
X180806D03*
X194006D03*
X226500Y649900D03*
X229206Y638753D03*
X224821Y660756D03*
X220421D03*
X198421D03*
X211621D03*
X189621D03*
X202821D03*
X207221D03*
X194021D03*
X185221D03*
X172021D03*
X176421D03*
X180821D03*
X229221D03*
X216021D03*
X292921Y-35764D03*
X287921D03*
X282921D03*
X277921D03*
X272921D03*
X267921D03*
X262921D03*
X257921D03*
X252921D03*
X247921D03*
X242921D03*
X237921D03*
X232921D03*
X292921Y-58764D03*
X287921D03*
X282921D03*
X277921D03*
X272921D03*
X267921D03*
X262921D03*
X257921D03*
X252921D03*
X247921D03*
X242921D03*
X237921D03*
X232921D03*
X234501Y270392D03*
X234000Y320900D03*
X290806Y638753D03*
X268806D03*
X273206D03*
X277606D03*
X282006D03*
X260006D03*
X264406D03*
X255606D03*
X251206D03*
X286406D03*
X242406D03*
X246806D03*
X233606D03*
X238006D03*
X286421Y660756D03*
X268821D03*
X282021D03*
X273221D03*
X277621D03*
X264421D03*
X251221D03*
X255621D03*
X260021D03*
X246821D03*
X242421D03*
X238021D03*
X233621D03*
X290821D03*
X352921Y-58764D03*
Y-35764D03*
X347921Y-58764D03*
Y-35764D03*
X342921Y-58764D03*
Y-35764D03*
X337921Y-58764D03*
Y-35764D03*
X332921Y-58764D03*
Y-35764D03*
X327921Y-58764D03*
Y-35764D03*
X322921Y-58764D03*
Y-35764D03*
X317921Y-58764D03*
Y-35764D03*
X312921Y-58764D03*
X307921D03*
Y-35764D03*
X302921Y-58764D03*
Y-35764D03*
X297921D03*
Y-58764D03*
X312921Y-35764D03*
X330406Y638753D03*
X348006D03*
X326006D03*
X312806D03*
X317206D03*
X321606D03*
X352406D03*
X295206D03*
X299606D03*
X308406D03*
X304006D03*
X334806D03*
X339206D03*
X343606D03*
X312821Y660756D03*
X317221D03*
X308421D03*
X304021D03*
X352421D03*
X295221D03*
X326021D03*
X321621D03*
X339221D03*
X299621D03*
X334821D03*
X330421D03*
X343621D03*
X348021D03*
X392921Y-35764D03*
X387921Y-58764D03*
Y-35764D03*
X382921Y-58764D03*
Y-35764D03*
X377921Y-58764D03*
Y-35764D03*
X372921Y-58764D03*
Y-35764D03*
X367921Y-58764D03*
Y-35764D03*
X362921Y-58764D03*
Y-35764D03*
X357921Y-58764D03*
Y-35764D03*
X392921Y-58764D03*
X402921Y-35764D03*
X397921Y-58764D03*
Y-35764D03*
X412921Y-58764D03*
Y-35764D03*
X407921Y-58764D03*
Y-35764D03*
X402921Y-58764D03*
X385494Y309904D03*
X367914Y309910D03*
X371237Y309846D03*
X389502Y309910D03*
X389528Y292910D03*
X392694Y292904D03*
X368116Y293087D03*
X371094Y292904D03*
X373736Y293068D03*
X382625Y293207D03*
X378294Y292904D03*
X385494D03*
X392694Y309904D03*
X374994Y309910D03*
X382497D03*
X378577Y309795D03*
X366822Y324459D03*
X377894Y326777D03*
X378785Y329580D03*
X375223Y326798D03*
X369748Y326902D03*
X367121Y327057D03*
X372391Y326746D03*
X375848Y329512D03*
X407094Y292904D03*
X396897Y293058D03*
X399894Y292904D03*
X404266Y293030D03*
X407094Y309904D03*
X396709Y309910D03*
X399894Y309904D03*
X404117Y309910D03*
X383206Y638753D03*
X387606D03*
X392006D03*
X396406D03*
X400806D03*
X405206D03*
X409606D03*
X414006D03*
X370006D03*
X365606D03*
X374406D03*
X378806D03*
X356806D03*
X361206D03*
X374421Y660756D03*
X387621D03*
X383221D03*
X400821D03*
X396421D03*
X392021D03*
X405221D03*
X409621D03*
X414021D03*
X361221D03*
X365621D03*
X356821D03*
X370021D03*
X378821D03*
X477921Y-58764D03*
Y-35764D03*
X472921Y-58764D03*
Y-35764D03*
X467921Y-58764D03*
Y-35764D03*
X462921Y-58764D03*
Y-35764D03*
X457921Y-58764D03*
Y-35764D03*
X452921Y-58764D03*
Y-35764D03*
X447921Y-58764D03*
Y-35764D03*
X442921Y-58764D03*
Y-35764D03*
X437921Y-58764D03*
Y-35764D03*
X432921Y-58764D03*
X422921Y-35764D03*
X417921Y-58764D03*
Y-35764D03*
X432921D03*
X427921Y-58764D03*
Y-35764D03*
X422921Y-58764D03*
X466806Y638753D03*
X462406D03*
X475606D03*
X471206D03*
X418406D03*
X422806D03*
X427206D03*
X440406D03*
X436006D03*
X431606D03*
X449206D03*
X458006D03*
X453606D03*
X444806D03*
X458021Y660756D03*
X449221D03*
X462421D03*
X466821D03*
X471221D03*
X418421D03*
X475621D03*
X453621D03*
X422821D03*
X427221D03*
X440421D03*
X431621D03*
X436021D03*
X444821D03*
X537921Y-58764D03*
Y-35764D03*
X532921Y-58764D03*
Y-35764D03*
X527921Y-58764D03*
Y-35764D03*
X522921Y-58764D03*
Y-35764D03*
X517921Y-58764D03*
Y-35764D03*
X512921Y-58764D03*
Y-35764D03*
X507921Y-58764D03*
Y-35764D03*
X502921Y-58764D03*
Y-35764D03*
X497921Y-58764D03*
Y-35764D03*
X492921Y-58764D03*
Y-35764D03*
X487921Y-58764D03*
Y-35764D03*
X482921Y-58764D03*
Y-35764D03*
X480006Y638753D03*
X484406D03*
X488806D03*
X493206D03*
X497606D03*
X510806D03*
X537206D03*
X519606D03*
X524006D03*
X532806D03*
X528406D03*
X515206D03*
X502006D03*
X506406D03*
X524021Y660756D03*
X480021D03*
X484421D03*
X497621D03*
X493221D03*
X488821D03*
X519621D03*
X532821D03*
X537221D03*
X528421D03*
X515221D03*
X510821D03*
X506421D03*
X502021D03*
X597921Y-35764D03*
Y-58764D03*
X592921Y-35764D03*
Y-58764D03*
X587921Y-35764D03*
Y-58764D03*
X582921Y-35764D03*
Y-58764D03*
X577921Y-35764D03*
Y-58764D03*
X572921Y-35764D03*
Y-58764D03*
X567921Y-35764D03*
Y-58764D03*
X562921Y-35764D03*
Y-58764D03*
X557921Y-35764D03*
Y-58764D03*
X552921Y-35764D03*
Y-58764D03*
X547921D03*
Y-35764D03*
X542921Y-58764D03*
Y-35764D03*
X590006Y638753D03*
X572406D03*
X559206D03*
X568006D03*
X563606D03*
X550406D03*
X581206D03*
X585606D03*
X576806D03*
X598806D03*
X594406D03*
X601500Y649500D03*
X554806Y638753D03*
X541606D03*
X546006D03*
X559221Y660756D03*
X546021D03*
X554821D03*
X598821D03*
X572421D03*
X568021D03*
X563621D03*
X585621D03*
X541621D03*
X594421D03*
X576821D03*
X590021D03*
X581221D03*
X550421D03*
X637921Y-58764D03*
X632921Y-35764D03*
Y-58764D03*
X627921Y-35764D03*
Y-58764D03*
X622921Y-35764D03*
Y-58764D03*
X617921Y-35764D03*
Y-58764D03*
X612921Y-35764D03*
Y-58764D03*
X607921Y-35764D03*
Y-58764D03*
X602921Y-35764D03*
Y-58764D03*
X652921Y-35764D03*
Y-58764D03*
X647921Y-35764D03*
Y-58764D03*
X642921Y-35764D03*
Y-58764D03*
X637921Y-35764D03*
X662921D03*
Y-58764D03*
X657921Y-35764D03*
Y-58764D03*
X653750Y225500D03*
X641600Y221400D03*
Y226600D03*
Y224000D03*
Y229200D03*
X644500D03*
Y224000D03*
Y226600D03*
X641600Y231800D03*
X644500D03*
X650700Y224000D03*
X647600D03*
X650700Y226600D03*
X647600D03*
X650700Y231800D03*
X647600D03*
Y229200D03*
X650700D03*
X641541Y236028D03*
Y238628D03*
X637001Y227337D03*
Y222137D03*
Y224737D03*
Y229937D03*
X641541Y243828D03*
Y241228D03*
X638406Y638753D03*
X634006D03*
X642806D03*
X629606D03*
X616406D03*
X612006D03*
X603206D03*
X625206D03*
X651606D03*
X647206D03*
X660406D03*
X620806D03*
X656006D03*
X607606D03*
X607621Y660756D03*
X638421D03*
X647221D03*
X616421D03*
X634021D03*
X612021D03*
X620821D03*
X625221D03*
X629621D03*
X642821D03*
X603221D03*
X656021D03*
X660421D03*
X651621D03*
X692921Y-58764D03*
X687921Y-35764D03*
Y-58764D03*
X682921Y-35764D03*
Y-58764D03*
X677921Y-35764D03*
Y-58764D03*
X672921Y-35764D03*
Y-58764D03*
X667921Y-35764D03*
Y-58764D03*
X697921Y-35764D03*
Y-58764D03*
X692921Y-35764D03*
X722921D03*
Y-58764D03*
X717921Y-35764D03*
Y-58764D03*
X712921Y-35764D03*
Y-58764D03*
X707921Y-35764D03*
Y-58764D03*
X702921Y-35764D03*
Y-58764D03*
X706164Y390143D03*
X708975Y390174D03*
X711575Y390150D03*
Y393150D03*
X706164Y393143D03*
X708975Y393174D03*
X703160Y392939D03*
X700391Y389737D03*
X703160Y390139D03*
X700291Y392637D03*
X700458Y395503D03*
X703169Y395986D03*
X711575Y396150D03*
X708975Y396174D03*
X706164Y396143D03*
X705673Y387012D03*
Y384412D03*
X711173Y387012D03*
X708373D03*
Y384412D03*
X700204Y386610D03*
X702973Y387012D03*
X700204Y384010D03*
X702973Y384412D03*
X711173Y384312D03*
X695606Y638753D03*
X673606D03*
X708806D03*
X704406D03*
X700006D03*
X722006D03*
X717606D03*
X713206D03*
X664806D03*
X669206D03*
X686806D03*
X682406D03*
X678006D03*
X691206D03*
X664821Y660756D03*
X695621D03*
X708821D03*
X700021D03*
X704421D03*
X669221D03*
X686821D03*
X691221D03*
X678021D03*
X673621D03*
X682421D03*
X722021D03*
X717621D03*
X713221D03*
X777921Y-58764D03*
X772921Y-35764D03*
Y-58764D03*
X767921Y-35764D03*
Y-58764D03*
X762921Y-35764D03*
Y-58764D03*
X757921Y-35764D03*
Y-58764D03*
X752921Y-35764D03*
Y-58764D03*
X787921Y-35764D03*
Y-58764D03*
X782921Y-35764D03*
Y-58764D03*
X777921Y-35764D03*
X747921D03*
Y-58764D03*
X742921Y-35764D03*
Y-58764D03*
X737921Y-35764D03*
Y-58764D03*
X732921Y-35764D03*
Y-58764D03*
X727921Y-35764D03*
Y-58764D03*
X786674Y211463D03*
X785920Y204763D03*
X786300Y207400D03*
X787200Y244200D03*
Y271900D03*
X787100Y241100D03*
X770632Y234833D03*
X770965Y237519D03*
X773800Y237700D03*
X768382Y237861D03*
X769637Y266647D03*
X770485Y269489D03*
X772630Y266810D03*
X787200Y276400D03*
X787100Y303900D03*
X775200Y301200D03*
X770900Y301800D03*
X768290Y301780D03*
X747498Y335516D03*
X750298Y338316D03*
Y335516D03*
X744698Y338316D03*
Y335516D03*
X747498Y338316D03*
X769440Y298735D03*
X772400Y299400D03*
X787000Y308300D03*
X771730Y330665D03*
X775732Y332989D03*
X770278Y333272D03*
X772949Y333009D03*
X787400Y340400D03*
X747000Y386000D03*
X743500D03*
X750500D03*
X754000D03*
X750298Y344833D03*
X744698Y347833D03*
X747498D03*
X750298D03*
X747673Y364009D03*
X745073D03*
X750273D03*
X747573Y366909D03*
X744973D03*
X750173D03*
X744698Y344833D03*
X747498D03*
X747000Y380000D03*
X743500D03*
X753874Y379863D03*
X750500Y380000D03*
Y374000D03*
X754000D03*
X747000D03*
X743500D03*
X769380Y366440D03*
X775070Y365070D03*
X772290Y365020D03*
X769440Y363810D03*
X775420Y397110D03*
X772742Y397209D03*
X766860Y396240D03*
X769770Y396070D03*
X770406Y638753D03*
X779206D03*
X774806D03*
X730806D03*
X726406D03*
X739606D03*
X735206D03*
X748406D03*
X744006D03*
X766006D03*
X761606D03*
X757206D03*
X752806D03*
X783606D03*
X744021Y660756D03*
X735221D03*
X779221D03*
X770421D03*
X774821D03*
X726421D03*
X730821D03*
X739621D03*
X748421D03*
X783621D03*
X757221D03*
X761621D03*
X752821D03*
X766021D03*
X842921Y-35764D03*
X837921Y-58764D03*
Y-35764D03*
X832921Y-58764D03*
X847921D03*
Y-35764D03*
X842921Y-58764D03*
X832921Y-35764D03*
X827921Y-58764D03*
Y-35764D03*
X822921Y-58764D03*
Y-35764D03*
X817921Y-58764D03*
Y-35764D03*
X812921Y-58764D03*
Y-35764D03*
X807921Y-58764D03*
Y-35764D03*
X802921Y-58764D03*
Y-35764D03*
X797921D03*
Y-58764D03*
X792921Y-35764D03*
Y-58764D03*
X816900Y216300D03*
X816874Y212863D03*
X814274D03*
X811674D03*
X808818Y211179D03*
X808618Y208579D03*
X803200Y213100D03*
X800600D03*
X794474Y211463D03*
X791874D03*
X789274D03*
X788522Y204343D03*
X791122Y204339D03*
X829327Y214740D03*
X832276Y214754D03*
X827322Y217430D03*
X826700Y214802D03*
X824072Y214865D03*
X824446Y217476D03*
X821775Y217617D03*
X821466Y214925D03*
X789432Y236947D03*
X789400Y273700D03*
X811983Y244843D03*
Y242243D03*
X814583Y239643D03*
X815432Y237000D03*
X814583Y244843D03*
Y242243D03*
X812832Y237000D03*
X811983Y239643D03*
X802432Y237000D03*
X799832D03*
X792032D03*
X794632D03*
X810232D03*
X797232D03*
X805032D03*
X807632D03*
X791000Y244400D03*
X793600D03*
X816800Y234300D03*
X816900Y230900D03*
X817000Y252500D03*
X789800Y276400D03*
X792400D03*
X801991Y276557D03*
X804591D03*
X792191Y269101D03*
X789591D03*
X814891Y271657D03*
Y274257D03*
Y276857D03*
Y269057D03*
X812291D03*
Y274257D03*
Y276857D03*
Y271657D03*
X817000Y255100D03*
Y257700D03*
X848282Y251727D03*
X828180Y231748D03*
X828682Y237027D03*
X831682D03*
X828682Y234327D03*
X837500Y239500D03*
X845050Y229400D03*
X837500Y234050D03*
Y236650D03*
X834682Y236877D03*
X840155Y234245D03*
X834700Y234200D03*
X831682Y234327D03*
X834682Y239627D03*
X831682D03*
X828682D03*
X848282Y246427D03*
Y249027D03*
X825682Y239627D03*
Y234327D03*
Y237027D03*
X825313Y231753D03*
X848382Y279727D03*
Y277027D03*
Y274427D03*
X825464Y277510D03*
Y274910D03*
Y280110D03*
X822464D03*
Y277510D03*
Y274910D03*
X834464Y280110D03*
X831464D03*
X828464Y277510D03*
Y274910D03*
Y280110D03*
X834464Y277510D03*
X831464D03*
X834464Y274910D03*
X845050Y252250D03*
X817491Y276857D03*
Y274257D03*
Y271657D03*
Y269057D03*
X837264Y274910D03*
Y280110D03*
Y277510D03*
X840064D03*
Y280110D03*
X817183Y242243D03*
Y239643D03*
Y244843D03*
X818032Y237000D03*
X822682Y234327D03*
Y231727D03*
Y237027D03*
Y239627D03*
X831464Y274910D03*
X844400Y280500D03*
X848282Y254327D03*
X788600Y306100D03*
X789500Y301200D03*
X797300D03*
X799900D03*
X810300D03*
X802500D03*
X812900D03*
X807700D03*
X805100D03*
X815500D03*
X811991Y308957D03*
Y306357D03*
Y303757D03*
X814591Y306357D03*
Y308957D03*
Y303757D03*
X792900Y308400D03*
X789900D03*
X794700Y301200D03*
X792100D03*
X793000Y340400D03*
X790300Y340300D03*
X816991Y337357D03*
Y334757D03*
Y339957D03*
X814391D03*
Y337357D03*
Y334757D03*
X811791Y337357D03*
Y339957D03*
Y334757D03*
X791879Y332798D03*
X794600Y332600D03*
X816938Y319888D03*
Y323888D03*
X817100Y317000D03*
X848382Y282327D03*
X834682Y298527D03*
X828682D03*
X825682D03*
Y295527D03*
Y301227D03*
Y303927D03*
X822682D03*
Y301227D03*
Y295527D03*
Y298527D03*
X844300Y312450D03*
X831682Y298527D03*
X837782Y298127D03*
Y301027D03*
Y303927D03*
X818100Y301200D03*
X817191Y303757D03*
Y306357D03*
Y308957D03*
X834682Y301227D03*
X831682D03*
X828682D03*
X831682Y303927D03*
X834682D03*
X822482Y339827D03*
Y337027D03*
X831482D03*
X834482D03*
X828482Y339827D03*
X831482D03*
X834482D03*
X840282Y340227D03*
X840382Y337427D03*
X837382Y339877D03*
Y337077D03*
X847682Y314627D03*
X847982Y338327D03*
Y341327D03*
X828482Y337027D03*
X828682Y303927D03*
X847682Y309327D03*
Y312027D03*
Y306727D03*
X825482Y339827D03*
Y337027D03*
X789860Y364947D03*
X820218Y385950D03*
Y382950D03*
X826097Y385923D03*
X816591Y369857D03*
Y372457D03*
X811391Y369857D03*
X813991D03*
Y372457D03*
X811391D03*
X790900Y372300D03*
X788300Y372400D03*
X802759Y364575D03*
X816672Y358809D03*
X795310Y364721D03*
X816593Y356210D03*
X807959Y364575D03*
X805359D03*
X810559D03*
X815759D03*
X813159D03*
X816900Y361400D03*
X792610Y364821D03*
X816591Y375057D03*
X792238Y396753D03*
X789600Y396809D03*
X811515Y397289D03*
X808915D03*
X813648Y395557D03*
X815472Y390442D03*
X814877Y393138D03*
X792000Y399409D03*
X789400D03*
X822089Y362782D03*
Y359782D03*
X822482Y342827D03*
X828482D03*
X831482D03*
X834482D03*
X828089Y359841D03*
X834089D03*
X831089D03*
X844350Y344000D03*
X840262Y343011D03*
X837382Y342877D03*
X821658Y369463D03*
X832058Y366863D03*
Y369463D03*
X834658D03*
Y366863D03*
X837363Y366829D03*
X826858Y366863D03*
Y369463D03*
X824258Y366863D03*
Y369463D03*
X829458D03*
Y366863D03*
X821658D03*
X847982Y344327D03*
X834089Y362782D03*
X831089D03*
X826216Y383108D03*
X823218Y382950D03*
X848608Y376068D03*
Y378668D03*
X846008Y376068D03*
Y378668D03*
X848932Y373257D03*
X823218Y385950D03*
X828089Y362782D03*
X825482Y342827D03*
X825089Y359841D03*
Y362782D03*
X849606Y638753D03*
X836406D03*
X832006D03*
X796806D03*
X801206D03*
X792406D03*
X827606D03*
X818806D03*
X823206D03*
X810006D03*
X788006D03*
X845206D03*
X814406D03*
X805606D03*
X840806D03*
X849621Y660756D03*
X832021D03*
X810021D03*
X818821D03*
X836421D03*
X788021D03*
X814421D03*
X801221D03*
X805621D03*
X823221D03*
X827621D03*
X840821D03*
X796821D03*
X792421D03*
X845221D03*
X907921Y-58764D03*
Y-35764D03*
X902921Y-58764D03*
Y-35764D03*
X897921Y-58764D03*
Y-35764D03*
X892921Y-58764D03*
Y-35764D03*
X887921Y-58764D03*
Y-35764D03*
X882921Y-58764D03*
Y-35764D03*
X877921Y-58764D03*
Y-35764D03*
X872921Y-58764D03*
Y-35764D03*
X867921Y-58764D03*
Y-35764D03*
X862921Y-58764D03*
Y-35764D03*
X857921Y-58764D03*
Y-35764D03*
X852921Y-58764D03*
Y-35764D03*
X854282Y251727D03*
X857282D03*
X851282D03*
X857282Y249027D03*
Y246427D03*
X851282D03*
Y249027D03*
X854282D03*
Y246427D03*
X851382Y277027D03*
Y274427D03*
X857382Y277027D03*
X854382Y279727D03*
X857382D03*
X854382Y274427D03*
X857382D03*
X854382Y277027D03*
X874586Y259278D03*
X854282Y254327D03*
X857282D03*
X869586Y254278D03*
X851282Y254327D03*
X851382Y279727D03*
X884586Y269278D03*
X879586Y264278D03*
X889586Y274278D03*
X851382Y282327D03*
X854382D03*
X857382D03*
X851075Y335405D03*
X857075D03*
X856982Y338327D03*
X853982D03*
X856682Y314627D03*
X853682D03*
X850682D03*
X856982Y341327D03*
X853982D03*
X862008Y341100D03*
X850982Y338327D03*
Y341327D03*
X872008Y331100D03*
X867008Y336100D03*
X850682Y306727D03*
Y309327D03*
Y312027D03*
X856682Y309327D03*
X853682D03*
X856682Y306727D03*
X853682D03*
X856682Y312027D03*
X853682D03*
X877008Y326100D03*
X854075Y335405D03*
X856982Y344327D03*
X853982D03*
X850982D03*
X851208Y376068D03*
Y378668D03*
X851727Y373197D03*
X858406Y638753D03*
X854006D03*
X884806D03*
X880406D03*
X876006D03*
X871606D03*
X867206D03*
X911206D03*
X906806D03*
X889206D03*
X898006D03*
X902406D03*
X893606D03*
X862806D03*
X854021Y660756D03*
X858421D03*
X862821D03*
X898021D03*
X902421D03*
X871621D03*
X884821D03*
X893621D03*
X867221D03*
X889221D03*
X911221D03*
X906821D03*
X880421D03*
X876021D03*
X937921Y-35764D03*
X932921Y-58764D03*
Y-35764D03*
X927921Y-58764D03*
Y-35764D03*
X922921Y-58764D03*
Y-35764D03*
X917921Y-58764D03*
Y-35764D03*
X912921Y-58764D03*
Y-35764D03*
X942921D03*
X967921D03*
X962921Y-58764D03*
Y-35764D03*
X957921Y-58764D03*
Y-35764D03*
X952921Y-58764D03*
Y-35764D03*
X947921Y-58764D03*
Y-35764D03*
X942921Y-58764D03*
X972921D03*
Y-35764D03*
X967921Y-58764D03*
X937921D03*
X924406Y638753D03*
X920006D03*
X915606D03*
X972806D03*
X968406D03*
X964006D03*
X917100Y649300D03*
X942006Y638753D03*
X937606D03*
X933206D03*
X928806D03*
X959606D03*
X955206D03*
X950806D03*
X946406D03*
X959621Y660756D03*
X964021D03*
X968421D03*
X972821D03*
X920021D03*
X915621D03*
X924421D03*
X946421D03*
X942021D03*
X937621D03*
X933221D03*
X928821D03*
X955221D03*
X950821D03*
X1002921Y-58764D03*
Y-35764D03*
X997921Y-58764D03*
Y-35764D03*
X992921Y-58764D03*
Y-35764D03*
X987921Y-58764D03*
Y-35764D03*
X982921Y-58764D03*
Y-35764D03*
X977921Y-58764D03*
Y-35764D03*
X1032921Y-58764D03*
Y-35764D03*
X1027921Y-58764D03*
Y-35764D03*
X1022921Y-58764D03*
Y-35764D03*
X1017921Y-58764D03*
Y-35764D03*
X1012921Y-58764D03*
Y-35764D03*
X1007921Y-58764D03*
Y-35764D03*
X1024994Y292918D03*
X1017630Y292910D03*
X1020702Y292904D03*
X1027902D03*
X1031953Y292910D03*
X1024140Y309910D03*
X1021065Y309759D03*
X1017083Y309910D03*
X1032042D03*
X1028136Y309815D03*
X1003606Y638753D03*
X1012406D03*
X977206D03*
X990406D03*
X986006D03*
X994806D03*
X1016806D03*
X1021206D03*
X981606D03*
X999206D03*
X1025606D03*
X1008006D03*
X1030006D03*
X1034406D03*
X999221Y660756D03*
X1034421D03*
X1030021D03*
X1008021D03*
X1012421D03*
X1003621D03*
X1016821D03*
X977221D03*
X981621D03*
X1021221D03*
X1025621D03*
X994821D03*
X986021D03*
X990421D03*
X1067921Y-58764D03*
Y-35764D03*
X1062921Y-58764D03*
Y-35764D03*
X1057921Y-58764D03*
Y-35764D03*
X1052921Y-58764D03*
Y-35764D03*
X1047921Y-58764D03*
Y-35764D03*
X1042921Y-58764D03*
Y-35764D03*
X1037921Y-58764D03*
Y-35764D03*
X1092921Y-58764D03*
Y-35764D03*
X1087921Y-58764D03*
Y-35764D03*
X1082921Y-58764D03*
Y-35764D03*
X1077921Y-58764D03*
Y-35764D03*
X1072921Y-58764D03*
Y-35764D03*
X1046276Y292910D03*
X1049502Y292904D03*
X1053684Y292910D03*
X1056702Y292904D03*
X1039182Y292919D03*
X1042302Y292904D03*
X1035102D03*
X1049547Y309904D03*
X1046612Y309910D03*
X1056747Y309904D03*
X1053594Y309910D03*
X1042347Y309904D03*
X1039383Y309910D03*
X1035147Y309904D03*
X1086126Y338758D03*
X1083301Y338841D03*
X1096006Y638753D03*
X1078406D03*
X1082806D03*
X1074006D03*
X1069606D03*
X1091606D03*
X1052006D03*
X1038806D03*
X1087206D03*
X1060806D03*
X1056406D03*
X1065206D03*
X1043206D03*
X1047606D03*
X1078421Y660756D03*
X1060821D03*
X1087221D03*
X1038821D03*
X1091621D03*
X1052021D03*
X1074021D03*
X1065221D03*
X1096021D03*
X1056421D03*
X1043221D03*
X1047621D03*
X1082821D03*
X1069621D03*
X1157921Y-58764D03*
Y-35764D03*
X1152921Y-58764D03*
Y-35764D03*
X1147921Y-58764D03*
Y-35764D03*
X1142921Y-58764D03*
Y-35764D03*
X1137921Y-58764D03*
Y-35764D03*
X1132921Y-58764D03*
Y-35764D03*
X1127921Y-58764D03*
Y-35764D03*
X1122921Y-58764D03*
Y-35764D03*
X1117921Y-58764D03*
Y-35764D03*
X1112921Y-58764D03*
Y-35764D03*
X1107921Y-58764D03*
Y-35764D03*
X1102921Y-58764D03*
Y-35764D03*
X1097921Y-58764D03*
Y-35764D03*
X1135606Y638753D03*
X1126806D03*
X1144406D03*
X1140006D03*
X1118006D03*
X1122406D03*
X1153206D03*
X1157606D03*
X1104806D03*
X1100406D03*
X1131206D03*
X1148806D03*
X1109206D03*
X1113606D03*
X1157621Y660756D03*
X1148821D03*
X1122421D03*
X1126821D03*
X1100421D03*
X1118021D03*
X1140021D03*
X1113621D03*
X1109221D03*
X1153221D03*
X1144421D03*
X1104821D03*
X1131221D03*
X1135621D03*
X1217921Y-58764D03*
Y-35764D03*
X1212921Y-58764D03*
Y-35764D03*
X1207921Y-58764D03*
Y-35764D03*
X1202921Y-58764D03*
Y-35764D03*
X1197921Y-58764D03*
Y-35764D03*
X1192921Y-58764D03*
Y-35764D03*
X1187921Y-58764D03*
Y-35764D03*
X1182921Y-58764D03*
Y-35764D03*
X1177921Y-58764D03*
Y-35764D03*
X1172921Y-58764D03*
Y-35764D03*
X1167921Y-58764D03*
Y-35764D03*
X1162921Y-58764D03*
Y-35764D03*
X1188406Y638753D03*
X1214806D03*
X1197206D03*
X1201606D03*
X1192806D03*
X1170806D03*
X1162006D03*
X1166406D03*
X1206006D03*
X1219206D03*
X1179606D03*
X1175206D03*
X1210406D03*
X1184006D03*
X1184021Y660756D03*
X1219221D03*
X1192821D03*
X1188421D03*
X1201621D03*
X1179621D03*
X1214821D03*
X1206021D03*
X1166421D03*
X1210421D03*
X1170821D03*
X1162021D03*
X1175221D03*
X1197221D03*
X1232921Y-58764D03*
Y-35764D03*
X1227921Y-58764D03*
Y-35764D03*
X1222921Y-58764D03*
Y-35764D03*
X1252921Y-58764D03*
Y-35764D03*
X1247921Y-58764D03*
Y-35764D03*
X1242921Y-58764D03*
Y-35764D03*
X1237921Y-58764D03*
Y-35764D03*
X1257921D03*
X1272921Y-58764D03*
Y-35764D03*
X1267921Y-58764D03*
Y-35764D03*
X1262921Y-58764D03*
Y-35764D03*
X1257921Y-58764D03*
X1277921D03*
Y-35764D03*
X1263206Y638753D03*
X1223606D03*
X1228006D03*
X1258806D03*
X1241206D03*
X1236806D03*
X1250006D03*
X1245606D03*
X1276406D03*
X1254406D03*
X1280806D03*
X1272006D03*
X1267606D03*
X1232406D03*
X1228021Y660756D03*
X1232421D03*
X1280821D03*
X1245621D03*
X1236821D03*
X1223621D03*
X1276421D03*
X1241221D03*
X1272021D03*
X1258821D03*
X1250021D03*
X1254421D03*
X1263221D03*
X1267621D03*
X1342921Y-35764D03*
Y-58764D03*
X1317921D03*
X1312921Y-35764D03*
Y-58764D03*
X1307921Y-35764D03*
Y-58764D03*
X1302921Y-35764D03*
Y-58764D03*
X1297921D03*
Y-35764D03*
X1292921Y-58764D03*
Y-35764D03*
X1287921Y-58764D03*
Y-35764D03*
X1282921Y-58764D03*
Y-35764D03*
X1322921D03*
Y-58764D03*
X1317921Y-35764D03*
X1337921D03*
Y-58764D03*
X1332921Y-35764D03*
Y-58764D03*
X1327921Y-35764D03*
Y-58764D03*
X1324806Y638753D03*
X1298406D03*
X1285206D03*
X1294006D03*
X1302806D03*
X1333606D03*
X1338006D03*
X1320406D03*
X1311606D03*
X1329206D03*
X1307206D03*
X1342406D03*
X1289606D03*
X1316006D03*
X1329221Y660756D03*
X1311621D03*
X1316021D03*
X1333621D03*
X1342421D03*
X1285221D03*
X1324821D03*
X1338021D03*
X1298421D03*
X1289621D03*
X1294021D03*
X1320421D03*
X1302821D03*
X1307221D03*
X1402921Y-58764D03*
X1397921D03*
X1402921Y-35764D03*
X1392921Y-58764D03*
X1397921Y-35764D03*
X1387921Y-58764D03*
X1392921Y-35764D03*
X1382921Y-58764D03*
X1387921Y-35764D03*
X1377921Y-58764D03*
X1382921Y-35764D03*
X1372921Y-58764D03*
X1377921Y-35764D03*
X1367921Y-58764D03*
X1362921Y-35764D03*
Y-58764D03*
X1357921Y-35764D03*
Y-58764D03*
X1352921Y-35764D03*
Y-58764D03*
X1347921Y-35764D03*
Y-58764D03*
X1351206Y638753D03*
X1360006D03*
X1404506Y638853D03*
X1355606Y638753D03*
X1386906Y638853D03*
X1364406Y638753D03*
X1391306Y638853D03*
X1346806Y638753D03*
X1400106Y638853D03*
X1382006Y638753D03*
X1377606D03*
X1373206D03*
X1395706Y638853D03*
X1368806Y638753D03*
X1368821Y660756D03*
X1346821D03*
X1355621D03*
X1360021D03*
X1364421D03*
X1351221D03*
X1404521Y660856D03*
X1400121D03*
X1395721D03*
X1386921D03*
X1377621Y660756D03*
X1382021D03*
X1373221D03*
X1391321Y660856D03*
X1407921Y-58764D03*
X1412921Y-35764D03*
X1407921D03*
X1442921Y-58764D03*
X1447921Y-35764D03*
X1437921Y-58764D03*
X1442921Y-35764D03*
X1432921Y-58764D03*
X1437921Y-35764D03*
X1427921Y-58764D03*
X1432921Y-35764D03*
X1422921Y-58764D03*
X1427921Y-35764D03*
X1417921Y-58764D03*
X1422921Y-35764D03*
X1412921Y-58764D03*
X1417921Y-35764D03*
X1462921Y-58764D03*
X1457921D03*
X1462921Y-35764D03*
X1452921Y-58764D03*
X1457921Y-35764D03*
X1447921Y-58764D03*
X1452921Y-35764D03*
X1456080Y547540D03*
X1463369Y561763D03*
X1446600Y563900D03*
X1449300D03*
X1454600D03*
X1451900D03*
X1457300D03*
X1452392Y544998D03*
X1453166Y547481D03*
X1422106Y638853D03*
X1466106D03*
X1448506D03*
X1457306D03*
X1417706D03*
X1413306D03*
X1461706D03*
X1452906D03*
X1408906D03*
X1444106D03*
X1435306D03*
X1426506D03*
X1430906D03*
X1439706D03*
X1457321Y660856D03*
X1417721D03*
X1413321D03*
X1408921D03*
X1422121D03*
X1426521D03*
X1435321D03*
X1444121D03*
X1439721D03*
X1430921D03*
X1448521D03*
X1452921D03*
X1466121D03*
X1461721D03*
X1502921Y-58764D03*
X1507921Y-35764D03*
X1497921Y-58764D03*
X1502921Y-35764D03*
X1492921Y-58764D03*
X1497921Y-35764D03*
X1487921Y-58764D03*
X1492921Y-35764D03*
X1482921Y-58764D03*
X1487921Y-35764D03*
X1477921Y-58764D03*
X1482921Y-35764D03*
X1472921Y-58764D03*
X1477921Y-35764D03*
X1467921Y-58764D03*
X1472921Y-35764D03*
X1467921D03*
X1527921Y-58764D03*
X1522921D03*
X1527921Y-35764D03*
X1517921Y-58764D03*
X1522921Y-35764D03*
X1512921Y-58764D03*
X1517921Y-35764D03*
X1507921Y-58764D03*
X1512921Y-35764D03*
X1514372Y248616D03*
Y243361D03*
X1514370Y246016D03*
X1473018Y562003D03*
X1470314Y561923D03*
X1467714Y561896D03*
X1526586Y559860D03*
X1527285Y562386D03*
X1524538Y562286D03*
X1495187Y561842D03*
X1497918Y561872D03*
X1492187Y561842D03*
X1489316Y561742D03*
X1500530Y561872D03*
X1492130Y545910D03*
X1495130D03*
X1497866Y545797D03*
X1496906Y638853D03*
X1492506D03*
X1501706Y638753D03*
X1506106D03*
X1514906D03*
X1483706Y638853D03*
X1523706Y638753D03*
X1510506D03*
X1488106Y638853D03*
X1474906D03*
X1519306Y638753D03*
X1479306Y638853D03*
X1528106Y638753D03*
X1470506Y638853D03*
X1496921Y660856D03*
X1483721D03*
X1488121D03*
X1492521D03*
X1479321D03*
X1510521Y660756D03*
X1528121D03*
X1523721D03*
X1501721D03*
X1506121D03*
X1514921D03*
X1519321D03*
X1474921Y660856D03*
X1470521D03*
X1587921Y-58764D03*
X1582921D03*
X1587921Y-35764D03*
X1532921D03*
X1542921D03*
X1532921Y-58764D03*
X1537921Y-35764D03*
X1577921Y-58764D03*
X1582921Y-35764D03*
X1572921Y-58764D03*
X1577921Y-35764D03*
X1567921Y-58764D03*
X1572921Y-35764D03*
X1562921Y-58764D03*
X1567921Y-35764D03*
X1557921Y-58764D03*
X1562921Y-35764D03*
X1552921Y-58764D03*
X1557921Y-35764D03*
X1547921Y-58764D03*
X1552921Y-35764D03*
X1542921Y-58764D03*
X1547921Y-35764D03*
X1537921Y-58764D03*
X1570020Y295340D03*
X1531986Y559860D03*
X1529286D03*
X1529985Y562386D03*
X1532685D03*
X1546795Y563316D03*
X1546685Y568656D03*
X1546825Y565986D03*
X1549395Y563541D03*
X1549285Y568881D03*
X1549425Y566211D03*
X1535385Y562386D03*
X1534897Y559808D03*
X1541267Y563185D03*
X1543967D03*
X1541080Y565859D03*
X1538331Y563913D03*
X1538385Y560978D03*
X1544080Y568859D03*
Y565859D03*
X1580121Y647556D03*
X1555106Y638753D03*
X1555121Y647556D03*
X1590121D03*
X1590106Y638753D03*
X1590121Y643156D03*
X1585121Y647556D03*
X1585106Y638753D03*
X1585121Y643156D03*
X1565121Y647556D03*
X1570121Y643156D03*
X1570106Y638753D03*
X1565106D03*
X1565121Y643156D03*
X1570121Y647556D03*
X1560121D03*
X1560106Y638753D03*
X1560121Y643156D03*
X1575121D03*
X1575106Y638753D03*
X1575121Y647556D03*
X1555121Y643156D03*
X1580106Y638753D03*
X1580121Y643156D03*
X1550121Y647556D03*
X1541306Y638753D03*
X1545706D03*
X1550106D03*
X1550121Y643156D03*
X1536906Y638753D03*
X1532506D03*
X1565121Y651956D03*
X1570121Y660756D03*
Y656356D03*
X1565121Y660756D03*
X1555121Y651956D03*
X1590121Y660756D03*
Y656356D03*
Y651956D03*
X1585121Y660756D03*
Y656356D03*
Y651956D03*
X1580121Y660756D03*
Y656356D03*
Y651956D03*
X1560121Y660756D03*
Y656356D03*
Y651956D03*
X1555121Y660756D03*
Y656356D03*
X1570121Y651956D03*
X1575121D03*
Y656356D03*
Y660756D03*
X1565121Y656356D03*
X1550121Y651956D03*
Y656356D03*
X1541321Y660756D03*
X1550121D03*
X1545721D03*
X1532521D03*
X1536921D03*
X1642921Y-35764D03*
Y-58764D03*
X1637921Y-35764D03*
Y-58764D03*
X1632921Y-35764D03*
Y-58764D03*
X1627921D03*
X1622921D03*
X1627921Y-35764D03*
X1617921Y-58764D03*
X1622921Y-35764D03*
X1612921Y-58764D03*
X1617921Y-35764D03*
X1607921Y-58764D03*
X1612921Y-35764D03*
X1602921Y-58764D03*
X1607921Y-35764D03*
X1597921Y-58764D03*
X1602921Y-35764D03*
X1592921Y-58764D03*
X1597921Y-35764D03*
X1592921D03*
X1647921D03*
Y-58764D03*
X1608280Y249234D03*
X1625106Y638753D03*
X1625121Y647556D03*
X1630121Y643156D03*
X1630106Y638753D03*
X1630121Y647556D03*
X1635121Y643156D03*
X1635106Y638753D03*
X1635121Y647556D03*
X1640121Y643156D03*
Y647556D03*
X1640106Y638753D03*
X1650121Y647556D03*
X1650106Y638753D03*
X1650121Y643156D03*
X1645121Y647556D03*
X1645106Y638753D03*
X1645121Y643156D03*
X1625121D03*
X1620121Y647556D03*
X1620106Y638753D03*
X1620121Y643156D03*
X1615121Y647556D03*
X1615106Y638753D03*
X1615121Y643156D03*
X1610121Y647556D03*
X1610106Y638753D03*
X1610121Y643156D03*
X1605121Y647556D03*
X1605106Y638753D03*
X1605121Y643156D03*
X1600121Y647556D03*
X1600106Y638753D03*
X1600121Y643156D03*
X1595121Y647556D03*
X1595106Y638753D03*
X1595121Y643156D03*
X1625121Y651956D03*
Y660756D03*
X1630121Y651956D03*
Y656356D03*
Y660756D03*
X1635121Y651956D03*
Y656356D03*
Y660756D03*
X1625121Y656356D03*
X1640121D03*
Y651956D03*
X1650121Y660756D03*
Y656356D03*
Y651956D03*
X1645121Y660756D03*
Y656356D03*
Y651956D03*
X1640121Y660756D03*
X1620121D03*
Y656356D03*
Y651956D03*
X1615121Y660756D03*
Y656356D03*
Y651956D03*
X1610121Y660756D03*
Y656356D03*
Y651956D03*
X1605121Y660756D03*
Y656356D03*
Y651956D03*
X1600121Y660756D03*
Y656356D03*
Y651956D03*
X1595121Y660756D03*
Y656356D03*
Y651956D03*
X1692921Y-40764D03*
X1702921Y-54764D03*
X1687921D03*
X1682921D03*
X1677921D03*
X1672921D03*
X1692921D03*
X1697921D03*
X1707921D03*
X1712921D03*
X1697921Y-40764D03*
X1692921Y-50764D03*
X1687921D03*
X1682921D03*
X1677921D03*
X1672921D03*
X1712921D03*
X1707921D03*
X1702921D03*
X1697921Y-45764D03*
X1707921D03*
X1702921D03*
X1712921D03*
X1697921Y-50764D03*
X1667921Y-35764D03*
X1712921D03*
Y-58764D03*
X1707921Y-35764D03*
Y-58764D03*
X1702921Y-35764D03*
Y-58764D03*
X1697921Y-35764D03*
Y-58764D03*
X1687921Y-40764D03*
X1672921Y-45764D03*
X1677921D03*
X1682921D03*
Y-40764D03*
X1687921Y-45764D03*
X1692921D03*
X1667921Y-58764D03*
X1662921Y-35764D03*
Y-58764D03*
X1657921Y-35764D03*
Y-58764D03*
X1652921Y-35764D03*
Y-58764D03*
X1712921Y-40764D03*
X1707921D03*
X1702921D03*
X1677921D03*
X1672921D03*
X1677921Y-35764D03*
Y-58764D03*
X1672921Y-35764D03*
Y-58764D03*
X1682921Y-35764D03*
Y-58764D03*
X1692921Y-35764D03*
Y-58764D03*
X1687921Y-35764D03*
Y-58764D03*
X1690121Y647556D03*
X1710121D03*
X1710106Y638753D03*
X1710121Y643156D03*
X1705121Y647556D03*
X1705106Y638753D03*
X1695121Y643156D03*
X1695106Y638753D03*
X1695121Y647556D03*
X1700121Y643156D03*
X1700106Y638753D03*
X1685121Y647556D03*
X1685106Y638753D03*
X1685121Y643156D03*
X1680121Y647556D03*
X1680106Y638753D03*
X1680121Y643156D03*
X1675121Y647556D03*
X1675106Y638753D03*
X1675121Y643156D03*
X1670121Y647556D03*
X1670106Y638753D03*
X1670121Y643156D03*
X1665121Y647556D03*
X1665106Y638753D03*
X1665121Y643156D03*
X1660121Y647556D03*
X1660106Y638753D03*
X1660121Y643156D03*
X1655121Y647556D03*
X1655106Y638753D03*
X1655121Y643156D03*
X1690121D03*
X1690106Y638753D03*
X1700121Y647556D03*
X1705121Y643156D03*
X1690121Y656356D03*
Y651956D03*
X1710121Y660756D03*
Y656356D03*
Y651956D03*
X1705121Y660756D03*
Y656356D03*
Y651956D03*
X1690121Y660756D03*
X1695121Y651956D03*
Y656356D03*
Y660756D03*
X1685121Y651956D03*
X1680121Y660756D03*
Y656356D03*
Y651956D03*
X1675121Y660756D03*
Y656356D03*
Y651956D03*
X1670121Y660756D03*
Y656356D03*
Y651956D03*
X1665121Y660756D03*
Y656356D03*
Y651956D03*
X1660121Y660756D03*
Y656356D03*
Y651956D03*
X1655121Y660756D03*
Y656356D03*
Y651956D03*
X1685121Y660756D03*
Y656356D03*
X1700121Y651956D03*
Y656356D03*
Y660756D03*
X1737921Y-50764D03*
X1722921Y-45764D03*
X1727921D03*
X1732921D03*
X1747921D03*
X1752921D03*
X1727921Y-54764D03*
X1757921D03*
X1717921D03*
X1722921D03*
X1767921Y-40764D03*
Y-50764D03*
X1762921D03*
X1757921D03*
X1762921Y-54764D03*
X1752921D03*
X1747921D03*
X1742921D03*
X1737921D03*
X1732921D03*
X1772921D03*
X1767921D03*
X1762921Y-40764D03*
X1772921D03*
X1722921Y-50764D03*
X1717921D03*
X1732921D03*
X1757921Y-40764D03*
X1717921Y-45764D03*
Y-58764D03*
X1742921Y-50764D03*
X1747921D03*
X1752921D03*
X1742921Y-58764D03*
X1737921Y-35764D03*
Y-58764D03*
X1732921Y-35764D03*
Y-58764D03*
X1727921Y-35764D03*
Y-58764D03*
X1722921Y-35764D03*
Y-58764D03*
X1717921Y-35764D03*
X1757921Y-45764D03*
X1762921D03*
X1742921D03*
X1752921Y-40764D03*
X1747921D03*
X1742921D03*
X1737921D03*
X1732921D03*
X1727921D03*
X1722921D03*
X1717921D03*
X1727921Y-50764D03*
X1767921Y-45764D03*
X1772921D03*
X1737921D03*
X1772921Y-35764D03*
Y-58764D03*
X1767921Y-35764D03*
Y-58764D03*
X1762921Y-35764D03*
Y-58764D03*
X1757921Y-35764D03*
Y-58764D03*
X1752921Y-35764D03*
Y-58764D03*
X1747921Y-35764D03*
Y-58764D03*
X1742921Y-35764D03*
X1772921Y-50764D03*
X1727600Y211300D03*
X1724800D03*
X1758324Y232657D03*
X1735000Y250000D03*
X1747227Y237314D03*
X1744308Y237295D03*
X1741668Y237314D03*
X1739044Y237284D03*
X1775121Y643156D03*
Y647556D03*
X1775106Y638753D03*
X1730121Y647556D03*
X1730106Y638753D03*
X1730121Y643156D03*
X1725121Y647556D03*
X1725106Y638753D03*
X1725121Y643156D03*
X1720121Y647556D03*
X1720106Y638753D03*
X1720121Y643156D03*
X1715121Y647556D03*
X1715106Y638753D03*
X1715121Y643156D03*
X1770121Y647556D03*
X1770106Y638753D03*
X1770121Y643156D03*
X1765121Y647556D03*
X1765106Y638753D03*
X1765121Y643156D03*
X1760121Y647556D03*
X1760106Y638753D03*
X1760121Y643156D03*
X1755121Y647556D03*
X1755106Y638753D03*
X1755121Y643156D03*
X1750121Y647556D03*
X1750106Y638753D03*
X1750121Y643156D03*
X1745121Y647556D03*
X1745106Y638753D03*
X1745121Y643156D03*
X1740121Y647556D03*
X1740106Y638753D03*
X1740121Y643156D03*
X1735121Y647556D03*
X1735106Y638753D03*
X1735121Y643156D03*
X1770121Y660756D03*
X1775121D03*
Y656356D03*
Y651956D03*
X1725121Y660756D03*
Y656356D03*
Y651956D03*
X1720121Y660756D03*
Y656356D03*
Y651956D03*
X1715121Y660756D03*
Y656356D03*
Y651956D03*
X1770121D03*
X1765121Y660756D03*
Y656356D03*
Y651956D03*
X1760121Y660756D03*
Y656356D03*
Y651956D03*
X1755121Y660756D03*
Y656356D03*
Y651956D03*
X1750121Y660756D03*
Y656356D03*
Y651956D03*
X1745121Y660756D03*
Y656356D03*
Y651956D03*
X1740121Y660756D03*
Y656356D03*
Y651956D03*
X1735121Y660756D03*
Y656356D03*
Y651956D03*
X1730121Y660756D03*
Y656356D03*
X1770121D03*
X1730121Y651956D03*
X1817921Y-40764D03*
X1832921Y-45764D03*
Y-54764D03*
X1827921D03*
X1822921D03*
X1817921D03*
X1812921D03*
X1807921D03*
X1802921D03*
X1797921D03*
X1792921D03*
X1787921D03*
X1782921D03*
X1777921D03*
X1832921Y-50764D03*
X1827921D03*
X1822921D03*
X1817921D03*
X1812921D03*
X1807921D03*
X1802921D03*
X1797921D03*
X1792921D03*
X1787921D03*
X1782921Y-40764D03*
X1792921D03*
X1802921D03*
X1807921D03*
X1822921D03*
X1827921D03*
X1832921D03*
X1812921D03*
X1797921D03*
X1777921Y-45764D03*
X1782921D03*
X1787921D03*
X1792921D03*
X1797921D03*
X1802921D03*
X1807921D03*
X1812921D03*
X1817921D03*
X1822921D03*
X1787921Y-40764D03*
X1832921Y-35764D03*
Y-58764D03*
X1827921Y-35764D03*
Y-58764D03*
X1822921Y-35764D03*
Y-58764D03*
X1817921Y-35764D03*
Y-58764D03*
X1812921Y-35764D03*
Y-58764D03*
X1807921Y-35764D03*
Y-58764D03*
X1802921Y-35764D03*
Y-58764D03*
X1797921Y-35764D03*
Y-58764D03*
X1792921Y-35764D03*
Y-58764D03*
X1787921Y-35764D03*
Y-58764D03*
X1782921Y-35764D03*
Y-58764D03*
X1777921Y-35764D03*
Y-58764D03*
X1782921Y-50764D03*
X1777921D03*
Y-40764D03*
X1827921Y-45764D03*
X1811967Y92168D03*
X1809267Y89468D03*
X1811967D03*
X1825930Y52900D03*
X1824410Y58030D03*
X1824350Y55180D03*
X1821270Y69470D03*
X1824180Y69460D03*
X1826900Y56500D03*
X1823830Y60700D03*
X1811967Y86868D03*
X1809267D03*
X1814667D03*
Y89468D03*
Y92168D03*
Y94868D03*
X1811967D03*
X1809267D03*
Y92168D03*
X1834059Y70501D03*
X1831460Y70600D03*
X1824060Y72460D03*
X1821070Y72480D03*
X1831460Y73300D03*
X1823155Y77329D03*
X1823188Y79943D03*
X1820488D03*
X1820455Y77329D03*
X1828390Y165600D03*
X1832000Y165800D03*
X1780121Y643156D03*
X1780106Y638753D03*
X1780121Y647556D03*
X1785121Y643156D03*
X1790121D03*
X1835121Y647556D03*
X1835106Y638753D03*
X1835121Y643156D03*
X1830121Y647556D03*
X1830106Y638753D03*
X1830121Y643156D03*
X1825121Y647556D03*
X1825106Y638753D03*
X1825121Y643156D03*
X1820121Y647556D03*
X1820106Y638753D03*
X1820121Y643156D03*
X1815121Y647556D03*
X1815106Y638753D03*
X1815121Y643156D03*
X1810121Y647556D03*
X1810106Y638753D03*
X1810121Y643156D03*
X1805121Y647556D03*
X1805106Y638753D03*
X1805121Y643156D03*
X1800121Y647556D03*
X1800106Y638753D03*
X1800121Y643156D03*
X1795121Y647556D03*
X1795106Y638753D03*
X1795121Y643156D03*
X1790121Y647556D03*
X1790106Y638753D03*
X1785121Y647556D03*
X1785106Y638753D03*
X1800121Y656356D03*
X1780121Y651956D03*
Y656356D03*
Y660756D03*
X1835121D03*
Y656356D03*
Y651956D03*
X1830121Y660756D03*
Y656356D03*
Y651956D03*
X1825121Y660756D03*
Y656356D03*
Y651956D03*
X1820121Y660756D03*
Y656356D03*
Y651956D03*
X1815121Y660756D03*
Y656356D03*
Y651956D03*
X1810121Y660756D03*
Y656356D03*
Y651956D03*
X1805121Y660756D03*
Y656356D03*
Y651956D03*
X1800121Y660756D03*
Y651956D03*
X1795121Y660756D03*
Y656356D03*
Y651956D03*
X1790121Y660756D03*
Y656356D03*
Y651956D03*
X1785121Y660756D03*
Y656356D03*
Y651956D03*
X1857921Y-45764D03*
X1837921D03*
X1897921D03*
X1892921D03*
X1887921D03*
X1882921D03*
X1877921D03*
X1872921D03*
X1867921D03*
X1862921D03*
X1842921Y-54764D03*
X1852921Y-45764D03*
X1847921D03*
X1842921D03*
X1897921Y-54764D03*
X1892921D03*
X1887921D03*
X1882921D03*
X1877921D03*
X1872921D03*
X1867921D03*
X1862921D03*
X1857921D03*
X1852921D03*
X1847921D03*
X1837921D03*
X1897921Y-50764D03*
X1892921D03*
X1887921D03*
X1882921D03*
X1877921D03*
X1872921D03*
X1867921D03*
X1862921D03*
X1857921D03*
X1852921D03*
X1847921D03*
X1842921D03*
X1837921D03*
X1892921Y-40764D03*
X1897921D03*
X1877921D03*
X1882921D03*
X1887921D03*
X1857921D03*
X1862921D03*
X1867921D03*
X1872921D03*
X1837921D03*
X1842921D03*
X1847921D03*
X1852921D03*
Y-35764D03*
Y-58764D03*
X1847921Y-35764D03*
Y-58764D03*
X1842921Y-35764D03*
Y-58764D03*
X1837921Y-35764D03*
Y-58764D03*
X1862921D03*
X1857921Y-35764D03*
Y-58764D03*
X1882921D03*
X1877921Y-35764D03*
Y-58764D03*
X1872921Y-35764D03*
Y-58764D03*
X1867921Y-35764D03*
Y-58764D03*
X1862921Y-35764D03*
X1897921D03*
Y-58764D03*
X1892921Y-35764D03*
Y-58764D03*
X1887921Y-35764D03*
Y-58764D03*
X1882921Y-35764D03*
X1862636Y26780D03*
X1851040Y24130D03*
X1855836Y21118D03*
X1852236D03*
X1859436D03*
X1862936D03*
X1865450Y22000D03*
X1860981Y23894D03*
X1857381D03*
X1853781D03*
X1864020Y24470D03*
X1851936Y26780D03*
X1859036D03*
X1855436D03*
X1883723Y263029D03*
Y260029D03*
X1880633Y260109D03*
Y263109D03*
X1895121Y647556D03*
X1895106Y638753D03*
X1895121Y643156D03*
X1890121Y647556D03*
X1890106Y638753D03*
X1890121Y643156D03*
X1885121Y647556D03*
X1885106Y638753D03*
X1885121Y643156D03*
X1880121Y647556D03*
X1880106Y638753D03*
X1880121Y643156D03*
X1875121Y647556D03*
X1875106Y638753D03*
X1875121Y643156D03*
X1870121Y647556D03*
X1870106Y638753D03*
X1870121Y643156D03*
X1865121Y647556D03*
X1865106Y638753D03*
X1865121Y643156D03*
X1860121Y647556D03*
X1860106Y638753D03*
X1860121Y643156D03*
X1855121Y647556D03*
X1855106Y638753D03*
X1855121Y643156D03*
X1850121Y647556D03*
X1850106Y638753D03*
X1850121Y643156D03*
X1845121Y647556D03*
X1845106Y638753D03*
X1845121Y643156D03*
X1840121Y647556D03*
X1840106Y638753D03*
X1840121Y643156D03*
X1895121Y660756D03*
Y656356D03*
Y651956D03*
X1890121Y660756D03*
Y656356D03*
Y651956D03*
X1885121Y660756D03*
Y656356D03*
Y651956D03*
X1880121Y660756D03*
Y656356D03*
Y651956D03*
X1875121Y660756D03*
Y656356D03*
Y651956D03*
X1870121Y660756D03*
Y656356D03*
Y651956D03*
X1865121Y660756D03*
Y656356D03*
Y651956D03*
X1860121Y660756D03*
Y656356D03*
Y651956D03*
X1855121Y660756D03*
Y656356D03*
Y651956D03*
X1850121Y660756D03*
Y656356D03*
Y651956D03*
X1845121Y660756D03*
Y656356D03*
Y651956D03*
X1840121Y660756D03*
Y656356D03*
Y651956D03*
X1927921Y-40764D03*
X1947921Y-45764D03*
X1942921D03*
X1937921D03*
X1932921D03*
X1927921D03*
X1922921D03*
X1917921D03*
X1912921D03*
X1907921D03*
X1902921D03*
X1927921Y-50764D03*
X1932921D03*
Y-40764D03*
X1937921D03*
X1942921D03*
X1947921D03*
X1907921Y-50764D03*
X1902921D03*
X1922921Y-40764D03*
X1917921D03*
X1912921D03*
X1907921D03*
X1902921D03*
X1922921Y-54764D03*
X1917921D03*
X1912921D03*
X1907921D03*
X1902921D03*
X1927921D03*
X1932921D03*
X1937921D03*
X1942921D03*
X1947921D03*
X1952921D03*
X1957921D03*
Y-50764D03*
X1952921D03*
X1947921D03*
X1942921D03*
X1937921D03*
X1922921D03*
X1917921D03*
X1912921D03*
X1957921Y-35764D03*
Y-58764D03*
X1952921Y-35764D03*
Y-58764D03*
X1947921Y-35764D03*
Y-58764D03*
X1942921Y-35764D03*
Y-58764D03*
X1937921Y-35764D03*
Y-58764D03*
X1932921Y-35764D03*
Y-58764D03*
X1927921Y-35764D03*
Y-58764D03*
X1922921Y-35764D03*
Y-58764D03*
X1917921Y-35764D03*
Y-58764D03*
X1912921Y-35764D03*
Y-58764D03*
X1907921Y-35764D03*
Y-58764D03*
X1902921Y-35764D03*
Y-58764D03*
X1907385Y93926D03*
X1904678Y93845D03*
X1907428Y91133D03*
X1904742Y96552D03*
X1907448Y96615D03*
X1908400Y101010D03*
X1914037Y243646D03*
X1960106Y638753D03*
X1955106D03*
X1950106D03*
X1945121Y647556D03*
Y643156D03*
X1945106Y638753D03*
X1940121Y647556D03*
Y643156D03*
X1940106Y638753D03*
X1935121Y647556D03*
Y643156D03*
X1935106Y638753D03*
X1930106D03*
X1925106D03*
X1920121Y647556D03*
X1910121Y643156D03*
X1910106Y638753D03*
X1905121Y647556D03*
Y643156D03*
X1905106Y638753D03*
X1900121Y647556D03*
X1900106Y638753D03*
X1900121Y643156D03*
X1920106Y638753D03*
X1915121Y647556D03*
X1920121Y643156D03*
X1910121Y647556D03*
X1915106Y638753D03*
X1915121Y643156D03*
X1960121Y656356D03*
Y660756D03*
X1955121Y656356D03*
Y660756D03*
X1950121Y651956D03*
Y656356D03*
Y660756D03*
X1945121Y651956D03*
Y656356D03*
Y660756D03*
X1940121Y651956D03*
Y656356D03*
Y660756D03*
X1935121Y651956D03*
Y656356D03*
Y660756D03*
X1930121Y651956D03*
Y656356D03*
Y660756D03*
X1925121Y651956D03*
Y656356D03*
Y660756D03*
X1920121Y651956D03*
Y656356D03*
X1905121Y651956D03*
Y656356D03*
Y660756D03*
X1900121D03*
Y656356D03*
Y651956D03*
X1915121D03*
Y656356D03*
Y660756D03*
X1920121D03*
X1910121D03*
Y656356D03*
Y651956D03*
X1967921Y-45764D03*
X1962921D03*
Y-40764D03*
X1967921D03*
Y-54764D03*
X1962921D03*
X1967921Y-50764D03*
X1962921D03*
X1967921Y-35764D03*
Y-58764D03*
X1962921Y-35764D03*
Y-58764D03*
X1970121Y647556D03*
Y643156D03*
X1970106Y638753D03*
X1965121Y647556D03*
Y643156D03*
X1965106Y638753D03*
X1970121Y651956D03*
Y656356D03*
Y660756D03*
X1965121Y651956D03*
Y656356D03*
Y660756D03*
G54D20*
G01X548049Y-193422D02*
Y-210922D01*
G01X543027Y-193422D02*
X553071D01*
G01X565549Y-199256D02*
Y-210922D01*
G01Y-194589D02*
X565112Y-194297D01*
Y-193714D01*
X565549Y-193422D01*
X565986Y-193714D01*
Y-194297D01*
X565549Y-194589D01*
G01X583049Y-210922D02*
X581739Y-210630D01*
X580429Y-209464D01*
X579555Y-207422D01*
X579119Y-205089D01*
X579555Y-202755D01*
X580429Y-200714D01*
X581739Y-199547D01*
X583049Y-199256D01*
X584359Y-199547D01*
X585669Y-200714D01*
X586542Y-202755D01*
X586761Y-205089D01*
X586542Y-207422D01*
X585669Y-209464D01*
X584359Y-210630D01*
X583049Y-210922D01*
G01X597492Y-215297D02*
X599021Y-216464D01*
X600767Y-216755D01*
X602295Y-216464D01*
X603606Y-215006D01*
X604479Y-212964D01*
Y-199256D01*
G01Y-201589D02*
X603606Y-200422D01*
X602295Y-199547D01*
X600767Y-199256D01*
X599021Y-199839D01*
X597929Y-201005D01*
X597055Y-203047D01*
X596619Y-205089D01*
X596837Y-206839D01*
X597711Y-208881D01*
X599021Y-210339D01*
X600767Y-210922D01*
X602077Y-210630D01*
X603606Y-209464D01*
X604479Y-208298D01*
G01X621979Y-210922D02*
Y-199256D01*
G01Y-201297D02*
X621106Y-200131D01*
X619795Y-199547D01*
X618267Y-199256D01*
X616739Y-199839D01*
X615429Y-201005D01*
X614555Y-202755D01*
X614119Y-205089D01*
X614555Y-207422D01*
X615429Y-209172D01*
X616739Y-210339D01*
X618267Y-210922D01*
X619795Y-210630D01*
X621106Y-209756D01*
X621979Y-208589D01*
G01X648682Y-210922D02*
Y-193422D01*
X653922D01*
X655669Y-194297D01*
X656979Y-196339D01*
X657416Y-198672D01*
X656979Y-201005D01*
X655887Y-202755D01*
X653922Y-203631D01*
X648682D01*
G01X674479Y-210922D02*
Y-199256D01*
G01Y-201297D02*
X673606Y-200131D01*
X672295Y-199547D01*
X670767Y-199256D01*
X669239Y-199839D01*
X667929Y-201005D01*
X667055Y-202755D01*
X666619Y-205089D01*
X667055Y-207422D01*
X667929Y-209172D01*
X669239Y-210339D01*
X670767Y-210922D01*
X672295Y-210630D01*
X673606Y-209756D01*
X674479Y-208589D01*
G01X684774Y-208881D02*
X685866Y-210047D01*
X687394Y-210922D01*
X688704D01*
X690014Y-210339D01*
X690887Y-209464D01*
X691324Y-208298D01*
X691106Y-206547D01*
X690232Y-205672D01*
X686302Y-203922D01*
X685429Y-201880D01*
X685866Y-200422D01*
X686739Y-199547D01*
X688049Y-199256D01*
X689359Y-199547D01*
X690669Y-200422D01*
G01X702274Y-208881D02*
X703366Y-210047D01*
X704894Y-210922D01*
X706204D01*
X707514Y-210339D01*
X708387Y-209464D01*
X708824Y-208298D01*
X708606Y-206547D01*
X707732Y-205672D01*
X703802Y-203922D01*
X702929Y-201880D01*
X703366Y-200422D01*
X704239Y-199547D01*
X705549Y-199256D01*
X706859Y-199547D01*
X708169Y-200422D01*
G01X735746Y-210922D02*
Y-193422D01*
X740112D01*
X741859Y-194297D01*
X743169Y-195464D01*
X744261Y-197213D01*
X745134Y-199256D01*
X745352Y-202172D01*
X745134Y-205089D01*
X744261Y-207131D01*
X743169Y-208881D01*
X741859Y-210047D01*
X740112Y-210922D01*
X735746D01*
G01X752590Y-193422D02*
X758049Y-210922D01*
X763508Y-193422D01*
G01X775549D02*
Y-210922D01*
G01X770527Y-193422D02*
X780571D01*
G01X804872Y-210922D02*
Y-193422D01*
X810549Y-208005D01*
X816226Y-193422D01*
Y-210922D01*
G01X829795Y-201589D02*
X830669Y-200714D01*
X831324Y-199256D01*
X831761Y-197213D01*
X831324Y-195464D01*
X830451Y-194297D01*
X828922Y-193422D01*
X823027D01*
Y-210922D01*
X830232D01*
X831761Y-209756D01*
X832634Y-208005D01*
X833071Y-205964D01*
X832634Y-203922D01*
X831324Y-202172D01*
X829795Y-201589D01*
X823027D01*
G01X647372Y-165922D02*
Y-148422D01*
X653049Y-163005D01*
X658726Y-148422D01*
Y-165922D01*
G01X670549D02*
X669239Y-165630D01*
X667929Y-164464D01*
X667055Y-162422D01*
X666619Y-160089D01*
X667055Y-157755D01*
X667929Y-155714D01*
X669239Y-154547D01*
X670549Y-154256D01*
X671859Y-154547D01*
X673169Y-155714D01*
X674042Y-157755D01*
X674261Y-160089D01*
X674042Y-162422D01*
X673169Y-164464D01*
X671859Y-165630D01*
X670549Y-165922D01*
G01X691979Y-148422D02*
Y-165922D01*
G01Y-163298D02*
X691106Y-164756D01*
X689795Y-165630D01*
X688267Y-165922D01*
X686521Y-165339D01*
X685211Y-163881D01*
X684337Y-162131D01*
X684119Y-160089D01*
X684337Y-158047D01*
X685211Y-156297D01*
X686521Y-154839D01*
X688267Y-154256D01*
X689795Y-154547D01*
X690887Y-155131D01*
X691979Y-156297D01*
G01X702274Y-158047D02*
X709261D01*
X708606Y-156005D01*
X707514Y-154839D01*
X705986Y-154256D01*
X704457Y-154547D01*
X703147Y-155422D01*
X702274Y-157464D01*
X701837Y-159214D01*
Y-160964D01*
X702274Y-162714D01*
X703366Y-164464D01*
X704676Y-165630D01*
X706204Y-165922D01*
X707732Y-165339D01*
X709261Y-163589D01*
G01X723049Y-165922D02*
Y-148422D01*
G01X975549Y-210922D02*
Y-193422D01*
X972929Y-196922D01*
G01Y-210922D02*
X978169D01*
G01X988246Y-208298D02*
X989555Y-209756D01*
X991084Y-210630D01*
X993049Y-210922D01*
X995014Y-210339D01*
X996542Y-209172D01*
X997634Y-207131D01*
X997852Y-204797D01*
X997416Y-202464D01*
X996324Y-201005D01*
X994795Y-199839D01*
X993267Y-199547D01*
X991739Y-199839D01*
X989774Y-201005D01*
X990429Y-193422D01*
X996324D01*
G01X1010549Y-210922D02*
Y-193422D01*
X1007929Y-196922D01*
G01Y-210922D02*
X1013169D01*
G01X1023901Y-196339D02*
X1025211Y-194589D01*
X1026739Y-193714D01*
X1028486Y-193422D01*
X1030669Y-194005D01*
X1032197Y-195464D01*
X1032634Y-197213D01*
X1032416Y-198964D01*
X1031542Y-200422D01*
X1027176Y-203339D01*
X1025211Y-205380D01*
X1023901Y-208298D01*
X1023464Y-210922D01*
X1032634D01*
G01X1041401Y-203631D02*
X1042929Y-201589D01*
X1044239Y-200422D01*
X1045986Y-199839D01*
X1047514Y-200422D01*
X1048606Y-201589D01*
X1049479Y-203339D01*
X1049697Y-205380D01*
X1049479Y-207131D01*
X1048606Y-208881D01*
X1047295Y-210339D01*
X1045767Y-210922D01*
X1044021Y-210339D01*
X1042492Y-208589D01*
X1041619Y-205964D01*
X1041401Y-203047D01*
X1041837Y-199256D01*
X1042492Y-197213D01*
X1043584Y-195172D01*
X1045112Y-193714D01*
X1046641Y-193422D01*
X1048169Y-194005D01*
X1049261Y-195464D01*
G01X962432Y-165922D02*
Y-148422D01*
X967672D01*
X969419Y-149297D01*
X970729Y-151339D01*
X971166Y-153672D01*
X970729Y-156005D01*
X969637Y-157755D01*
X967672Y-158631D01*
X962432D01*
G01X989102Y-149881D02*
X987792Y-149005D01*
X986264Y-148422D01*
X984517D01*
X982552Y-149297D01*
X981024Y-150755D01*
X979932Y-152506D01*
X979059Y-155422D01*
X978840Y-158047D01*
X979277Y-160672D01*
X979932Y-162422D01*
X981242Y-164172D01*
X982771Y-165339D01*
X984299Y-165922D01*
X985827D01*
X987356Y-165339D01*
X988666Y-164464D01*
X989758Y-163298D01*
G01X1003545Y-156589D02*
X1004419Y-155714D01*
X1005074Y-154256D01*
X1005511Y-152213D01*
X1005074Y-150464D01*
X1004201Y-149297D01*
X1002672Y-148422D01*
X996777D01*
Y-165922D01*
X1003982D01*
X1005511Y-164756D01*
X1006384Y-163005D01*
X1006821Y-160964D01*
X1006384Y-158922D01*
X1005074Y-157172D01*
X1003545Y-156589D01*
X996777D01*
G01X1012749Y-171755D02*
X1025849D01*
G01X1031777Y-165922D02*
Y-148422D01*
X1041821Y-165922D01*
Y-148422D01*
G01X1054299Y-165922D02*
X1052552Y-165630D01*
X1051024Y-164464D01*
X1049714Y-162714D01*
X1048840Y-160672D01*
X1048404Y-158339D01*
Y-156005D01*
X1048840Y-153672D01*
X1049714Y-151630D01*
X1051024Y-149881D01*
X1052552Y-148714D01*
X1054299Y-148422D01*
X1056045Y-148714D01*
X1057574Y-149881D01*
X1058884Y-151630D01*
X1059758Y-153672D01*
X1060194Y-156005D01*
Y-158339D01*
X1059758Y-160672D01*
X1058884Y-162714D01*
X1057574Y-164464D01*
X1056045Y-165630D01*
X1054299Y-165922D01*
G01X1128099Y-210922D02*
Y-193422D01*
X1125479Y-196922D01*
G01Y-210922D02*
X1130719D01*
G01X1147345Y-201589D02*
X1148219Y-200714D01*
X1148874Y-199256D01*
X1149311Y-197213D01*
X1148874Y-195464D01*
X1148001Y-194297D01*
X1146472Y-193422D01*
X1140577D01*
Y-210922D01*
X1147782D01*
X1149311Y-209756D01*
X1150184Y-208005D01*
X1150621Y-205964D01*
X1150184Y-203922D01*
X1148874Y-202172D01*
X1147345Y-201589D01*
X1140577D01*
G01X1105140Y-148422D02*
X1110599Y-165922D01*
X1116058Y-148422D01*
G01X1132466Y-165922D02*
X1123732D01*
Y-148422D01*
X1132466D01*
G01X1128972Y-156880D02*
X1123732D01*
G01X1141232Y-165922D02*
Y-148422D01*
X1146691D01*
X1148437Y-149297D01*
X1149529Y-150464D01*
X1149966Y-152797D01*
X1149529Y-155131D01*
X1148219Y-156589D01*
X1146691Y-157464D01*
X1141232D01*
G01X1146691D02*
X1149966Y-165922D01*
G01X1163099Y-166505D02*
X1162662Y-166214D01*
Y-165630D01*
X1163099Y-165339D01*
X1163536Y-165630D01*
Y-166214D01*
X1163099Y-166505D01*
G01X1317416Y-193422D02*
Y-210922D01*
X1308682D01*
G01X1295549D02*
X1294021Y-210630D01*
X1292274Y-209756D01*
X1291182Y-208298D01*
X1290746Y-206255D01*
X1291182Y-204214D01*
X1292492Y-202464D01*
X1294457Y-201589D01*
X1296641D01*
X1297951Y-201005D01*
X1299043Y-199547D01*
X1299479Y-197506D01*
X1298824Y-195464D01*
X1297296Y-194005D01*
X1295549Y-193422D01*
X1293803Y-194005D01*
X1292274Y-195464D01*
X1291619Y-197506D01*
X1292056Y-199547D01*
X1293147Y-201005D01*
X1294457Y-201589D01*
X1296641D01*
X1298606Y-202464D01*
X1299916Y-204214D01*
X1300352Y-206255D01*
X1299916Y-208298D01*
X1298824Y-209756D01*
X1297077Y-210630D01*
X1295549Y-210922D01*
G01X1283508Y-193422D02*
X1278049Y-210922D01*
X1272590Y-193422D01*
G01X1255746Y-194881D02*
X1257056Y-194005D01*
X1258584Y-193422D01*
X1260331D01*
X1262296Y-194297D01*
X1263824Y-195755D01*
X1264916Y-197506D01*
X1265789Y-200422D01*
X1266008Y-203047D01*
X1265571Y-205672D01*
X1264916Y-207422D01*
X1263606Y-209172D01*
X1262077Y-210339D01*
X1260549Y-210922D01*
X1259021D01*
X1257492Y-210339D01*
X1256182Y-209464D01*
X1255090Y-208298D01*
G01X1238246Y-194881D02*
X1239556Y-194005D01*
X1241084Y-193422D01*
X1242831D01*
X1244796Y-194297D01*
X1246324Y-195755D01*
X1247416Y-197506D01*
X1248289Y-200422D01*
X1248508Y-203047D01*
X1248071Y-205672D01*
X1247416Y-207422D01*
X1246106Y-209172D01*
X1244577Y-210339D01*
X1243049Y-210922D01*
X1241521D01*
X1239992Y-210339D01*
X1238682Y-209464D01*
X1237590Y-208298D01*
G01X1238682Y-148422D02*
Y-165922D01*
X1247416D01*
G01X1264479D02*
Y-154256D01*
G01Y-156297D02*
X1263606Y-155131D01*
X1262295Y-154547D01*
X1260767Y-154256D01*
X1259239Y-154839D01*
X1257929Y-156005D01*
X1257055Y-157755D01*
X1256619Y-160089D01*
X1257055Y-162422D01*
X1257929Y-164172D01*
X1259239Y-165339D01*
X1260767Y-165922D01*
X1262295Y-165630D01*
X1263606Y-164756D01*
X1264479Y-163589D01*
G01X1273464Y-171172D02*
X1274774Y-171755D01*
X1276521Y-171172D01*
X1277612Y-170006D01*
X1278486Y-168547D01*
X1279795Y-163881D01*
X1282634Y-154256D01*
G01X1275647D02*
X1279795Y-163881D01*
G01X1292274Y-158047D02*
X1299261D01*
X1298606Y-156005D01*
X1297514Y-154839D01*
X1295986Y-154256D01*
X1294457Y-154547D01*
X1293147Y-155422D01*
X1292274Y-157464D01*
X1291837Y-159214D01*
Y-160964D01*
X1292274Y-162714D01*
X1293366Y-164464D01*
X1294676Y-165630D01*
X1296204Y-165922D01*
X1297732Y-165339D01*
X1299261Y-163589D01*
G01X1309992Y-165922D02*
Y-154256D01*
G01Y-156589D02*
X1311084Y-155422D01*
X1312176Y-154547D01*
X1313704Y-154256D01*
X1314795Y-154547D01*
X1316106Y-155422D01*
G01X1380796Y-165922D02*
Y-148422D01*
X1385162D01*
X1386909Y-149297D01*
X1388219Y-150464D01*
X1389311Y-152213D01*
X1390184Y-154256D01*
X1390402Y-157172D01*
X1390184Y-160089D01*
X1389311Y-162131D01*
X1388219Y-163881D01*
X1386909Y-165047D01*
X1385162Y-165922D01*
X1380796D01*
G01X1399824Y-158047D02*
X1406811D01*
X1406156Y-156005D01*
X1405064Y-154839D01*
X1403536Y-154256D01*
X1402007Y-154547D01*
X1400697Y-155422D01*
X1399824Y-157464D01*
X1399387Y-159214D01*
Y-160964D01*
X1399824Y-162714D01*
X1400916Y-164464D01*
X1402226Y-165630D01*
X1403754Y-165922D01*
X1405282Y-165339D01*
X1406811Y-163589D01*
G01X1417324Y-163881D02*
X1418416Y-165047D01*
X1419944Y-165922D01*
X1421254D01*
X1422564Y-165339D01*
X1423437Y-164464D01*
X1423874Y-163298D01*
X1423656Y-161547D01*
X1422782Y-160672D01*
X1418852Y-158922D01*
X1417979Y-156880D01*
X1418416Y-155422D01*
X1419289Y-154547D01*
X1420599Y-154256D01*
X1421909Y-154547D01*
X1423219Y-155422D01*
G01X1438099Y-154256D02*
Y-165922D01*
G01Y-149589D02*
X1437662Y-149297D01*
Y-148714D01*
X1438099Y-148422D01*
X1438536Y-148714D01*
Y-149297D01*
X1438099Y-149589D01*
G01X1452542Y-170297D02*
X1454071Y-171464D01*
X1455817Y-171755D01*
X1457345Y-171464D01*
X1458656Y-170006D01*
X1459529Y-167964D01*
Y-154256D01*
G01Y-156589D02*
X1458656Y-155422D01*
X1457345Y-154547D01*
X1455817Y-154256D01*
X1454071Y-154839D01*
X1452979Y-156005D01*
X1452105Y-158047D01*
X1451669Y-160089D01*
X1451887Y-161839D01*
X1452761Y-163881D01*
X1454071Y-165339D01*
X1455817Y-165922D01*
X1457127Y-165630D01*
X1458656Y-164464D01*
X1459529Y-163298D01*
G01X1469387Y-165922D02*
Y-154256D01*
G01Y-157172D02*
X1470261Y-155714D01*
X1471571Y-154547D01*
X1473317Y-154256D01*
X1474845Y-154547D01*
X1476156Y-155714D01*
X1476811Y-157755D01*
Y-165922D01*
G01X1487324Y-158047D02*
X1494311D01*
X1493656Y-156005D01*
X1492564Y-154839D01*
X1491036Y-154256D01*
X1489507Y-154547D01*
X1488197Y-155422D01*
X1487324Y-157464D01*
X1486887Y-159214D01*
Y-160964D01*
X1487324Y-162714D01*
X1488416Y-164464D01*
X1489726Y-165630D01*
X1491254Y-165922D01*
X1492782Y-165339D01*
X1494311Y-163589D01*
G01X1505042Y-165922D02*
Y-154256D01*
G01Y-156589D02*
X1506134Y-155422D01*
X1507226Y-154547D01*
X1508754Y-154256D01*
X1509845Y-154547D01*
X1511156Y-155422D01*
G01X1426729Y-193422D02*
X1431969D01*
G01X1429349D02*
Y-210922D01*
G01X1426729D02*
X1431969D01*
G01X1441390Y-193422D02*
X1446849Y-210922D01*
X1452308Y-193422D01*
G01X1464349Y-210922D02*
Y-203047D01*
X1459982Y-193422D01*
G01X1468716D02*
X1464349Y-203047D01*
G01X1551799Y-193422D02*
X1550052Y-194005D01*
X1548742Y-195464D01*
X1547869Y-197213D01*
X1547214Y-199547D01*
X1546996Y-202172D01*
X1547214Y-204797D01*
X1547869Y-207131D01*
X1548742Y-208881D01*
X1550052Y-210339D01*
X1551799Y-210922D01*
X1553545Y-210339D01*
X1554856Y-208881D01*
X1555729Y-207131D01*
X1556384Y-204797D01*
X1556602Y-202172D01*
X1556384Y-199547D01*
X1555729Y-197213D01*
X1554856Y-195464D01*
X1553545Y-194005D01*
X1551799Y-193422D01*
G01X1565151Y-196339D02*
X1566461Y-194589D01*
X1567989Y-193714D01*
X1569736Y-193422D01*
X1571919Y-194005D01*
X1573447Y-195464D01*
X1573884Y-197213D01*
X1573666Y-198964D01*
X1572792Y-200422D01*
X1568426Y-203339D01*
X1566461Y-205380D01*
X1565151Y-208298D01*
X1564714Y-210922D01*
X1573884D01*
G01X1582869Y-211505D02*
X1590729Y-193422D01*
G01X1604299Y-210922D02*
Y-193422D01*
X1601679Y-196922D01*
G01Y-210922D02*
X1606919D01*
G01X1621799Y-193422D02*
X1620052Y-194005D01*
X1618742Y-195464D01*
X1617869Y-197213D01*
X1617214Y-199547D01*
X1616996Y-202172D01*
X1617214Y-204797D01*
X1617869Y-207131D01*
X1618742Y-208881D01*
X1620052Y-210339D01*
X1621799Y-210922D01*
X1623545Y-210339D01*
X1624856Y-208881D01*
X1625729Y-207131D01*
X1626384Y-204797D01*
X1626602Y-202172D01*
X1626384Y-199547D01*
X1625729Y-197213D01*
X1624856Y-195464D01*
X1623545Y-194005D01*
X1621799Y-193422D01*
G01X1635369Y-211505D02*
X1643229Y-193422D01*
G01X1652651Y-196339D02*
X1653961Y-194589D01*
X1655489Y-193714D01*
X1657236Y-193422D01*
X1659419Y-194005D01*
X1660947Y-195464D01*
X1661384Y-197213D01*
X1661166Y-198964D01*
X1660292Y-200422D01*
X1655926Y-203339D01*
X1653961Y-205380D01*
X1652651Y-208298D01*
X1652214Y-210922D01*
X1661384D01*
G01X1674299Y-193422D02*
X1672552Y-194005D01*
X1671242Y-195464D01*
X1670369Y-197213D01*
X1669714Y-199547D01*
X1669496Y-202172D01*
X1669714Y-204797D01*
X1670369Y-207131D01*
X1671242Y-208881D01*
X1672552Y-210339D01*
X1674299Y-210922D01*
X1676045Y-210339D01*
X1677356Y-208881D01*
X1678229Y-207131D01*
X1678884Y-204797D01*
X1679102Y-202172D01*
X1678884Y-199547D01*
X1678229Y-197213D01*
X1677356Y-195464D01*
X1676045Y-194005D01*
X1674299Y-193422D01*
G01X1691799Y-210922D02*
Y-193422D01*
X1689179Y-196922D01*
G01Y-210922D02*
X1694419D01*
G01X1708862D02*
X1709299Y-207131D01*
X1709954Y-203922D01*
X1710827Y-201005D01*
X1711919Y-197797D01*
X1713666Y-193422D01*
X1704932D01*
G01X1599496Y-165922D02*
Y-148422D01*
X1603862D01*
X1605609Y-149297D01*
X1606919Y-150464D01*
X1608011Y-152213D01*
X1608884Y-154256D01*
X1609102Y-157172D01*
X1608884Y-160089D01*
X1608011Y-162131D01*
X1606919Y-163881D01*
X1605609Y-165047D01*
X1603862Y-165922D01*
X1599496D01*
G01X1625729D02*
Y-154256D01*
G01Y-156297D02*
X1624856Y-155131D01*
X1623545Y-154547D01*
X1622017Y-154256D01*
X1620489Y-154839D01*
X1619179Y-156005D01*
X1618305Y-157755D01*
X1617869Y-160089D01*
X1618305Y-162422D01*
X1619179Y-164172D01*
X1620489Y-165339D01*
X1622017Y-165922D01*
X1623545Y-165630D01*
X1624856Y-164756D01*
X1625729Y-163589D01*
G01X1639299Y-148422D02*
Y-165922D01*
G01X1636242Y-154256D02*
X1642356D01*
G01X1653524Y-158047D02*
X1660511D01*
X1659856Y-156005D01*
X1658764Y-154839D01*
X1657236Y-154256D01*
X1655707Y-154547D01*
X1654397Y-155422D01*
X1653524Y-157464D01*
X1653087Y-159214D01*
Y-160964D01*
X1653524Y-162714D01*
X1654616Y-164464D01*
X1655926Y-165630D01*
X1657454Y-165922D01*
X1658982Y-165339D01*
X1660511Y-163589D01*
G54D11*
G01X430749Y-124922D02*
G02I-12000J0D01*
G01X425599D02*
G02I-6850J0D01*
G01X434749D02*
X402749D01*
G01X434749Y-140922D02*
Y-220922D01*
G01D02*
X1729349D01*
G01X434749Y-176422D02*
X1729349D01*
G01X418749Y-140922D02*
Y-108922D01*
G01X434749Y-140922D02*
X1729349D01*
G01X821358Y176066D02*
X790644D01*
X788628Y174050D01*
X673250D01*
X666370Y167170D01*
X653230D01*
X644750Y175650D01*
G01X1209033Y183907D02*
X1202740Y190200D01*
X835492D01*
X821358Y176066D01*
G01X941849Y-140922D02*
Y-220922D01*
G01X1079349Y-140922D02*
Y-220922D01*
G01X1194349Y-140922D02*
Y-220922D01*
G01X1361849Y-140922D02*
Y-220922D01*
G01X1531849Y-140922D02*
Y-220922D01*
G01X1729349Y-140922D02*
Y-220922D01*
G01X1757349Y-124922D02*
G02I-12000J0D01*
G01X1752199D02*
G02I-6850J0D01*
G01X1745349Y-140922D02*
Y-108922D01*
G01X1761349Y-124922D02*
X1729349D01*
X-16602Y81858D03*
Y79358D03*
X8660Y27274D03*
X8988Y58267D03*
X-8562Y81858D03*
Y79358D03*
X-14102Y81858D03*
Y79358D03*
X-5912Y84258D03*
X-8812Y84308D03*
X-5930Y79358D03*
X-5860Y81858D03*
X-11452Y79308D03*
Y81808D03*
X17000Y475500D03*
X41993Y523425D03*
X37000Y511200D03*
X39200Y509500D03*
X40111Y520623D03*
X31800Y510600D03*
X38389Y523748D03*
X34300Y511000D03*
X37600Y507400D03*
X35707Y509055D03*
X77000Y25992D03*
X74000D03*
X62000Y28500D03*
X59500D03*
X65000D03*
X68000D03*
X71000D03*
X74000D03*
X77000D03*
X80000Y29000D03*
Y26000D03*
X62000D03*
X59500D03*
X65000D03*
X71000Y25992D03*
X68000D03*
X82013Y14129D03*
X79372Y14895D03*
X79096Y9886D03*
X79116Y12361D03*
X81669Y11693D03*
X81610Y9159D03*
X60500Y79000D03*
X70500Y70500D03*
X73000D03*
X78000D03*
X75500D03*
X81000Y61500D03*
Y58500D03*
X63000Y74000D03*
X60500D03*
X63000Y76500D03*
X60500D03*
X67500Y49500D03*
X70500D03*
X73500D03*
X79500D03*
X61500Y43500D03*
X59000D03*
X64500D03*
X67500D03*
X70500D03*
X60500Y70500D03*
X63000D03*
X61500Y58500D03*
Y49500D03*
X59000Y56000D03*
X61500D03*
X59000Y49500D03*
X76500Y43500D03*
X79500Y82000D03*
Y46500D03*
X76500D03*
X73500D03*
X70500D03*
X67500D03*
X64500D03*
X59000D03*
X61500D03*
X68000Y70500D03*
X65500D03*
X79500Y43500D03*
X63000Y81500D03*
X59000Y58500D03*
X61500Y61000D03*
X59000D03*
X76500Y49500D03*
X73500Y43500D03*
X64500Y49500D03*
X79500Y79000D03*
X63000D03*
X79500Y72500D03*
X79725Y75993D03*
X97900Y194500D03*
X104820Y198800D03*
X97800Y197600D03*
X104820Y202100D03*
Y195700D03*
X97800Y200800D03*
X53400Y298100D03*
X79410Y331636D03*
X84000Y324542D03*
X77960Y541468D03*
Y538468D03*
X75461Y541468D03*
Y538468D03*
X73009Y541444D03*
Y538444D03*
X71500Y575000D03*
Y578000D03*
Y582000D03*
X81500Y575000D03*
X78500D03*
X81500Y578000D03*
X78500D03*
X74500Y575000D03*
Y578000D03*
Y582000D03*
X81500D03*
X78500D03*
X75500Y557500D03*
X72500Y561500D03*
Y557500D03*
X69500Y561500D03*
Y557500D03*
X75500Y561500D03*
X78500D03*
X81500D03*
Y557500D03*
X78500D03*
X66500Y554500D03*
X70521Y538403D03*
X68500Y535500D03*
X70498Y541394D03*
X75500Y554500D03*
X72500D03*
X69500D03*
X81500D03*
X78500D03*
X80389Y541468D03*
Y538468D03*
X66500Y557500D03*
Y561500D03*
X78500Y615500D03*
X81500D03*
X75500D03*
X72500D03*
X69500D03*
X78500Y602000D03*
X72500D03*
X69500Y596000D03*
X81500Y599000D03*
X78500D03*
X81500Y596000D03*
Y612000D03*
X78500D03*
X69500Y599000D03*
Y602000D03*
X75500D03*
X78500Y596000D03*
X72500D03*
X66500Y599000D03*
Y602000D03*
Y596000D03*
X81500Y602000D03*
X75500Y596000D03*
X72500Y599000D03*
X75500D03*
X114680Y17320D03*
X112007Y93139D03*
X114082Y55100D03*
X117652Y132792D03*
X120117Y132865D03*
X120138Y130408D03*
X117682Y130387D03*
X156954Y192872D03*
X154454Y193021D03*
X151810Y192670D03*
X141263Y215216D03*
X137763Y217716D03*
X141263D03*
X137763Y215216D03*
X169150Y223600D03*
Y227600D03*
X141263Y234216D03*
X141200Y229600D03*
X141211Y225615D03*
X141300Y221700D03*
X139763Y231700D03*
Y227600D03*
Y223700D03*
X139582Y219800D03*
X125563Y234316D03*
X125663Y230716D03*
X125563Y227116D03*
X141263Y249716D03*
Y247216D03*
X137763D03*
Y249716D03*
X125563Y259116D03*
X125663Y262716D03*
X125563Y266316D03*
X141300Y253700D03*
X139631Y251900D03*
X137763Y279216D03*
X141263Y266216D03*
X139763Y255700D03*
Y259600D03*
X139800Y263700D03*
X141313Y257533D03*
X141263Y279216D03*
X141200Y261600D03*
X137300Y337200D03*
X125663Y294716D03*
X125563Y298316D03*
Y291116D03*
X141263Y311216D03*
X137763D03*
X141263Y281716D03*
X139730Y284200D03*
X139763Y288200D03*
Y292000D03*
Y296000D03*
X141200Y286100D03*
X141261Y290076D03*
X141300Y294000D03*
X141263Y298216D03*
X137763Y281716D03*
X141211Y325515D03*
X141263Y330216D03*
X139763Y327800D03*
X141300Y317500D03*
Y321500D03*
X139582Y315800D03*
X139763Y319400D03*
X125563Y323116D03*
X125663Y326716D03*
X125563Y330316D03*
X141263Y313716D03*
X137763D03*
X139763Y323600D03*
X141289Y349488D03*
X141300Y353300D03*
X141200Y357200D03*
X137763Y345716D03*
X141263D03*
Y343216D03*
X137763D03*
X125563Y362316D03*
Y355116D03*
X125663Y358716D03*
X141263Y362216D03*
X139582Y347800D03*
X139763Y351400D03*
Y355200D03*
Y359500D03*
X141300Y381800D03*
X139763Y384000D03*
X141263Y394216D03*
Y390416D03*
X141261Y385876D03*
X139736Y392300D03*
X125663Y390716D03*
X125563Y387116D03*
Y394316D03*
X137763Y375216D03*
X141263D03*
Y377716D03*
X137763D03*
X139631Y379900D03*
X139900Y388000D03*
X114792Y528600D03*
X113692Y566000D03*
X114792Y604600D03*
X206800Y246500D03*
X203947Y280933D03*
X206600Y372400D03*
X195233Y348402D03*
X271239Y211060D03*
X284759Y207159D03*
X291519D03*
X274619Y213009D03*
Y216909D03*
X277999Y211060D03*
Y214960D03*
Y203260D03*
Y207159D03*
X281379Y213009D03*
X288139Y216909D03*
X284759Y214960D03*
X291519D03*
Y218860D03*
X281379Y201309D03*
X284759Y199360D03*
X291519D03*
X267859Y244209D03*
Y240309D03*
X271239Y238360D03*
X264179D03*
X264092Y222710D03*
X264179Y226660D03*
X271239Y277360D03*
X267392Y276000D03*
X267359Y279310D03*
X291519Y238360D03*
X284759Y234460D03*
X288139Y232509D03*
X281379D03*
X277999Y234460D03*
X274619Y232509D03*
Y220809D03*
Y224709D03*
Y228610D03*
X277999Y230559D03*
X274619Y244209D03*
Y240309D03*
Y236409D03*
X291519Y246160D03*
X284759D03*
X291519Y242260D03*
X281379Y220809D03*
X284759Y226660D03*
X288139Y236409D03*
X291519Y234460D03*
Y222760D03*
Y230559D03*
Y226660D03*
X281379Y240309D03*
X288139Y279310D03*
X274619D03*
X281379D03*
X239778Y274478D03*
X271239Y320260D03*
Y324160D03*
X270939Y316160D03*
X267359Y318309D03*
X267859Y326110D03*
X267392Y322000D03*
X270892Y304660D03*
Y311960D03*
Y300760D03*
Y308560D03*
Y292959D03*
Y289060D03*
X271239Y281260D03*
X270892Y285500D03*
Y296860D03*
X267359Y283209D03*
X281379Y302709D03*
X288139D03*
X291519Y304660D03*
X281379Y306609D03*
Y310509D03*
X288139Y306609D03*
Y310509D03*
X284759Y304660D03*
X281379Y287109D03*
X288139Y291009D03*
X284759Y289060D03*
Y281260D03*
X291519Y289060D03*
Y281260D03*
Y296860D03*
X288139Y298809D03*
X274619Y306609D03*
Y310509D03*
X277999Y304660D03*
X274619Y302709D03*
Y298809D03*
Y294909D03*
X277999Y289060D03*
Y281260D03*
X274619Y283209D03*
Y287109D03*
Y291009D03*
X277999Y296860D03*
X288139Y283209D03*
Y287109D03*
X281379Y298809D03*
Y294909D03*
X288139D03*
X284759Y296860D03*
X281379Y291009D03*
Y283209D03*
X291519Y312460D03*
X284759D03*
X277999D03*
X274619Y314409D03*
X281379D03*
X288139D03*
X274619Y318309D03*
X267559Y369010D03*
X267492Y380709D03*
X271239Y390460D03*
X267859Y388509D03*
X271239Y382660D03*
X291519Y359260D03*
Y355360D03*
X274619Y365109D03*
X277999Y367060D03*
X274619Y369010D03*
X288139Y365109D03*
X281379D03*
X284759Y363160D03*
X291519D03*
X284759Y370959D03*
X291519Y367060D03*
Y370959D03*
X288139Y361209D03*
Y380709D03*
Y400209D03*
X274619Y380709D03*
X277999Y394359D03*
X274619Y392410D03*
X277999Y390460D03*
Y386560D03*
X274619Y376809D03*
Y372909D03*
X291519Y374860D03*
X277999Y382660D03*
X284759Y398260D03*
X281379Y396309D03*
X291519Y398260D03*
X284759Y390460D03*
X291519D03*
X281379Y376809D03*
Y384609D03*
X284759Y382660D03*
X291519D03*
Y378760D03*
X321061Y-1743D03*
X314368Y-1843D03*
X331100Y-4536D03*
X327754Y-7108D03*
X317714Y-9786D03*
X311021D03*
X314368Y9114D03*
X321061D03*
X331100D03*
X311021Y28014D03*
X317714D03*
X311021Y17057D03*
X317714D03*
X327754D03*
Y28014D03*
X347833Y-7108D03*
X351179Y9122D03*
Y-4536D03*
X341140Y-1743D03*
X337793Y-9901D03*
X341140Y9122D03*
X347833Y17057D03*
Y28022D03*
X337793Y17057D03*
Y28014D03*
X311021Y65814D03*
X317714D03*
X321061Y35957D03*
X314368D03*
Y46914D03*
X311021Y54857D03*
X317714D03*
X321061Y46914D03*
X331100D03*
X327754Y65814D03*
X331100Y35957D03*
X327754Y54857D03*
Y92757D03*
X331100Y84714D03*
Y73757D03*
X314368D03*
Y87392D03*
X311021Y89964D03*
X317714D03*
X321061Y87392D03*
Y73757D03*
X341140Y35957D03*
X337793Y65814D03*
Y54857D03*
X351179Y46922D03*
X347833Y54857D03*
X341140Y46922D03*
X347833Y65822D03*
X351179Y35957D03*
X347833Y92757D03*
X351179Y84599D03*
Y73757D03*
X337793Y89964D03*
X341140Y87392D03*
Y73757D03*
X294899Y213009D03*
X308418Y201309D03*
X317428Y193507D03*
X301648Y194841D03*
X332078Y218860D03*
X329818Y214958D03*
X298279Y218860D03*
X311798Y211060D03*
Y218860D03*
Y214960D03*
X308418Y213009D03*
X305039Y211060D03*
Y218860D03*
X324200Y201308D03*
X298279Y199360D03*
X294899Y201309D03*
X312918Y205210D03*
X315178Y209109D03*
X298279Y207159D03*
Y203260D03*
Y211060D03*
X318558Y218860D03*
X315178Y216909D03*
Y213009D03*
X301659Y209109D03*
X325318Y211060D03*
X334328Y199108D03*
X348978Y209109D03*
X352357Y211060D03*
X338838Y211058D03*
X335458Y216909D03*
X355737Y209109D03*
X294899Y224709D03*
X332078Y242260D03*
X328698Y232509D03*
Y220809D03*
X332078Y234460D03*
X298279Y246160D03*
X305039D03*
X308418Y244209D03*
X294899D03*
X325318Y242260D03*
Y226660D03*
X298279Y234460D03*
X308418Y228610D03*
Y224709D03*
X305039Y230559D03*
X311798Y222760D03*
X308418Y232509D03*
X294899Y228610D03*
X325318Y234460D03*
Y230559D03*
Y222760D03*
X318558Y246160D03*
X308418Y240309D03*
X315178D03*
X301659D03*
X318558Y242260D03*
X298279Y226660D03*
X318558D03*
X315178Y220809D03*
X321938D03*
X315178Y232509D03*
X301659Y228610D03*
X308418Y236409D03*
X321938D03*
X311798Y238360D03*
X318558D03*
X305039Y226660D03*
X301659Y279310D03*
X308418D03*
X294899D03*
X348978Y220809D03*
X352357Y238360D03*
X345598D03*
X342218Y220809D03*
X338838Y246160D03*
Y242260D03*
Y234460D03*
X335458Y236409D03*
X338838Y238360D03*
X335458Y224709D03*
X355737Y220809D03*
X348978Y267609D03*
X345598Y277360D03*
X348978Y279310D03*
Y275409D03*
Y271509D03*
X352357Y265660D03*
X355737Y263709D03*
X335458Y322209D03*
X308418Y306609D03*
X301659Y310509D03*
Y306609D03*
X311798Y304660D03*
X305039D03*
X321938Y306609D03*
X325318Y304660D03*
Y308560D03*
X298279Y304660D03*
X294899Y302709D03*
X308418D03*
X301659D03*
X315178D03*
X321938D03*
X294899Y310509D03*
Y306609D03*
X318558Y304660D03*
Y308560D03*
X321938Y291009D03*
X318558Y296860D03*
X315178Y294909D03*
X321938D03*
X301659D03*
X325318Y285160D03*
Y289060D03*
Y296860D03*
X298279D03*
Y289060D03*
Y281260D03*
X308418Y298809D03*
X301659D03*
X308418Y283209D03*
X305039Y281260D03*
Y289060D03*
X308418Y291009D03*
Y287109D03*
X311798Y281260D03*
Y289060D03*
X308418Y294909D03*
X311798Y296860D03*
X305039D03*
X315178Y287109D03*
X318558Y285160D03*
X321938Y287109D03*
X301659Y283209D03*
Y287109D03*
Y291009D03*
X294899Y298809D03*
Y294909D03*
Y291009D03*
Y283209D03*
Y287109D03*
X315178Y298809D03*
X321938D03*
X318558Y289060D03*
X315178Y291009D03*
X332078Y308560D03*
Y304660D03*
X328698Y302709D03*
Y306609D03*
Y287109D03*
Y291009D03*
Y294909D03*
Y298809D03*
X332078Y296860D03*
Y285160D03*
Y289060D03*
X315178Y306609D03*
X308418Y310509D03*
X311798Y312460D03*
X305039D03*
X298279D03*
X294899Y314409D03*
X308418D03*
X301659D03*
X328698D03*
X321938D03*
X332078Y328060D03*
X328698Y322209D03*
Y318309D03*
X332078Y324160D03*
Y320260D03*
Y316360D03*
X325318Y320260D03*
X305039D03*
X321938Y318309D03*
X315178D03*
X318558Y316360D03*
X301659Y322209D03*
X325318Y316360D03*
X305039Y324160D03*
X311798Y320260D03*
X308418Y322209D03*
X301659Y326110D03*
X335458Y298809D03*
X348978Y287109D03*
X345598Y285160D03*
Y281260D03*
X348978Y283209D03*
Y298809D03*
Y291009D03*
X345598Y289060D03*
Y292959D03*
Y296860D03*
X348978Y294909D03*
X345598Y300760D03*
X348978Y302709D03*
Y306609D03*
X345598Y304660D03*
Y308560D03*
X348978Y310509D03*
X342218Y302709D03*
Y306609D03*
Y291009D03*
Y287109D03*
Y294909D03*
Y298809D03*
X338838Y308560D03*
X335458Y302709D03*
X338838Y304660D03*
X335458Y306609D03*
Y287109D03*
X338838Y289060D03*
Y285160D03*
X335458Y291009D03*
X338838Y296860D03*
X335458Y294909D03*
X348978Y314409D03*
X345598Y312460D03*
Y316360D03*
X335458Y314409D03*
Y326110D03*
Y318309D03*
X338838Y320260D03*
Y324160D03*
Y328060D03*
X308418Y357309D03*
X311798Y359260D03*
X298279Y351460D03*
X294899Y349509D03*
Y353409D03*
X321938Y349509D03*
X318558Y359260D03*
X321938Y361209D03*
X315178Y357309D03*
X301659D03*
Y349509D03*
X308418Y361209D03*
Y353409D03*
X325318Y343660D03*
Y347560D03*
X328698Y365109D03*
X332078Y363160D03*
X328698Y345609D03*
X325318Y355360D03*
X332078Y347560D03*
Y355360D03*
X294899Y369010D03*
X325318Y367060D03*
Y370959D03*
X318558D03*
X308418Y365109D03*
X315178D03*
X325318Y363160D03*
X298279D03*
X305039Y370959D03*
X308418Y369010D03*
X305039Y367060D03*
X301659Y369010D03*
X298279Y370959D03*
X318558Y351460D03*
Y355360D03*
X305039Y351460D03*
X301659Y388509D03*
X308418D03*
X318558Y394359D03*
X324458Y399911D03*
X332078Y378760D03*
X318558Y386560D03*
X325318D03*
X311798Y374860D03*
X325318D03*
X294899Y372909D03*
X308418D03*
X321938Y376809D03*
X318558Y382660D03*
Y378760D03*
X298279D03*
X305039D03*
X308418Y384609D03*
X311798Y382660D03*
Y378760D03*
X315178Y376809D03*
X328698D03*
X294899Y384609D03*
X318558Y390460D03*
X320808Y401941D03*
X298279Y386560D03*
Y390460D03*
X315178Y392410D03*
Y388509D03*
X311798Y386560D03*
X298279Y398260D03*
Y394359D03*
X294899Y396309D03*
X325318Y378760D03*
X321938Y380709D03*
X305039Y394359D03*
X302608Y402421D03*
X352357Y359260D03*
X338838Y347560D03*
X335458Y361209D03*
X338838Y359260D03*
Y355360D03*
Y351460D03*
X335458Y349509D03*
X345598Y359260D03*
X348978Y349509D03*
X345598Y343660D03*
X342218Y345609D03*
X355737Y349509D03*
Y376809D03*
Y388509D03*
X348978Y376809D03*
X342218Y388509D03*
Y376809D03*
X335458Y372909D03*
Y384609D03*
Y380709D03*
X345598Y390460D03*
X352357Y386560D03*
X317714Y515364D03*
X321061Y512792D03*
X331100Y510114D03*
X327754Y518157D03*
X314368Y512792D03*
X311021Y515364D03*
X337793D03*
X350882Y509999D03*
X347833Y518157D03*
X341140Y512792D03*
X321061Y536957D03*
X317714Y529014D03*
X331100Y547914D03*
Y536957D03*
X327754Y529014D03*
X321061Y547914D03*
X314368D03*
Y536957D03*
X311021Y529014D03*
X327754Y555857D03*
X317714D03*
X311021D03*
X327754Y566814D03*
X331100Y574757D03*
Y585714D03*
X314368D03*
Y574757D03*
X317714Y566814D03*
X311021D03*
X321061Y585714D03*
Y574757D03*
X337793Y529014D03*
X351179Y547922D03*
Y536957D03*
X347833Y529022D03*
X341140Y547922D03*
Y536957D03*
X337793Y555857D03*
X347833D03*
X337793Y566814D03*
X341140Y574757D03*
Y585722D03*
X351179Y574757D03*
Y585722D03*
X347833Y566822D03*
X327754Y607292D03*
X331100Y609864D03*
X327754Y593657D03*
X317714D03*
X311021D03*
X317714Y604614D03*
X311021D03*
X314368Y612457D03*
X321061D03*
X337793Y593657D03*
Y604499D03*
X352109Y609918D03*
X347833Y607292D03*
X341140Y612457D03*
X347833Y593657D03*
X357872Y-9786D03*
X367911D03*
Y-1858D03*
X357872D03*
X367911Y9114D03*
X357672D03*
X357872Y28014D03*
X367911D03*
Y17042D03*
X357872Y17014D03*
X398029Y-4536D03*
X401375Y-7108D03*
X408068Y-1743D03*
X411415Y-9786D03*
X398029Y9107D03*
X408069D03*
X411416Y17057D03*
X401376Y17042D03*
X367911Y46914D03*
Y54842D03*
Y35942D03*
X358619Y36031D03*
X358618Y54842D03*
X357872Y65736D03*
X366992Y65950D03*
X357872Y46914D03*
X357965Y92500D03*
X367911Y87500D03*
X368311Y92500D03*
X367742Y73450D03*
X357872Y87500D03*
X358491Y73479D03*
X408069Y35942D03*
X401376Y54842D03*
X408069Y46907D03*
X398029Y35942D03*
Y46907D03*
X411416Y54857D03*
X401375Y92757D03*
X398029Y84800D03*
Y73742D03*
X408068Y87392D03*
X411415Y89964D03*
X408069Y73742D03*
X408126Y105750D03*
X414820Y105800D03*
X401375D03*
X362497Y209109D03*
X382777D03*
X376017D03*
X389537D03*
X396296D03*
X407706D03*
X379397Y238360D03*
X362497Y220809D03*
X369257D03*
X382777D03*
X376017D03*
X386157Y238360D03*
X389537Y248109D03*
Y220809D03*
X382777Y248109D03*
X386157Y250060D03*
X359117Y238360D03*
X365877D03*
X372637D03*
Y253960D03*
X376017Y252009D03*
X357057Y277360D03*
X368127Y264300D03*
X364747Y266300D03*
X361492Y268100D03*
X362497Y259809D03*
X365877Y257860D03*
X369257Y255909D03*
X357092Y270700D03*
X391787Y254259D03*
X388407Y256500D03*
X359648Y269777D03*
X374887Y260300D03*
X385027Y254259D03*
X359117Y261760D03*
X371507Y262300D03*
X381647Y256400D03*
X378267Y258400D03*
X357057Y273460D03*
X392916Y250060D03*
Y238360D03*
X396296Y248109D03*
Y220809D03*
X399676Y250060D03*
X407706Y248109D03*
Y220809D03*
X395166Y256400D03*
X398546Y254259D03*
X405306Y254500D03*
X401926Y256500D03*
X357057Y281260D03*
Y296860D03*
Y285160D03*
Y292959D03*
Y300760D03*
Y308560D03*
Y304660D03*
Y289060D03*
Y312460D03*
X369257Y341709D03*
X365877Y339760D03*
X381647Y341260D03*
X378267Y339309D03*
X357057Y316360D03*
X414294Y292904D03*
X411294D03*
Y309904D03*
X414294D03*
X379397Y359260D03*
X391787Y347109D03*
X388407Y345160D03*
X372637Y343660D03*
X385027Y343209D03*
X386157Y351460D03*
Y359260D03*
X389537Y353409D03*
X372637Y359260D03*
X365877D03*
X359117D03*
X376017Y376809D03*
X369257D03*
X382777Y388509D03*
X369257D03*
X362497D03*
X376017D03*
X389537D03*
Y376809D03*
X382777D03*
X362497D03*
X396296Y353409D03*
X399676Y351460D03*
X395166Y345160D03*
X398546Y347109D03*
X401926Y345160D03*
X392916Y351460D03*
Y359260D03*
X396296Y388509D03*
Y376809D03*
X411086Y374860D03*
X403056Y376809D03*
Y388509D03*
X386630Y521860D03*
X359042Y515200D03*
X358918Y510114D03*
X366865D03*
Y515152D03*
X401375Y518157D03*
X398029Y509999D03*
X411415Y515364D03*
X408068Y512792D03*
X370080Y555700D03*
X366890Y586000D03*
X367692Y547914D03*
X357672D03*
X357872Y528942D03*
X367911Y529057D03*
X367692Y536200D03*
X357910Y536727D03*
X367211Y555842D03*
X357910D03*
X367192Y566814D03*
X357910D03*
X367192Y574742D03*
X357872D03*
X357025Y585714D03*
X398029Y536942D03*
X408069Y547907D03*
Y536942D03*
X398029Y547907D03*
X401376Y555842D03*
X411416Y555857D03*
X398029Y574742D03*
Y585707D03*
X408069D03*
Y574742D03*
X408068Y612657D03*
X357872Y604614D03*
X367170Y611759D03*
X357872Y612242D03*
X367911Y593642D03*
X357026D03*
X367911Y604614D03*
X398029Y609864D03*
X401376Y593642D03*
X401375Y607292D03*
X411416Y593657D03*
X411415Y604614D03*
X418108Y-4536D03*
X431494D03*
X424801D03*
X428147Y-7108D03*
X434840D03*
X431494Y9107D03*
X424801D03*
X418108D03*
Y-9701D03*
X441533Y-1843D03*
Y9107D03*
X434842Y17057D03*
X441533Y17042D03*
X418108D03*
X428149Y17057D03*
X418108Y28007D03*
X441533D03*
X434842Y54857D03*
X441533Y54842D03*
X424801Y46907D03*
X431494D03*
X428149Y54857D03*
X441533Y46907D03*
X418108Y65807D03*
Y54842D03*
X441533Y65807D03*
X431494Y35942D03*
X441533D03*
X424801D03*
X418108D03*
Y46907D03*
X428147Y92500D03*
X424801Y84800D03*
X431400D03*
X431494Y73742D03*
X441533Y87392D03*
Y92500D03*
Y73742D03*
X418108Y89964D03*
Y84599D03*
Y73742D03*
X424801D03*
X434840Y92500D03*
X427696Y105800D03*
X421503D03*
X476672Y262996D03*
Y266896D03*
X473292Y268847D03*
Y264947D03*
X442020Y339220D03*
X438240Y339380D03*
X449500Y309800D03*
X451648Y308341D03*
X447000Y309800D03*
X421494Y292904D03*
X435894D03*
X432894D03*
X440094D03*
X443094D03*
X425694D03*
X418494D03*
X428694D03*
X418494Y309904D03*
X421494D03*
X425694D03*
X428694D03*
X432894D03*
X435894D03*
X440094Y309841D03*
X443148D03*
X454148Y310341D03*
Y307841D03*
X474413Y329296D03*
X468783Y332897D03*
X474413Y333196D03*
Y325396D03*
X477792Y323446D03*
Y331247D03*
Y335147D03*
Y339047D03*
X443993Y358547D03*
X437233D03*
X450753Y366347D03*
Y358547D03*
X437233Y362447D03*
X423714D03*
X433854Y368296D03*
X427094D03*
X440613Y364396D03*
X427094Y372197D03*
X447373D03*
Y368296D03*
X440613Y372197D03*
Y368296D03*
X443993Y366347D03*
X427094Y356596D03*
X437233Y354647D03*
X423714D03*
X430474D03*
X427094Y360496D03*
X433854D03*
X451883Y342646D03*
X448503Y344597D03*
X421464Y348497D03*
X438363Y346546D03*
X424844D03*
X434983Y348497D03*
X428224D03*
X431604Y346546D03*
X430474Y385847D03*
X450753Y397547D03*
X440613Y395595D03*
X429354Y399496D03*
X433854Y379996D03*
X423714Y374146D03*
X437233D03*
X430474Y378047D03*
X433854Y376096D03*
X443993Y397546D03*
Y401447D03*
Y393647D03*
X440613Y391696D03*
X443993Y385847D03*
X427094Y376096D03*
X437233Y381947D03*
X447373Y376096D03*
X440613Y379996D03*
X443993Y378047D03*
X423715Y397548D03*
X430474Y393647D03*
X433854Y391696D03*
X423715Y401449D03*
X450753Y385847D03*
Y393647D03*
Y378047D03*
X437233Y389747D03*
Y385847D03*
X423714D03*
X443993Y405347D03*
X441533Y512792D03*
Y518057D03*
X433192Y497650D03*
X434840Y518157D03*
X431494Y509999D03*
X424801Y510114D03*
X418108Y515364D03*
Y509999D03*
X428147Y518157D03*
X418108Y536942D03*
Y547907D03*
X431494D03*
X424801D03*
X441533D03*
X418108Y529007D03*
X431494Y536942D03*
X424801D03*
X441533Y536957D03*
Y529007D03*
X418108Y555842D03*
X428149Y555857D03*
X434842D03*
X441533Y555842D03*
Y585707D03*
Y574742D03*
X418108Y566807D03*
X441533D03*
X424801Y574742D03*
X418108Y585599D03*
Y574742D03*
X431494D03*
Y585707D03*
X424801D03*
X441533Y612557D03*
Y607292D03*
X434840D03*
X428147D03*
X418108Y609864D03*
X424801D03*
X431494D03*
X418108Y593642D03*
X434842Y593657D03*
X428149D03*
X441533Y593642D03*
X418108Y604499D03*
X504832Y264947D03*
X487932Y270796D03*
X498072Y268847D03*
X491312D03*
X487932Y266896D03*
X491312Y264947D03*
X480052D03*
X481172Y270796D03*
X494692Y262996D03*
Y305896D03*
X491312Y311747D03*
X501452Y301996D03*
X491312Y307847D03*
X498072Y311747D03*
X511592Y296147D03*
X501452Y294196D03*
X498072Y296147D03*
X504832D03*
X508212Y298096D03*
X498072Y300047D03*
X484552Y307847D03*
X508212Y340996D03*
X498072Y339047D03*
X501452Y313696D03*
X494692D03*
X501452Y329296D03*
X487932Y340996D03*
Y329296D03*
X494692D03*
X491312Y327347D03*
X498072Y331247D03*
X484552Y335147D03*
X481172Y337096D03*
X501452Y321496D03*
X481172Y340996D03*
X484552Y339047D03*
X487932Y337096D03*
Y333196D03*
X491312Y335147D03*
X494692Y333196D03*
X498072Y335147D03*
X491312Y319547D03*
X494692Y321496D03*
X501452Y317596D03*
X498072Y315647D03*
Y323446D03*
X494692Y325396D03*
X501452D03*
X514972Y298096D03*
X518352Y292245D03*
Y288347D03*
X521731Y286396D03*
Y290296D03*
Y298096D03*
X525111Y292245D03*
Y296147D03*
X528491Y290296D03*
X525111Y288347D03*
X521731Y294196D03*
X518352Y300047D03*
Y296147D03*
X514972Y340996D03*
X525111Y339047D03*
X535251Y333196D03*
Y325396D03*
X484552Y342947D03*
X508212Y344896D03*
Y348796D03*
X511592Y346847D03*
Y350747D03*
Y342947D03*
X504832Y362447D03*
X494692Y368296D03*
Y352696D03*
X508212Y356596D03*
X504832Y350747D03*
X487932Y348796D03*
X481172Y356596D03*
X484552Y358547D03*
Y350747D03*
Y354647D03*
X487932Y352696D03*
Y344896D03*
X511592Y374146D03*
X501452Y383896D03*
X498072Y389747D03*
X494692Y376096D03*
X508212Y379996D03*
X521731Y368296D03*
X518352Y366347D03*
X514972Y348796D03*
Y344896D03*
Y352696D03*
X518352Y358547D03*
X521731Y344896D03*
X538631Y370247D03*
X525111Y350747D03*
X514972Y399496D03*
X538631Y381947D03*
X531871Y385847D03*
X528491Y391696D03*
X525111Y397546D03*
X531871Y405347D03*
X590500Y215800D03*
Y213000D03*
X599773Y199596D03*
X600286Y202921D03*
X600400Y226800D03*
X592300Y220500D03*
X548771Y337096D03*
Y329296D03*
X542011Y364396D03*
Y372197D03*
Y352696D03*
X545391Y342947D03*
X559212Y385847D03*
X663699Y3861D03*
X656300Y22800D03*
X653800D03*
X656600Y31500D03*
X663300Y10000D03*
X609860Y201356D03*
X613082Y200676D03*
X613773Y196796D03*
X610273Y197496D03*
X606400Y201000D03*
X606773Y198196D03*
X603273Y198896D03*
X613648Y204494D03*
X608648D03*
X604453Y202983D03*
X623648Y209494D03*
Y216994D03*
Y211994D03*
Y214494D03*
X613648Y209494D03*
Y211994D03*
X618648Y209494D03*
Y214494D03*
X621148Y211994D03*
Y216994D03*
X613648Y214494D03*
Y216994D03*
X623648Y206994D03*
X611148D03*
X618648D03*
X621148D03*
X616148D03*
Y211994D03*
Y216994D03*
X644750Y175650D03*
X616148Y221994D03*
X623648Y224494D03*
Y226994D03*
X611148Y224494D03*
X613648D03*
X618648D03*
Y226994D03*
X621148D03*
X616148D03*
X608648D03*
Y224494D03*
X603300Y226700D03*
X613648Y226994D03*
Y229494D03*
X621148D03*
X618648D03*
X611148D03*
X623648Y221994D03*
Y219494D03*
X611148Y221994D03*
X618648Y219494D03*
X621148Y221994D03*
X613648Y219494D03*
Y221994D03*
X662800Y248600D03*
X639320Y268000D03*
X652500Y273600D03*
X606148Y229494D03*
X652000Y284500D03*
X663200Y298600D03*
X644800Y292150D03*
X654500Y298600D03*
X652100Y288300D03*
X639045Y299555D03*
X639100Y309500D03*
X649000Y339400D03*
X638790Y329500D03*
X639350Y339980D03*
X639100Y319500D03*
X655900Y307700D03*
X656300Y312300D03*
X660700Y307700D03*
X655900Y316500D03*
X656000Y329800D03*
X655900Y320500D03*
X656000Y325100D03*
X660900Y329800D03*
X664100Y348000D03*
X648800D03*
X658900D03*
X662936Y367171D03*
X659936Y364171D03*
X662936D03*
X654000Y348000D03*
X624600Y419400D03*
X626737Y421000D03*
X619800Y416200D03*
X624300Y422100D03*
X627000Y423436D03*
X622900Y424200D03*
X619680Y422600D03*
X621800Y421100D03*
X619700Y419500D03*
X629600Y425100D03*
X622100Y417900D03*
X605249Y480891D03*
X605826Y475894D03*
Y473394D03*
X634967Y470790D03*
X605206Y483291D03*
X637148Y472809D03*
X657227Y479116D03*
X662181Y479149D03*
X659770D03*
X661500Y569800D03*
X658900D03*
X650050Y568623D03*
X647350D03*
X663100Y574200D03*
X665942Y4716D03*
X666100Y10000D03*
X693600Y103100D03*
X694459Y105382D03*
X691810Y105540D03*
X701953Y104902D03*
X696100Y102700D03*
X696832Y104986D03*
X699400Y105060D03*
X704419Y104448D03*
X698600Y102600D03*
X709341Y190507D03*
X716480Y194700D03*
X709400Y195763D03*
X701956Y195294D03*
X705292Y195729D03*
X714137Y195682D03*
X711886Y194714D03*
X719686Y195421D03*
X722117Y195399D03*
X697568Y196197D03*
X707529Y193200D03*
X704907Y191638D03*
X701129Y192106D03*
X697746Y193205D03*
X678454Y278000D03*
X675380Y246340D03*
X678000Y246400D03*
X667240Y246600D03*
X672530Y246300D03*
X667600Y250200D03*
X690380Y252240D03*
X690939Y266630D03*
X693530Y261240D03*
X690660Y264000D03*
X690704Y271324D03*
X701800Y246480D03*
X669750Y246350D03*
X700900Y264100D03*
X672300Y269200D03*
X672200Y256800D03*
X719900Y269300D03*
X725500Y279300D03*
X725300Y269400D03*
X719600Y279400D03*
X704175Y287275D03*
X704214Y290775D03*
X680000Y281900D03*
X672150Y288350D03*
X695300Y338100D03*
X695400Y328000D03*
X684100Y338200D03*
X695400Y318000D03*
X695800Y308000D03*
X696088Y297069D03*
X704500Y293800D03*
X707130Y310150D03*
X718200Y295000D03*
X706300Y318400D03*
X678200Y307800D03*
X672700Y307700D03*
X667100D03*
X678100Y324800D03*
X672200Y329800D03*
X678100Y329600D03*
X666900Y329700D03*
X678200Y313700D03*
Y319300D03*
X679000Y348000D03*
X688600Y365100D03*
X671936Y367171D03*
X665936Y370171D03*
X684900Y348000D03*
X674600D03*
X671936Y370171D03*
X665936Y367171D03*
X668936Y370171D03*
Y367171D03*
X665936Y364171D03*
X668936D03*
X669093Y348120D03*
X671936Y373171D03*
X668936D03*
X670300Y375600D03*
X713900Y347800D03*
X698560Y374430D03*
X713900Y342800D03*
Y352800D03*
Y350300D03*
Y345300D03*
X665700Y574200D03*
X722200Y571300D03*
X712000Y597000D03*
Y599500D03*
X708800Y599300D03*
Y596700D03*
X734500Y-5700D03*
X734916Y-1587D03*
X732316D03*
X732191Y-4087D03*
X735020Y-8858D03*
X729500Y23500D03*
X764100Y17100D03*
X731200Y68600D03*
X733600Y68546D03*
X733642Y66146D03*
X731242Y66200D03*
X731332Y63801D03*
X733732Y63747D03*
X764100Y55100D03*
X761650Y94550D03*
X733564Y189288D03*
X742091Y188333D03*
X747469Y188368D03*
X755248D03*
X739641Y190634D03*
X752708Y188455D03*
X750167Y188490D03*
X744928Y188438D03*
X737319Y189766D03*
X739359Y188125D03*
X735626Y187965D03*
X731155Y189256D03*
X737536Y192392D03*
X766368Y183636D03*
X765227Y186164D03*
X765007Y188583D03*
X762667Y186186D03*
X762533Y188626D03*
X763881Y184103D03*
X760084Y188508D03*
X760258Y186077D03*
X767692Y185654D03*
X767476Y188323D03*
X757654Y188464D03*
X787371Y215216D03*
Y217716D03*
X737837Y222364D03*
Y224964D03*
X740300Y228100D03*
X742937Y221174D03*
Y223774D03*
X740437Y224964D03*
Y222364D03*
X731100Y269300D03*
Y279300D03*
X775200Y230500D03*
X775171Y227116D03*
Y234316D03*
X787371Y247216D03*
Y249716D03*
X775271Y262716D03*
X775171Y259116D03*
Y266316D03*
X787371Y279216D03*
X749126Y220843D03*
X742897Y226773D03*
X727300Y302910D03*
X727474Y338363D03*
Y335363D03*
X732474D03*
Y338363D03*
X729974D03*
Y335363D03*
X775271Y294716D03*
X775171Y291116D03*
Y298316D03*
X787371Y281716D03*
Y311216D03*
X775271Y326716D03*
X775171Y323116D03*
Y330316D03*
X787371Y313716D03*
X727474Y344663D03*
Y367463D03*
X732474D03*
X729974D03*
X727474Y364863D03*
X732474D03*
X729974D03*
Y347663D03*
X727474D03*
X732474D03*
Y344663D03*
X727574Y373463D03*
X732574D03*
X730074D03*
X732574Y376063D03*
X730074D03*
X729974Y344663D03*
X731100Y362300D03*
X763333Y400212D03*
X772300Y403520D03*
X775171Y362316D03*
X775271Y358716D03*
X775171Y355116D03*
X787371Y343216D03*
Y345716D03*
X787321Y374916D03*
Y377316D03*
X775121Y394316D03*
X775221Y390716D03*
X775121Y387116D03*
X755487Y409903D03*
Y412403D03*
X748085Y412338D03*
X750585D03*
X753085D03*
Y409838D03*
X750585D03*
X748085D03*
X760326Y414167D03*
Y411667D03*
X757826D03*
Y414167D03*
X743483Y492937D03*
X748524Y502174D03*
X743524D03*
X748524Y499674D03*
X750931Y499916D03*
X746024Y499674D03*
X743524D03*
X746024Y502174D03*
X732098Y550000D03*
X729550D03*
X732098Y553000D03*
X729550D03*
X732098Y556000D03*
X729550D03*
X764400Y528600D03*
X763300Y566000D03*
X764400Y604600D03*
X822400Y212400D03*
X790871Y215216D03*
Y217716D03*
X799620Y186547D03*
X798337Y181216D03*
X804470Y186814D03*
X789500Y231800D03*
X790900Y234000D03*
Y229700D03*
X790846Y225774D03*
X790882Y221723D03*
X790871Y247216D03*
Y249716D03*
X789471Y227742D03*
X789576Y223737D03*
X789554Y219723D03*
X790900Y253900D03*
X789432Y252000D03*
X790871Y266216D03*
X789432Y255800D03*
X790867Y257724D03*
X789432Y259800D03*
X789500Y263900D03*
X790885Y261711D03*
X790871Y279216D03*
Y311216D03*
X789432Y284200D03*
Y288300D03*
Y292400D03*
X789400Y296200D03*
X790871Y298216D03*
X790937Y294270D03*
X790900Y290300D03*
Y286200D03*
X790871Y281716D03*
Y313716D03*
X789432Y319900D03*
Y323900D03*
X790900Y322000D03*
Y326000D03*
X790871Y330216D03*
X789500Y328000D03*
X789478Y315671D03*
X790800Y317700D03*
X789432Y348100D03*
Y352100D03*
X789597Y356105D03*
X789500Y360200D03*
X790900Y358200D03*
X790835Y354048D03*
X790867Y350024D03*
X790871Y345716D03*
Y343216D03*
Y362216D03*
X790821Y374916D03*
X790900Y389300D03*
X789500Y391300D03*
X790900Y393400D03*
Y381100D03*
X789582Y383200D03*
X790900Y385300D03*
X789500Y387300D03*
X790821Y377316D03*
X789282Y379200D03*
X882008Y321100D03*
X851430Y367468D03*
X960629Y-9786D03*
X963976Y-1843D03*
X970669Y-1743D03*
X967322Y-9786D03*
X963976Y9114D03*
X970669D03*
X967322Y28014D03*
X960629Y17057D03*
Y28014D03*
X967322Y17057D03*
Y65814D03*
X960629D03*
X970669Y35957D03*
Y46914D03*
X967322Y54857D03*
X963976Y35957D03*
Y46914D03*
X960629Y54857D03*
X963976Y73757D03*
X960629Y89964D03*
X963976Y87392D03*
X967322Y89964D03*
X970669Y87392D03*
Y73757D03*
X927607Y203260D03*
Y207159D03*
X934367D03*
X937747Y216909D03*
X924227D03*
X968166Y218860D03*
X947887Y203260D03*
Y207159D03*
X941127D03*
X947887Y218860D03*
X941127D03*
X962526Y205210D03*
X961406Y214960D03*
Y211060D03*
X951267Y209109D03*
X958026Y213009D03*
X954647Y211060D03*
X964786Y213009D03*
Y216909D03*
Y209109D03*
X934367Y226660D03*
X924227Y236409D03*
X920847Y238360D03*
X913787Y226660D03*
X913700Y222710D03*
X913787Y238360D03*
X924227Y232509D03*
X927607Y230559D03*
Y234460D03*
X930987Y232509D03*
X934367Y234460D03*
X924227Y228610D03*
X930987Y220809D03*
X924227Y224709D03*
X937747Y232509D03*
Y236409D03*
X924227Y240309D03*
X917467D03*
X930987D03*
X924227Y244209D03*
X917467D03*
X934367Y246160D03*
X924227Y220809D03*
X937747Y279310D03*
X917000Y276000D03*
X920847Y277360D03*
X924227Y279310D03*
X916967D03*
X930987D03*
X958026Y244209D03*
X968166Y242260D03*
X944507Y228610D03*
Y224709D03*
Y244209D03*
X941127Y242260D03*
Y246160D03*
X947887D03*
X941127Y222760D03*
X947887Y226660D03*
Y234460D03*
X941127Y238360D03*
Y234460D03*
Y230559D03*
Y226660D03*
X968166Y246160D03*
X951267Y240309D03*
X958026D03*
X964786D03*
X954647Y246160D03*
X958026Y228610D03*
Y236409D03*
X961406Y238360D03*
X951267Y228610D03*
X954647Y226660D03*
X958026Y224709D03*
Y232509D03*
X954647Y230559D03*
X971546Y236409D03*
X968166Y238360D03*
X971546Y220809D03*
X964786Y232509D03*
X944507Y279310D03*
X958026D03*
X951267D03*
X937747Y287109D03*
X920500Y304660D03*
Y300760D03*
X930987Y302709D03*
X924227D03*
X920500Y311960D03*
X927607Y304660D03*
X924227Y306609D03*
X930987D03*
Y310509D03*
X934367Y304660D03*
X924227Y310509D03*
X920500Y308560D03*
Y289060D03*
X934367Y296860D03*
X930987Y294909D03*
X920500Y296860D03*
Y292959D03*
X927607Y296860D03*
X924227Y298809D03*
X930987D03*
X924227Y283209D03*
X927607Y281260D03*
X920500Y285500D03*
X924227Y287109D03*
X920847Y281260D03*
X930987Y287109D03*
X934367Y289060D03*
Y281260D03*
X930987Y283209D03*
X924227Y291009D03*
X930987D03*
X927607Y289060D03*
X937747Y302709D03*
Y306609D03*
Y310509D03*
Y283209D03*
Y291009D03*
Y294909D03*
Y298809D03*
Y314409D03*
X924227D03*
X930987D03*
X934367Y312460D03*
X927607D03*
X920847Y324160D03*
X924227Y318309D03*
X920547Y316160D03*
X917167Y318309D03*
Y322209D03*
X917467Y326110D03*
X920847Y320260D03*
X971546Y294909D03*
X944507Y283209D03*
X964786Y291009D03*
X954647Y281260D03*
X958026Y283209D03*
X951267Y287109D03*
X958026D03*
X951267Y283209D03*
X961406Y281260D03*
Y296860D03*
X964786Y298809D03*
Y302709D03*
X971546D03*
X961406Y304660D03*
X958026Y302709D03*
X951267D03*
X968166Y308560D03*
X964786Y306609D03*
X968166Y304660D03*
X971546Y306609D03*
X951267Y310509D03*
X954647Y304660D03*
X958026Y306609D03*
Y310509D03*
X951267Y306609D03*
X944507Y302709D03*
Y306609D03*
Y310509D03*
X941127Y304660D03*
X947887D03*
X944507Y294909D03*
Y287109D03*
X971546Y298809D03*
X968166Y285160D03*
X964786Y287109D03*
X944507Y291009D03*
X941127Y281260D03*
Y289060D03*
Y296860D03*
X944507Y298809D03*
X947887Y289060D03*
Y296860D03*
Y281260D03*
X968166Y296860D03*
X964786Y294909D03*
X971546Y291009D03*
Y287109D03*
X968166Y289060D03*
X961406D03*
X958026Y298809D03*
X951267D03*
Y291009D03*
X958026D03*
X954647Y289060D03*
Y296860D03*
X958026Y294909D03*
X951267D03*
X944507Y314409D03*
X951267D03*
X958026D03*
X961406Y312460D03*
X954647D03*
X941127D03*
X947887D03*
X971546Y314409D03*
Y318309D03*
X964786D03*
X951267Y322209D03*
X954647Y324160D03*
X961406Y320260D03*
X954647D03*
X958026Y322209D03*
X951267Y326110D03*
X968166Y316360D03*
X937747Y365109D03*
Y361209D03*
X930987Y365109D03*
X927607Y367060D03*
X934367Y370959D03*
Y363160D03*
X924227Y369010D03*
X917167D03*
X934367Y382660D03*
X930987Y384609D03*
Y376809D03*
X934367Y390460D03*
X927607Y386560D03*
Y390460D03*
X930987Y396309D03*
X934367Y398260D03*
X927607Y394359D03*
X917467Y388509D03*
X924227Y392410D03*
X920847Y390460D03*
X924227Y372909D03*
X937747Y400209D03*
X917100Y380709D03*
X937747D03*
X924227D03*
X920847Y382660D03*
X924227Y376809D03*
X927607Y382660D03*
X968166Y370959D03*
X958026Y361209D03*
X961406Y359260D03*
X958026Y357309D03*
X951267D03*
X941127Y355360D03*
Y351460D03*
X954647D03*
X958026Y353409D03*
X968166Y355360D03*
Y351460D03*
X964786Y357309D03*
X971546Y361209D03*
X968166Y359260D03*
X958026Y365109D03*
X964786D03*
X954647Y370959D03*
Y367060D03*
X958026Y369010D03*
X951267D03*
X971546Y349509D03*
X947887Y363160D03*
X941127D03*
X947887Y370959D03*
X941127D03*
Y367060D03*
X944507Y369010D03*
X941127Y359260D03*
X944507Y353409D03*
X947887Y351460D03*
X958026Y372909D03*
X941127Y374860D03*
X961406D03*
X944507Y372909D03*
X941127Y382660D03*
Y378760D03*
X947887D03*
X944507Y384609D03*
X947887Y390460D03*
Y386560D03*
X941127Y390460D03*
X947887Y398260D03*
X941127D03*
X944507Y396309D03*
X947887Y394359D03*
X964786Y376809D03*
X971546D03*
X968166Y378760D03*
Y386560D03*
X964786Y392410D03*
X968166Y390460D03*
Y394359D03*
X964786Y388509D03*
X961406Y378760D03*
X954647D03*
X958026Y384609D03*
X961406Y382660D03*
X951267Y388509D03*
X958026D03*
X954647Y394359D03*
X961406Y386560D03*
X952216Y402421D03*
X970416Y401941D03*
X971546Y380709D03*
X968166Y382660D03*
X970669Y512792D03*
X967322Y515364D03*
X963976Y512792D03*
X960629Y515364D03*
Y529014D03*
X963976Y536957D03*
X970669D03*
X967322Y529014D03*
X963976Y547914D03*
X970669D03*
X967322Y555857D03*
X960629D03*
X970669Y585714D03*
Y574757D03*
X960629Y566814D03*
X963976Y585714D03*
Y574757D03*
X967322Y566814D03*
Y593657D03*
X963976Y612457D03*
X970669D03*
X960629Y604614D03*
X967322D03*
X960629Y593657D03*
X980708Y-4536D03*
X987401Y-9901D03*
X997441Y-7108D03*
X990748Y-1743D03*
X977362Y-7108D03*
X980708Y9114D03*
X990748Y9122D03*
X977362Y28014D03*
X987401D03*
Y17057D03*
X977362D03*
X997441Y28022D03*
Y17057D03*
X1000787Y-4536D03*
Y9122D03*
X1017519Y-1858D03*
Y-9786D03*
X1007480Y-1858D03*
X1007280Y9114D03*
X1017519D03*
X1007480Y-9786D03*
Y17014D03*
Y28014D03*
X1017519D03*
Y17042D03*
X987401Y65814D03*
X977362D03*
X987401Y54857D03*
X977362D03*
X990748Y46922D03*
Y35957D03*
X980708D03*
Y46914D03*
X997441Y65822D03*
Y54857D03*
Y92757D03*
X990748Y73757D03*
Y87392D03*
X977362Y92757D03*
X987401Y89964D03*
X980708Y84714D03*
Y73757D03*
X1000787Y35957D03*
Y46922D03*
X1017519Y54842D03*
X1007480Y46914D03*
X1008226Y54842D03*
X1008217Y35942D03*
X1007480Y65736D03*
X1016600Y65950D03*
X1017519Y35942D03*
Y46914D03*
X1030300Y63200D03*
X1017919Y92500D03*
X1017519Y87500D03*
X1000787Y84599D03*
Y73757D03*
X1007480Y87500D03*
X1007573Y92500D03*
X1008099Y73479D03*
X1017350Y73450D03*
X1024945Y86377D03*
Y83877D03*
X998586Y209109D03*
X981686Y218860D03*
X974926Y211060D03*
X985066Y216909D03*
X988446Y211058D03*
X979426Y214958D03*
X1005345Y209109D03*
X1001965Y211060D03*
X1025625Y209109D03*
X1012105D03*
X1032385D03*
X995206Y238360D03*
X988446Y234460D03*
X998586Y220809D03*
X988446Y250060D03*
X974926Y242260D03*
X988446D03*
X991826Y248109D03*
X988446Y238360D03*
X985066Y236409D03*
X981686Y234460D03*
X974926Y226660D03*
X991826Y220809D03*
X974926Y222760D03*
X985066Y224709D03*
X978306Y220809D03*
X991826Y252009D03*
X995206Y277360D03*
X998586Y267609D03*
Y271509D03*
Y275409D03*
Y279310D03*
X1029005Y238360D03*
X1008725D03*
X1001965D03*
X1005345Y220809D03*
X1029005Y250060D03*
X1032385Y248109D03*
X1025625D03*
Y220809D03*
X1012105D03*
X1015485Y238360D03*
X1022245D03*
X1018865Y220809D03*
X1032385D03*
X1022245Y253960D03*
X1025625Y252009D03*
X1017735Y264300D03*
X1014355Y266300D03*
X1021115Y262300D03*
X1024495Y260300D03*
X1027875Y258400D03*
X1031255Y256400D03*
X1005345Y263709D03*
X1001965Y265660D03*
X1009256Y269777D03*
X1008725Y261760D03*
X1006665Y277360D03*
X1006700Y270700D03*
X1006665Y273460D03*
X1011100Y268100D03*
X1015485Y257860D03*
X1018865Y255909D03*
X1012105Y259809D03*
X995206Y296860D03*
X985066Y294909D03*
Y287109D03*
X988446Y285160D03*
X991826Y287109D03*
X995206Y281260D03*
X978306Y298809D03*
Y287109D03*
X981686Y285160D03*
X978306Y294909D03*
X981686Y296860D03*
Y289060D03*
X978306Y291009D03*
X998586Y302709D03*
Y306609D03*
Y310509D03*
Y287109D03*
Y294909D03*
Y291009D03*
Y298809D03*
Y283209D03*
X985066Y302709D03*
X978306D03*
X988446Y304660D03*
Y308560D03*
X985066Y306609D03*
X995206Y304660D03*
Y308560D03*
X991826Y306609D03*
X978306D03*
X981686Y308560D03*
Y304660D03*
X974926D03*
Y308560D03*
X995206Y300760D03*
X991826Y302709D03*
X974926Y285160D03*
Y296860D03*
Y289060D03*
X995206Y292959D03*
X988446Y296860D03*
X991826Y294909D03*
X995206Y289060D03*
X988446D03*
X991826Y291009D03*
X985066D03*
X995206Y285160D03*
X985066Y298809D03*
X991826D03*
X998586Y314409D03*
X995206Y312460D03*
Y316360D03*
X985066Y314409D03*
X978306D03*
Y318309D03*
Y322209D03*
X981686Y320260D03*
X974926Y316360D03*
Y320260D03*
X985066Y326110D03*
X981686Y328060D03*
X988446D03*
Y324160D03*
X985066Y318309D03*
Y322209D03*
X988446Y320260D03*
X981686Y324160D03*
Y316360D03*
X1006665Y300760D03*
Y304660D03*
Y308560D03*
Y285160D03*
Y296860D03*
Y289060D03*
Y281260D03*
Y292959D03*
X1018865Y341709D03*
X1015485Y339760D03*
X1016399Y324304D03*
X1022393Y326580D03*
X1024893D03*
X1017393D03*
X1028393Y329580D03*
X1019893Y326580D03*
X1027393D03*
X1025755Y328951D03*
X1006665Y312460D03*
X1027875Y339309D03*
X1031255Y341260D03*
X1006665Y316360D03*
X995206Y343660D03*
X985066Y361209D03*
X974926Y355360D03*
Y347560D03*
X981686D03*
X978306Y345609D03*
X981686Y355360D03*
X985066Y349509D03*
X998586D03*
X978306Y365109D03*
X981686Y363160D03*
X974926D03*
Y367060D03*
Y370959D03*
Y343660D03*
X995206Y359260D03*
X988446D03*
Y347560D03*
X991826Y345609D03*
X988446Y351460D03*
Y355360D03*
X985066Y372909D03*
X974926Y374860D03*
X985066Y384609D03*
X998586Y376809D03*
X991826Y388509D03*
X995206Y390460D03*
X974926Y386560D03*
X991826Y376809D03*
X974066Y399911D03*
X978306Y376809D03*
X974926Y378760D03*
X981686D03*
X985066Y380709D03*
X1022245Y343660D03*
X1001965Y359260D03*
X1005345Y349509D03*
X1008725Y359260D03*
X1015485D03*
X1022245D03*
X1029005D03*
X1032385Y388509D03*
Y376809D03*
X1005345D03*
Y388509D03*
X1001965Y386560D03*
X1025625Y376809D03*
Y388509D03*
X1018865Y376809D03*
X1012105D03*
X1018865Y388509D03*
X1012105D03*
X987401Y515364D03*
X990748Y512792D03*
X997441Y518157D03*
X980708Y510114D03*
X977362Y518157D03*
X1000490Y509999D03*
X1016473Y515152D03*
Y510114D03*
X1008650Y515200D03*
X1008526Y510114D03*
X1024800Y516356D03*
Y518856D03*
X1019800Y555800D03*
X990748Y536957D03*
X977362Y529014D03*
X980708Y536957D03*
X987401Y529014D03*
X990748Y547922D03*
X980708Y547914D03*
X997441Y529022D03*
X977362Y555857D03*
X987401D03*
X997441D03*
X977362Y566814D03*
X990748Y574757D03*
Y585722D03*
X980708Y585714D03*
Y574757D03*
X997441Y566822D03*
X987401Y566814D03*
X1000787Y536957D03*
Y547922D03*
X1017300Y536200D03*
X1017519Y529057D03*
X1007518Y536727D03*
X1007480Y528942D03*
X1007280Y547914D03*
X1026400Y543700D03*
X1016800Y566814D03*
X1019277Y585714D03*
X1016800Y574742D03*
X1000787Y585722D03*
Y574757D03*
X1007518Y555842D03*
Y566814D03*
X1007480Y574742D03*
X1006633Y585714D03*
X977362Y593657D03*
X987401D03*
X997441D03*
Y607292D03*
X977362D03*
X990748Y612457D03*
X980708Y609864D03*
X987401Y604499D03*
X1016778Y611759D03*
X1017519Y604614D03*
Y593642D03*
X1007480Y612242D03*
X1000787Y609864D03*
X1007480Y604614D03*
X1006634Y593642D03*
X1047637Y-4536D03*
X1057676Y-1743D03*
X1047637Y9107D03*
X1057677D03*
X1050983Y-7108D03*
X1050984Y17042D03*
X1061023Y-9786D03*
X1067716Y-4536D03*
Y-9901D03*
X1081102Y-4536D03*
X1074409D03*
X1084448Y-7108D03*
X1077755D03*
X1091141Y-1843D03*
X1067716Y9107D03*
X1091141D03*
X1074409D03*
X1081102D03*
X1061024Y17057D03*
X1067716Y28007D03*
Y17042D03*
X1091141D03*
X1084450Y17057D03*
X1077757D03*
X1091141Y28007D03*
X1050984Y54842D03*
X1047637Y35942D03*
Y46907D03*
X1057677Y35942D03*
Y46907D03*
X1057676Y87392D03*
X1050983Y92757D03*
X1047637Y84599D03*
X1035000Y81200D03*
X1057677Y73742D03*
X1047637D03*
X1061024Y54857D03*
X1067716Y54842D03*
Y35942D03*
Y46907D03*
Y65807D03*
X1091141Y54842D03*
Y35942D03*
X1084450Y54857D03*
X1081102Y35942D03*
X1074409D03*
X1077757Y54857D03*
X1081102Y46907D03*
X1074409D03*
X1091141D03*
Y65807D03*
X1067716Y89964D03*
Y84599D03*
X1081102D03*
X1091141Y87392D03*
Y92657D03*
X1077755Y92757D03*
X1074409Y84714D03*
X1084448Y92757D03*
X1061023Y89964D03*
X1067716Y73742D03*
X1074409D03*
X1081102D03*
X1091141D03*
X1050983Y105800D03*
X1057734Y105750D03*
X1077304Y105800D03*
X1071111D03*
X1064428D03*
X1057314Y209109D03*
X1045904D03*
X1039145D03*
X1045904Y220809D03*
X1057314D03*
X1035765Y238360D03*
Y250060D03*
X1057314Y248109D03*
X1039145D03*
X1042524Y250060D03*
X1049284D03*
X1045904Y248109D03*
X1042524Y238360D03*
X1039145Y220809D03*
X1038015Y256500D03*
X1041395Y254259D03*
X1048154D03*
X1051534Y256500D03*
X1044774Y256400D03*
X1054914Y254500D03*
X1034635Y254259D03*
X1071102Y292904D03*
X1068102D03*
X1063902D03*
X1075302Y309904D03*
X1082502D03*
X1092756Y309841D03*
X1089702Y309904D03*
X1085502D03*
X1078302D03*
X1071102D03*
X1068102D03*
X1063902D03*
X1060902D03*
Y292904D03*
X1085502D03*
X1082502D03*
X1078302D03*
X1075302D03*
X1089702D03*
X1092702D03*
X1042524Y359260D03*
X1049284Y351460D03*
X1045904Y353409D03*
X1035765Y351460D03*
Y359260D03*
X1039145Y353409D03*
X1042524Y351460D03*
X1034635Y343209D03*
X1038015Y345160D03*
X1041395Y347109D03*
X1048154D03*
X1044774Y345160D03*
X1051534D03*
X1039145Y388509D03*
X1045904D03*
X1052664D03*
X1039145Y376809D03*
X1045904D03*
X1052664D03*
X1086841Y358547D03*
Y354647D03*
X1073322D03*
X1076702Y356596D03*
X1080082Y354647D03*
X1083462Y368296D03*
X1076702Y372197D03*
Y368296D03*
X1073322Y362447D03*
X1086841D03*
X1090221Y372197D03*
Y364396D03*
X1093601Y366347D03*
X1090221Y368296D03*
X1076702Y360496D03*
X1083462D03*
X1093601Y358547D03*
X1071072Y348497D03*
X1087971Y346546D03*
X1074452D03*
X1081212D03*
X1077832Y348497D03*
X1084591D03*
X1090221Y379996D03*
X1073323Y401449D03*
X1078962Y399496D03*
X1093601Y401447D03*
X1060694Y374860D03*
X1073322Y374146D03*
X1086841D03*
X1073323Y397548D03*
X1073322Y385847D03*
X1080082Y393647D03*
X1083462Y391696D03*
X1080082Y385847D03*
X1083462Y376096D03*
X1080082Y378047D03*
X1083462Y379996D03*
X1076702Y376096D03*
X1090221Y395595D03*
X1086841Y389747D03*
X1093601Y393647D03*
X1090221Y391696D03*
X1093601Y385847D03*
X1086841D03*
X1093601Y397546D03*
Y378047D03*
X1086841Y381947D03*
X1093601Y405347D03*
X1077832Y407800D03*
X1047637Y509999D03*
X1057676Y512792D03*
X1035000Y521556D03*
X1050983Y518157D03*
X1067716Y509999D03*
X1074409Y510114D03*
X1061023Y515364D03*
X1091141Y518057D03*
X1077755Y518157D03*
X1081102Y509999D03*
X1084448Y518157D03*
X1082800Y497650D03*
X1091141Y512792D03*
X1067716Y515364D03*
X1057677Y547907D03*
Y536942D03*
X1047637Y547907D03*
Y536942D03*
X1057677Y574742D03*
Y585707D03*
X1047637Y574742D03*
Y585707D03*
X1050984Y555842D03*
X1074409Y547907D03*
X1081102D03*
X1091141D03*
Y529007D03*
Y536942D03*
X1074409D03*
X1081102D03*
X1067716D03*
Y529007D03*
X1061024Y555857D03*
X1077757D03*
X1084450D03*
X1091141Y555842D03*
X1067716D03*
X1081102Y574742D03*
Y585707D03*
X1074409D03*
X1091141Y574742D03*
Y585707D03*
X1067716Y574742D03*
Y585599D03*
Y566807D03*
X1091141D03*
X1074409Y574742D03*
X1091141Y612557D03*
X1057676Y612657D03*
X1050984Y593642D03*
X1047637Y609864D03*
X1061024Y593657D03*
X1061023Y604614D03*
X1077757Y593657D03*
X1084450D03*
X1067716Y593642D03*
Y609864D03*
Y604499D03*
X1081102Y609864D03*
X1091141Y593642D03*
Y607292D03*
X1084448D03*
X1077755D03*
X1050983D03*
X1074409Y609864D03*
X1137540Y266896D03*
X1147680Y268847D03*
X1137540Y270796D03*
X1140920Y268847D03*
Y264947D03*
X1144300Y262996D03*
X1126280Y266896D03*
X1129660Y264947D03*
X1122900D03*
Y268847D03*
X1126280Y262996D03*
X1154440Y264947D03*
X1118391Y332897D03*
X1134160Y307847D03*
X1151060Y294196D03*
X1147680Y300047D03*
Y296147D03*
X1140920Y307847D03*
Y311747D03*
X1151060Y301996D03*
X1144300Y305896D03*
X1147680Y311747D03*
X1157820Y298096D03*
X1154440Y296147D03*
X1134160Y335147D03*
Y339047D03*
X1140920Y319547D03*
X1124021Y325396D03*
X1127400Y323446D03*
X1124021Y329296D03*
Y333196D03*
X1154440Y327347D03*
X1147680Y339047D03*
X1157820Y321496D03*
X1144300Y313696D03*
X1151060D03*
X1144300Y325396D03*
Y321496D03*
X1151060Y329296D03*
X1147680Y335147D03*
Y331247D03*
X1140920Y335147D03*
X1144300Y333196D03*
X1151060Y325396D03*
Y321496D03*
X1147680Y323446D03*
X1137540Y329296D03*
X1144300D03*
X1140920Y327347D03*
X1130780Y340996D03*
Y337096D03*
X1127400Y331247D03*
Y335147D03*
Y339047D03*
X1147680Y315647D03*
X1151060Y317596D03*
X1137540Y337096D03*
Y340996D03*
Y333196D03*
X1096981Y368296D03*
Y372197D03*
X1101491Y342646D03*
X1098111Y344597D03*
X1096981Y376096D03*
X1134160Y358547D03*
X1157820Y356596D03*
X1144300Y352696D03*
X1154440Y350747D03*
Y362447D03*
X1144300Y368296D03*
X1137540Y352696D03*
X1130780Y356596D03*
X1134160Y342947D03*
Y354647D03*
Y350747D03*
X1137540Y348796D03*
Y344896D03*
X1157820Y379996D03*
X1147680Y389747D03*
X1144300Y376096D03*
X1151060Y383896D03*
X1096699Y407782D03*
X1209033Y183907D03*
X1174719Y292247D03*
Y288347D03*
X1171339Y286396D03*
Y290296D03*
X1167960Y300047D03*
X1164580Y298096D03*
X1167960Y296147D03*
Y292247D03*
Y288347D03*
X1161200Y296147D03*
X1178099Y290296D03*
X1174719Y303947D03*
X1167960D03*
X1178099Y309797D03*
X1171339Y305896D03*
X1164580Y309797D03*
Y305896D03*
X1167960Y307847D03*
Y311747D03*
X1171339Y309797D03*
X1178099Y301996D03*
X1174719Y311747D03*
Y307847D03*
X1178099Y305896D03*
X1171339Y298096D03*
Y294196D03*
X1174719Y296147D03*
Y339047D03*
X1164580Y340996D03*
X1167960Y331247D03*
X1171339Y321496D03*
X1178099Y313696D03*
X1171339D03*
X1164580D03*
X1184859Y325396D03*
Y333196D03*
X1198379Y337096D03*
Y329296D03*
X1167960Y358547D03*
X1171339Y344896D03*
X1174719Y350747D03*
X1167960Y366347D03*
X1171339Y368296D03*
X1161200Y374146D03*
X1178099Y391696D03*
X1174719Y397546D03*
X1164580Y399496D03*
X1188239Y370247D03*
X1191619Y372197D03*
Y364396D03*
Y352696D03*
X1194999Y342947D03*
X1181479Y385847D03*
X1188239Y381947D03*
X1208819Y385847D03*
X1181479Y405347D03*
X1263080Y191320D03*
X1260140Y191670D03*
X1260510Y206840D03*
X1267220Y203600D03*
X1267218Y207495D03*
X1258810Y204840D03*
X1263728Y211444D03*
X1262250Y201227D03*
X1265718Y201459D03*
X1258482Y201495D03*
X1257770Y199150D03*
X1260260Y199862D03*
X1264180Y199510D03*
X1240500Y218200D03*
X1240452Y208240D03*
Y215740D03*
Y213240D03*
Y210740D03*
X1243196Y207002D03*
X1242800Y204150D03*
X1244380Y202160D03*
X1255310Y193850D03*
X1252930Y193270D03*
X1263040Y193930D03*
X1259360Y193950D03*
X1257210Y192340D03*
X1268986Y205727D03*
X1269254Y197923D03*
X1270930Y200220D03*
X1268930Y201820D03*
X1272522Y202191D03*
X1270754Y203959D03*
X1267486Y199691D03*
X1262018Y197959D03*
X1265786Y197691D03*
X1259518Y197459D03*
X1263950Y203227D03*
X1260620Y203130D03*
X1255982Y200995D03*
X1255833Y197423D03*
X1256810Y203340D03*
X1262182Y204995D03*
X1265420Y205400D03*
X1250235Y199342D03*
X1251940Y197530D03*
X1247803Y198486D03*
X1254065Y199191D03*
X1252330Y201030D03*
X1254310Y202840D03*
X1250625Y202804D03*
X1248290Y201720D03*
X1246620Y203570D03*
X1246090Y200330D03*
X1245014Y205405D03*
X1251089Y194810D03*
X1249571Y196718D03*
X1253521Y195666D03*
X1267554Y195923D03*
X1261220Y195650D03*
X1263804Y196318D03*
X1265570Y194510D03*
X1257601Y195655D03*
X1262080Y209140D03*
X1265450Y209263D03*
X1263680Y207160D03*
X1243300Y223100D03*
X1278183Y231886D03*
X1251395Y226373D03*
X1253791Y226228D03*
X1248672Y226494D03*
X1252221Y228668D03*
X1245300Y224800D03*
X1301279Y10058D03*
X1304079D03*
X1306879D03*
X1301200Y12610D03*
X1306800D03*
X1301200Y15200D03*
X1301100Y2700D03*
X1316300Y-14800D03*
X1320800Y-16900D03*
X1307900Y-14700D03*
X1309500Y-16800D03*
X1323600Y-16900D03*
X1322000Y-14800D03*
X1324800D03*
X1326000Y-12700D03*
X1323600Y-12600D03*
X1327600Y-14800D03*
Y4700D03*
X1326400Y2600D03*
X1324800Y4700D03*
X1322000D03*
X1323600Y2600D03*
X1306700Y2700D03*
X1309500D03*
X1307900Y4800D03*
X1320800Y2600D03*
X1316300Y4700D03*
X1317900Y2600D03*
X1319200Y4700D03*
X1313500Y4800D03*
X1315004Y2567D03*
X1326400Y-16900D03*
X1302300Y4800D03*
X1303900Y2700D03*
X1310700Y4800D03*
X1312300Y2700D03*
X1305100Y4800D03*
X1322532Y9822D03*
X1325332D03*
X1306700Y-16800D03*
X1328800Y-12700D03*
X1312300Y-16800D03*
X1310700Y-14700D03*
X1315004Y-16933D03*
X1313500Y-14700D03*
X1319200Y-14800D03*
X1317900Y-16900D03*
X1321452Y31803D03*
X1304000Y15200D03*
X1328085Y9865D03*
X1322483Y12834D03*
X1328045Y15831D03*
X1325308Y15734D03*
X1322508D03*
X1328123Y12730D03*
X1306800Y15200D03*
X1328987Y2525D03*
X1313942Y30714D03*
X1309760Y30691D03*
X1316300Y31911D03*
X1318700Y31943D03*
X1311809Y32096D03*
X1325383Y12634D03*
X1304000Y12610D03*
X1295581Y94320D03*
X1310600Y41500D03*
X1308100D03*
X1323400Y41439D03*
X1326000D03*
X1326058Y43956D03*
X1323400Y43839D03*
X1331770Y399490D03*
X1332650Y374450D03*
X1317788Y402562D03*
Y400062D03*
X1331856Y401995D03*
X1329064Y399556D03*
X1329288Y402062D03*
X1330200Y377300D03*
X1330758Y389785D03*
Y386785D03*
Y383785D03*
X1324872Y380682D03*
X1322054Y380560D03*
X1324872Y383682D03*
X1327800Y383500D03*
X1325000Y377500D03*
X1327600Y377400D03*
X1319300Y378500D03*
X1327700Y380400D03*
X1322100Y377800D03*
X1323288Y402062D03*
X1323064Y399556D03*
X1320423Y399579D03*
X1320288Y402062D03*
X1326288D03*
X1326064Y399556D03*
X1332600Y377200D03*
X1332748Y380503D03*
X1330190Y380406D03*
X1334889Y421400D03*
X1332236Y419004D03*
X1329400Y404524D03*
X1329736Y419004D03*
X1329889Y421400D03*
X1332389D03*
X1331973Y404580D03*
X1322370Y421400D03*
X1324889Y421470D03*
X1320400Y404524D03*
X1326400D03*
X1323400D03*
X1324736Y419074D03*
X1322217Y419004D03*
X1327236Y419030D03*
X1327389Y421426D03*
X1334967Y419001D03*
X1325100Y457500D03*
Y452500D03*
X1320100Y457500D03*
Y452500D03*
X1315100D03*
X1310100D03*
X1315100Y457500D03*
X1305100D03*
Y452500D03*
X1310100Y457500D03*
X1330100D03*
Y452500D03*
X1300000Y552400D03*
Y558400D03*
Y555400D03*
X1317500Y552400D03*
X1320500D03*
X1323500D03*
X1317500Y555400D03*
X1320500D03*
X1323500D03*
X1303000Y576000D03*
Y579000D03*
Y571400D03*
Y568900D03*
Y565900D03*
Y563400D03*
X1306000Y579000D03*
X1323774Y563145D03*
Y566145D03*
X1309000Y565900D03*
Y563400D03*
Y571400D03*
X1306000Y568900D03*
X1309000D03*
X1306000Y576000D03*
X1324000Y568900D03*
X1306000Y571400D03*
X1321000D03*
X1324000D03*
X1321000Y568900D03*
X1318000D03*
X1312000D03*
X1318000Y571400D03*
X1315000D03*
Y568900D03*
X1312000Y571400D03*
X1320500Y558400D03*
X1317500D03*
X1312000Y563400D03*
Y565900D03*
X1315000Y563400D03*
Y565900D03*
X1323500Y558400D03*
X1318000Y563400D03*
Y565900D03*
X1321000Y563400D03*
Y565900D03*
X1306000D03*
Y563400D03*
X1306600Y610000D03*
X1306556Y607558D03*
X1324200Y610100D03*
Y600100D03*
Y597600D03*
X1321100Y598500D03*
Y601000D03*
X1315100Y598500D03*
Y601000D03*
X1312100Y598500D03*
X1309100D03*
Y601000D03*
X1312100D03*
X1318100Y598500D03*
Y601000D03*
X1324200Y602700D03*
Y605100D03*
Y607500D03*
X1400616Y13795D03*
X1403746Y91680D03*
X1403264Y82000D03*
X1394700Y122950D03*
X1391700D03*
Y125950D03*
X1394700D03*
Y128950D03*
X1391700D03*
X1388450Y331250D03*
X1359200Y322200D03*
X1389500Y360500D03*
X1390100Y432500D03*
X1385100Y427500D03*
Y442500D03*
Y437500D03*
X1395725Y417193D03*
X1393900Y415000D03*
X1396900D03*
Y412500D03*
X1393900D03*
X1389900Y427400D03*
X1385100Y432500D03*
X1365100D03*
Y427500D03*
Y437500D03*
X1380100Y442500D03*
Y437500D03*
X1370100D03*
X1375100D03*
X1400445Y510159D03*
X1386800Y535600D03*
Y541500D03*
Y538500D03*
X1384310Y538540D03*
Y535540D03*
Y541540D03*
X1407964Y79700D03*
X1407960Y93800D03*
X1407300Y77300D03*
X1410200Y77400D03*
X1405149Y93679D03*
X1406746Y91680D03*
X1406264Y82000D03*
X1409264D03*
X1404964Y79700D03*
X1454070Y163360D03*
X1454660Y166200D03*
X1433362Y280744D03*
X1455600Y254826D03*
X1462704Y254470D03*
X1448050Y374950D03*
X1464273Y397648D03*
X1463200Y362200D03*
X1452699Y404060D03*
X1428500Y521000D03*
X1422509Y576823D03*
X1419809Y570723D03*
X1422509Y573823D03*
X1419809Y573723D03*
Y576723D03*
X1422509Y570823D03*
X1417252Y573470D03*
X1414743Y573363D03*
X1414851Y576624D03*
X1414744Y570801D03*
X1417182Y570711D03*
X1417288Y576624D03*
X1504400Y20300D03*
X1481600Y5300D03*
X1522600Y-6500D03*
X1490900Y146600D03*
X1477397Y256657D03*
X1484000Y257500D03*
X1492697Y267303D03*
X1493240Y325828D03*
X1520766Y341000D03*
X1505000Y340990D03*
X1484620Y339152D03*
X1508650Y287500D03*
X1473255Y372654D03*
X1512954Y407653D03*
X1524575Y407624D03*
X1518650Y416750D03*
X1497200Y421200D03*
X1505715Y441368D03*
X1506059Y429249D03*
X1505459Y421107D03*
X1503128Y419892D03*
X1512350Y423050D03*
X1518650Y426200D03*
Y423050D03*
X1515500Y426200D03*
Y423050D03*
X1524950Y426200D03*
Y423050D03*
X1509200Y416750D03*
X1512350D03*
X1505605Y423604D03*
X1509200Y423050D03*
Y419900D03*
X1515500D03*
X1512350D03*
Y426200D03*
X1509200D03*
X1515500Y429350D03*
X1518650D03*
X1509200D03*
X1512350D03*
X1518650Y438800D03*
X1515500D03*
X1512350D03*
X1505392Y437133D03*
X1509200Y438800D03*
Y441950D03*
X1512350D03*
X1515500D03*
X1524950Y438800D03*
X1509200Y435650D03*
X1518650D03*
X1515500D03*
X1512350D03*
X1524950D03*
X1525000Y416750D03*
X1544882Y-6900D03*
X1575959Y84198D03*
X1587734Y70974D03*
X1538870Y78980D03*
X1541988Y90207D03*
Y92707D03*
X1541670Y87760D03*
X1544180Y91660D03*
X1589622Y112876D03*
X1589200Y121800D03*
X1580275Y101041D03*
X1531700Y155600D03*
X1541800Y99700D03*
X1541900Y97300D03*
X1541413Y155259D03*
X1533596Y273504D03*
X1542751Y240477D03*
X1585479Y316610D03*
X1582859Y341112D03*
X1570574Y341776D03*
X1554932Y332171D03*
X1560024Y331800D03*
X1538406Y330157D03*
X1543528Y349946D03*
X1584975Y460210D03*
X1587475D03*
X1582200Y460310D03*
X1532375Y407934D03*
X1531250Y445100D03*
Y448250D03*
Y426200D03*
Y429350D03*
Y423050D03*
Y438800D03*
Y435650D03*
X1528475Y407934D03*
X1543850Y416750D03*
Y413600D03*
X1540700Y416750D03*
X1534400D03*
X1537550D03*
X1536275Y407934D03*
X1540175D03*
X1540700Y413600D03*
X1549926Y411312D03*
X1553825Y411314D03*
X1544150Y409900D03*
X1540700Y445100D03*
X1537550Y448250D03*
X1534400D03*
X1540700D03*
X1537550Y445100D03*
X1534400D03*
X1540700Y435650D03*
X1547754Y430351D03*
X1547755Y423570D03*
X1547754Y427884D03*
X1553825Y453686D03*
X1547000Y435650D03*
X1549925Y431594D03*
X1547755Y421138D03*
X1540700Y423050D03*
X1537550Y429350D03*
X1540700D03*
X1534400Y426200D03*
X1537550D03*
X1540700D03*
X1534400Y429350D03*
Y423050D03*
X1537550D03*
X1534400Y438800D03*
Y435650D03*
X1537550Y438800D03*
X1540700D03*
X1536300Y455200D03*
X1587679Y596867D03*
X1585179Y596902D03*
X1579900Y606050D03*
X1592453Y8502D03*
X1608500Y-3600D03*
X1638550Y7200D03*
X1617000Y9500D03*
X1601650Y24160D03*
X1606579Y86726D03*
X1599500Y84500D03*
X1614169Y95004D03*
X1617347Y94581D03*
X1590949Y97850D03*
X1627177Y260267D03*
X1642712Y342347D03*
X1622100Y400600D03*
X1597900Y370000D03*
X1597850Y367329D03*
X1630219Y446000D03*
X1621000Y440500D03*
X1621044Y433364D03*
X1612250Y432500D03*
X1611418Y422971D03*
X1621182Y427091D03*
X1621347Y415297D03*
X1603719Y412000D03*
X1646480Y443880D03*
X1614900Y498575D03*
X1615100Y481400D03*
X1617600D03*
X1612500Y510300D03*
X1615000D03*
X1617771Y498714D03*
X1599070Y562266D03*
X1596570D03*
X1599120Y564764D03*
X1596620D03*
X1596600Y567250D03*
X1601540Y588793D03*
X1590304Y596896D03*
X1666500Y10500D03*
X1682396Y74344D03*
X1707268Y77668D03*
X1712600Y46100D03*
X1711000Y55525D03*
X1696870Y86093D03*
X1667000Y51500D03*
X1663000Y81600D03*
X1652991Y321341D03*
X1657494Y292816D03*
X1668843Y465060D03*
X1661549Y451251D03*
X1681115Y525218D03*
X1710000Y595500D03*
Y604500D03*
Y600000D03*
X1741544Y9151D03*
X1752908Y9481D03*
X1713900Y87900D03*
X1760016Y65774D03*
X1771707Y86500D03*
X1727620Y444380D03*
X1774200Y512800D03*
X1724250Y588250D03*
X1756578Y586743D03*
X1767141Y555500D03*
X1733000Y557000D03*
X1742200Y552863D03*
X1762595Y576191D03*
X1724899Y584748D03*
X1739500Y586500D03*
X1735000Y621002D03*
X1764823Y613600D03*
X1758550Y604350D03*
X1829636Y26680D03*
X1831000Y-16300D03*
X1788421Y8122D03*
X1827000Y94550D03*
X1787500Y155170D03*
X1783252Y109044D03*
X1803058Y143733D03*
X1815348Y143437D03*
X1796500Y120000D03*
X1815200Y501500D03*
X1801600Y515600D03*
X1794100Y521900D03*
X1783700Y576400D03*
X1798250Y529200D03*
X1810863Y560637D03*
X1816175Y567669D03*
X1805000Y606500D03*
X1870600Y25000D03*
X1878800Y43207D03*
X1897450Y213951D03*
Y216551D03*
X1836900Y165800D03*
X1872323Y264167D03*
X1896700Y472600D03*
X1896800Y470200D03*
X1894100Y472600D03*
X1894200Y470200D03*
X1864339Y509560D03*
X1838000Y549700D03*
X1838224Y586650D03*
X1878500Y553500D03*
X1858500Y540000D03*
X1852250Y547900D03*
X1858681Y568087D03*
X1879862Y581862D03*
X1896899Y557790D03*
X1845407Y533178D03*
X1868110Y536000D03*
X1878736Y533040D03*
X1864580Y537060D03*
X1858000Y586250D03*
X1916078Y-16368D03*
X1956891Y92513D03*
X1952110Y95513D03*
X1954391Y92513D03*
X1951670Y90363D03*
Y92863D03*
X1951770Y87863D03*
X1954169Y84111D03*
X1954861Y95163D03*
X1949610Y95513D03*
X1949270Y87863D03*
X1949170Y92863D03*
Y90363D03*
X1946670Y87863D03*
X1946570Y92863D03*
Y90363D03*
X1946670Y85363D03*
X1949270D03*
X1951770D03*
X1957361Y95163D03*
X1926890Y73106D03*
X1937900Y153600D03*
X1921264Y153000D03*
X1943752Y137548D03*
X1947078Y139300D03*
X1931483Y199350D03*
X1901100Y194200D03*
X1940647Y161600D03*
X1928218Y175443D03*
X1914173Y448200D03*
X1917700Y435600D03*
X1920700D03*
X1914700D03*
X1917322Y447930D03*
X1920472D03*
X1935300Y450600D03*
X1899100Y472600D03*
X1899200Y470200D03*
X1904200Y472700D03*
X1901700Y472600D03*
X1904300Y470300D03*
X1901800Y470200D03*
X1938300Y486250D03*
X1957250Y512050D03*
X1937300Y508900D03*
X1915050Y547900D03*
X1900250Y533700D03*
X1900729Y569557D03*
X1913800Y555500D03*
X1937250Y578200D03*
X1938000Y597320D03*
X1923504Y592500D03*
X1973328Y147303D03*
X1963400Y141100D03*
X1967200Y521600D03*
X1963097Y551000D03*
X1972700Y576400D03*
G54D21*
G01X988446Y250060D02*
X984402D01*
X982351Y248009D01*
X980920D01*
X979837Y246926D01*
Y245394D01*
X980155Y245075D01*
Y243443D01*
X979072Y242360D01*
X977641D01*
X975692Y240411D01*
X974362D01*
X973077Y239126D01*
Y237493D01*
X973395Y237175D01*
Y235643D01*
X972312Y234560D01*
X970881D01*
X968729Y232408D01*
X967400D01*
X965652Y230660D01*
X964122D01*
X962172Y228710D01*
X960841D01*
X959557Y227426D01*
Y225894D01*
X959875Y225576D01*
Y223943D01*
X958590Y222658D01*
X957260D01*
X955513Y220911D01*
X953984D01*
X952033Y218960D01*
X950703D01*
X948552Y216809D01*
X947121D01*
X945372Y215060D01*
X943642D01*
X941893Y216809D01*
X940361D01*
X938612Y215060D01*
X936882D01*
X935133Y216809D01*
X933601D01*
X931852Y215060D01*
X930122D01*
X928373Y216809D01*
X926841D01*
X925092Y215060D01*
X920900D01*
G01X919800Y212909D02*
X921712D01*
X923461Y211160D01*
X925092D01*
X926841Y212909D01*
X928472D01*
X930221Y211160D01*
X931852D01*
X933601Y212909D01*
X935232D01*
X936981Y211160D01*
X938612D01*
X940361Y212909D01*
X941992D01*
X943741Y211160D01*
X945372D01*
X947121Y212909D01*
X948552D01*
X950501Y214858D01*
X951831D01*
X953984Y217011D01*
X955413D01*
X957160Y218758D01*
X958689D01*
X960842Y220911D01*
X962172D01*
X963255Y221994D01*
Y223526D01*
X962937Y223844D01*
Y225475D01*
X964223Y226761D01*
X965552D01*
X967300Y228509D01*
X968830D01*
X970981Y230660D01*
X972312D01*
X974263Y232611D01*
X975692D01*
X976775Y233694D01*
Y235324D01*
X976457Y235643D01*
Y237175D01*
X977540Y238258D01*
X978969D01*
X981122Y240411D01*
X982452D01*
X983535Y241494D01*
Y243125D01*
X983217Y243443D01*
Y244975D01*
X984502Y246260D01*
X985832D01*
X987783Y248211D01*
X989212D01*
X991826Y250825D01*
Y252009D01*
G01Y248109D02*
X990295Y246578D01*
Y245394D01*
X989010Y244109D01*
X987680D01*
X986597Y243026D01*
Y241393D01*
X986915Y241075D01*
Y239543D01*
X985630Y238258D01*
X984199D01*
X982452Y236511D01*
X981122D01*
X979837Y235226D01*
Y233694D01*
X980155Y233376D01*
Y231743D01*
X978871Y230459D01*
X977540D01*
X975590Y228509D01*
X974060D01*
X972312Y226761D01*
X970983D01*
X968831Y224609D01*
X967400D01*
X966317Y223526D01*
Y221994D01*
X966635Y221676D01*
Y220043D01*
X965350Y218758D01*
X963919D01*
X961970Y216809D01*
X960640D01*
X958689Y214858D01*
X957160D01*
X955413Y213111D01*
X954011D01*
X951858Y210958D01*
X950501D01*
X948551Y209008D01*
X947121D01*
X945373Y207260D01*
X943741D01*
X941993Y209008D01*
X940361D01*
X938613Y207260D01*
X936981D01*
X935233Y209008D01*
X933601D01*
X931853Y207260D01*
X930221D01*
X928473Y209008D01*
X926841D01*
X925093Y207260D01*
X923461D01*
X921713Y209008D01*
X920081D01*
X918998Y207925D01*
G54D12*
X30500Y-42250D03*
Y-52250D03*
X50500Y-42250D03*
X70500D03*
X90500D03*
X110500D03*
X50500Y-52250D03*
X70500D03*
X90500D03*
X110500D03*
X130500Y-42250D03*
Y-52250D03*
X457246Y-52301D03*
Y-42301D03*
X477246Y-52301D03*
Y-42301D03*
X497246Y-52301D03*
Y-42301D03*
X517246Y-52301D03*
Y-42301D03*
X537246Y-52301D03*
Y-42301D03*
X557246Y-52301D03*
Y-42301D03*
X788984Y-52057D03*
Y-42057D03*
X808984Y-52057D03*
Y-42057D03*
X828984Y-52057D03*
Y-42057D03*
X848984Y-52057D03*
Y-42057D03*
X868984Y-52057D03*
Y-42057D03*
X888984Y-52057D03*
Y-42057D03*
X1125583Y-52285D03*
Y-42285D03*
X1145583Y-52285D03*
Y-42285D03*
X1382258Y-52257D03*
Y-42257D03*
X1402258Y-52257D03*
Y-42257D03*
X1422258Y-52257D03*
Y-42257D03*
X1442258Y-52257D03*
Y-42257D03*
G54D13*
X42724Y644684D03*
Y644656D03*
Y654684D03*
Y654656D03*
X67724Y644684D03*
Y644656D03*
Y654684D03*
Y654656D03*
X221656Y644656D03*
X196656D03*
X231446Y644756D03*
Y644784D03*
X221656Y644684D03*
X196656D03*
X221656Y654656D03*
X196656D03*
X231446Y654756D03*
Y654784D03*
X221656Y654684D03*
X196656D03*
X256446Y644756D03*
Y644784D03*
Y654756D03*
Y654784D03*
X409240Y644564D03*
X384240D03*
X418914Y644486D03*
Y644514D03*
X409240Y644536D03*
X384240D03*
X409240Y654564D03*
X384240D03*
X418914Y654486D03*
Y654514D03*
X409240Y654536D03*
X384240D03*
X443914Y644486D03*
Y644514D03*
Y654486D03*
Y654514D03*
X596707Y644293D03*
X571707D03*
X596708Y644266D03*
X571708D03*
X596707Y654293D03*
X571707D03*
X596708Y654266D03*
X571708D03*
X606462Y644245D03*
X631462D03*
X606462Y644217D03*
X631462D03*
X606462Y654245D03*
X631462D03*
X606462Y654217D03*
X631462D03*
X912351Y644245D03*
X887351D03*
X912351Y644273D03*
X887351D03*
X912351Y654245D03*
X887351D03*
X912351Y654273D03*
X887351D03*
X922116Y644206D03*
X947116D03*
X922116Y644234D03*
X947116D03*
X922116Y654206D03*
X947116D03*
X922116Y654234D03*
X947116D03*
X1200877Y644262D03*
Y644234D03*
Y654262D03*
Y654234D03*
X1225877Y644262D03*
X1235614Y644236D03*
X1260614D03*
X1235614Y644264D03*
X1260614D03*
X1225877Y644234D03*
Y654262D03*
X1235614Y654236D03*
X1260614D03*
X1235614Y654264D03*
X1260614D03*
X1225877Y654234D03*
X1514375Y644292D03*
Y644264D03*
Y654292D03*
Y654264D03*
X1539375Y644292D03*
Y644264D03*
Y654292D03*
Y654264D03*
G54D14*
X95275Y217545D03*
X91626Y215364D03*
X85156Y212774D03*
X89386Y212744D03*
X87416Y215504D03*
X87542Y210043D03*
X83366Y215624D03*
X95140Y220946D03*
X91809Y221009D03*
X88447Y221136D03*
X85188Y221341D03*
X49560Y649770D03*
Y644670D03*
X54360D03*
X49560Y649570D03*
Y644670D03*
X54360D03*
X49560Y654670D03*
X54360D03*
X49560D03*
X54360D03*
X214820Y649570D03*
Y644670D03*
X210020D03*
X214820Y649770D03*
Y644670D03*
X210020D03*
X214820Y654670D03*
X210020D03*
X214820D03*
X210020D03*
X238282Y649670D03*
Y644770D03*
X243082D03*
X238282Y649870D03*
Y644770D03*
X243082D03*
X238282Y654770D03*
X243082D03*
X238282D03*
X243082D03*
X402404Y649650D03*
Y644550D03*
X397604D03*
X402404Y649450D03*
Y644550D03*
X397604D03*
X402404Y654550D03*
X397604D03*
X402404D03*
X397604D03*
X425750Y649400D03*
Y644500D03*
X430550D03*
X425750Y649600D03*
Y644500D03*
X430550D03*
X425750Y654500D03*
X430550D03*
X425750D03*
X430550D03*
X589871Y649379D03*
Y644279D03*
X585071D03*
X589872Y649180D03*
Y644280D03*
X585072D03*
X589871Y654279D03*
X585071D03*
X589872Y654280D03*
X585072D03*
X613298Y649331D03*
Y644231D03*
X618098D03*
X613298Y649131D03*
Y644231D03*
X618098D03*
X613298Y654231D03*
X618098D03*
X613298D03*
X618098D03*
X905515Y649159D03*
Y644259D03*
X900715D03*
X905515Y649359D03*
Y644259D03*
X900715D03*
X905515Y654259D03*
X900715D03*
X905515D03*
X900715D03*
X928952Y649120D03*
Y644220D03*
X933752D03*
X928952Y649320D03*
Y644220D03*
X933752D03*
X928952Y654220D03*
X933752D03*
X928952D03*
X933752D03*
X1219041Y649348D03*
Y644248D03*
X1214241D03*
X1219041Y649148D03*
Y644248D03*
X1214241D03*
X1219041Y654248D03*
X1214241D03*
X1219041D03*
X1214241D03*
X1242450Y649150D03*
Y644250D03*
X1247250D03*
X1242450Y649350D03*
Y644250D03*
X1247250D03*
X1242450Y654250D03*
X1247250D03*
X1242450D03*
X1247250D03*
X1527739Y644278D03*
D03*
Y654278D03*
D03*
X1532539Y649378D03*
Y644278D03*
Y649178D03*
Y644278D03*
Y654278D03*
D03*
G54D15*
X320784Y203219D03*
X330948Y201258D03*
X401377Y28022D03*
X411416D03*
X401377Y65822D03*
X411416D03*
X401377Y529022D03*
X411416D03*
X401377Y566822D03*
X411416D03*
X428149Y28022D03*
X434842Y28268D03*
X421456Y35957D03*
X434842Y65822D03*
X428149D03*
Y529022D03*
X434842D03*
X428149Y566822D03*
X434842D03*
X970392Y203219D03*
X1050985Y28022D03*
X1061024D03*
X1077757D03*
X1084450Y28098D03*
X1050985Y65822D03*
X1071064Y35957D03*
X1061024Y65822D03*
X1084450D03*
X1077757D03*
X1050985Y529022D03*
Y566822D03*
X1061024Y529022D03*
X1084450D03*
X1077757D03*
X1067716Y547907D03*
X1071064Y574757D03*
X1061024Y566822D03*
X1084450D03*
X1077757D03*
X1442303Y267303D03*
X1454902Y276753D03*
X1451753Y279902D03*
X1454902Y308247D03*
X1451753Y305098D03*
X1442303Y298799D03*
X1464351Y298798D03*
X1461202D03*
Y295649D03*
X1445528Y317772D03*
X1461202Y286202D03*
X1464351D03*
X1461202Y289351D03*
X1480098Y276753D03*
X1483247Y279902D03*
X1470649Y298798D03*
Y286202D03*
X1473798Y295649D03*
X1483247Y305098D03*
X1480098Y308247D03*
X1473798Y298798D03*
X1492696Y314546D03*
X1473798Y289351D03*
Y286202D03*
X1629489Y153286D03*
X1620040Y134388D03*
Y128089D03*
G54D16*
X1952756Y-14960D03*
G54D17*
G01X61195Y31002D02*
X55431D01*
X49469Y25040D01*
X35936D01*
X34096Y23200D01*
X22280D01*
X17890Y27590D01*
X8976D01*
X8660Y27274D01*
G01X61056Y52800D02*
X22800D01*
X17333Y58267D01*
X8988D01*
G01X62449Y32256D02*
X61195Y31002D01*
G01X920900Y215060D02*
X915643D01*
X904877Y204294D01*
X827351D01*
X823150Y200093D01*
X816863D01*
X815363Y201593D01*
X810149D01*
X797063Y188507D01*
Y182490D01*
X798337Y181216D01*
G01X799620Y186547D02*
X803180Y190107D01*
X812648D01*
X819634Y197093D01*
X824393D01*
X828594Y201294D01*
X906300D01*
X907736Y202730D01*
X907830D01*
X918009Y212909D01*
X919800D01*
G01X918998Y207925D02*
X917583Y206510D01*
X915866D01*
X907650Y198294D01*
X829837D01*
X825636Y194093D01*
X823448D01*
X823447Y194092D01*
X821940D01*
X814845Y186997D01*
X804653D01*
X804470Y186814D01*
G54D18*
G01X1872323Y264167D02*
X1682133D01*
X1676400Y269900D01*
Y306199D01*
X1678700Y308499D01*
Y431500D01*
X1683500Y436300D01*
X1723073D01*
X1727620Y440847D01*
Y444380D01*
G01X1758324Y232657D02*
X1762162Y228819D01*
X1857070D01*
X1863124Y222765D01*
X1871322D01*
X1878652Y230095D01*
Y240157D01*
X1882178Y243683D01*
X1914000D01*
X1914037Y243646D01*
G54D19*
G01X1452550Y275250D02*
X1444400D01*
G01X1457150Y275200D02*
X1462200D01*
G01X1456400Y274900D02*
Y269250D01*
G01X1453350Y274950D02*
Y269350D01*
G01X1449800Y278350D02*
X1444550D01*
G01X1457200Y278300D02*
X1465150D01*
G01X1456450Y278950D02*
Y290400D01*
G01X1457200Y306750D02*
X1459000D01*
G01X1457300Y309900D02*
X1459000D01*
G01X1449550Y309800D02*
X1441400D01*
G01X1450100Y310550D02*
Y318750D01*
G01X1456550Y306000D02*
Y294750D01*
G01X1453300D02*
Y302950D01*
G01Y310500D02*
Y318850D01*
G01X1456450Y310750D02*
Y315450D01*
G01X1449400Y303550D02*
X1441150D01*
G01X1449400Y306700D02*
X1441300D01*
G01X1450100Y294700D02*
Y302900D01*
G01X1459650Y301300D02*
Y306000D01*
G01X1462750Y301150D02*
Y305900D01*
G01X1465000Y306700D02*
X1463600D01*
G01X1459550Y310650D02*
Y315400D01*
G01X1465450Y309750D02*
X1463500D01*
G01X1462800Y312300D02*
Y310650D01*
G01X1449650Y281500D02*
X1447750D01*
G01X1450150Y282350D02*
Y290050D01*
G01X1453250Y282250D02*
Y290350D01*
G01X1484350Y275200D02*
X1482250D01*
G01X1480950Y303450D02*
X1469650D01*
G01X1469400Y306600D02*
X1477800D01*
G01X1478000Y309900D02*
X1469550D01*
G01X1478500Y312100D02*
Y310650D01*
G01X1487350Y303600D02*
X1485600D01*
G01X1487350Y306600D02*
X1485650D01*
G01X1481650Y294600D02*
Y302800D01*
G01X1490550Y309850D02*
X1482350D01*
G01X1481650Y310500D02*
Y315350D01*
G01X1484850Y294350D02*
Y302800D01*
M02*
